G04 ================== begin FILE IDENTIFICATION RECORD ==================*
G04 Layout Name:  F:/<user>/2022/FB/R4006-TIMING/brd/gerber-3/R4006-B0001-02_R01.brd*
G04 Film Name:    R4006-B0001-02_R01_ASM*
G04 File Format:  Gerber RS274X*
G04 File Origin:  Cadence Allegro 17.2-S079*
G04 Origin Date:  Fri Feb 25 18:14:44 2022*
G04 *
G04 Layer:  DRAWING FORMAT/ASM*
G04 Layer:  DRAWING FORMAT/OUTLINE*
G04 *
G04 Offset:    (0.00 0.00)*
G04 Mirror:    No*
G04 Mode:      Positive*
G04 Rotation:  0*
G04 FullContactRelief:  No*
G04 UndefLineWidth:     6.00*
G04 ================== end FILE IDENTIFICATION RECORD ====================*
%FSLAX55Y55*MOIN*%
%IR0*IPPOS*OFA0.00000B0.00000*MIA0B0*SFA1.00000B1.00000*%
%ADD10C,.01*%
%ADD11C,.014*%
%ADD12C,.001*%
%ADD13C,.006*%
%ADD14C,.00001*%
G75*
%LPD*%
G75*
G36*
G01X-957648Y478346D02*
Y482346D01*
X-950560D01*
Y478346D01*
X-957648D01*
G37*
G36*
G01X-927240Y463998D02*
Y467998D01*
X-920152D01*
Y463998D01*
X-927240D01*
G37*
G36*
G01Y491556D02*
Y495556D01*
X-920152D01*
Y491556D01*
X-927240D01*
G37*
G36*
G01X-903618Y463998D02*
Y467998D01*
X-896530D01*
Y463998D01*
X-903618D01*
G37*
G36*
G01Y491556D02*
Y495556D01*
X-896530D01*
Y491556D01*
X-903618D01*
G37*
G36*
G01X-879996Y463998D02*
Y467998D01*
X-872908D01*
Y463998D01*
X-879996D01*
G37*
G36*
G01Y491556D02*
Y495556D01*
X-872908D01*
Y491556D01*
X-879996D01*
G37*
G36*
G01X-856374Y463998D02*
Y467998D01*
X-849286D01*
Y463998D01*
X-856374D01*
G37*
G36*
G01Y491556D02*
Y495556D01*
X-849286D01*
Y491556D01*
X-856374D01*
G37*
G36*
G01X-809130D02*
Y495556D01*
X-802042D01*
Y491556D01*
X-809130D01*
G37*
G36*
G01X-785508D02*
Y495556D01*
X-778420D01*
Y491556D01*
X-785508D01*
G37*
G36*
G01X271826Y362048D02*
Y366048D01*
X302930D01*
Y362048D01*
X271826D01*
G37*
G54D10*
G01X1049850Y-1584500D02*
X1024850D01*
Y-1534500D01*
X1049850D01*
G01X1039850Y-1558666D02*
X1024850D01*
G54D11*
G01X896578Y99538D02*
X1116578D01*
Y49538D01*
X896578D01*
Y99538D01*
G54D12*
G01X-2466000Y-1412000D02*
X-2433100D01*
G01X-2466000Y-1078500D02*
X-2433100D01*
G01X-2466000Y-745100D02*
X-2433100D01*
G01X-2466000Y-411500D02*
X-2433100D01*
G01X-2476400Y-82400D02*
X-2433100D01*
G01X-2466000Y251200D02*
X-2433100D01*
G01X-2466000Y584600D02*
X-2433100D01*
G01X-2466000Y918100D02*
X-2433100D01*
G01X-2466000Y1251500D02*
X-2433100D01*
G01X-2457800Y-1593700D02*
X-2448600Y-1568000D01*
G01X-2455900Y-1588200D02*
X-2441400D01*
G01X-2448600Y-1568000D02*
X-2439500Y-1593700D01*
G01X-2457800Y-1232300D02*
Y-1258000D01*
G01D02*
X-2448600D01*
G01D02*
X-2445100Y-1257600D01*
G01Y-1244000D02*
X-2448600Y-1243400D01*
G01D02*
X-2457800D01*
G01X-2448600D02*
X-2445400Y-1242800D01*
G01Y-1232900D02*
X-2448600Y-1232300D01*
G01D02*
X-2457800D01*
G01Y-904400D02*
Y-919200D01*
G01D02*
X-2457000Y-921200D01*
G01D02*
X-2455100Y-923000D01*
G01D02*
X-2452200Y-924200D01*
G01D02*
X-2448600Y-924600D01*
G01D02*
X-2439500D01*
G01X-2452200Y-899400D02*
X-2455100Y-900600D01*
G01D02*
X-2457000Y-902300D01*
G01D02*
X-2457800Y-904400D01*
G01X-2439500Y-898900D02*
X-2448600D01*
G01D02*
X-2452200Y-899400D01*
G01X-2457800Y-591200D02*
X-2448600D01*
G01D02*
X-2445100Y-590200D01*
G01X-2457800Y-565400D02*
Y-591200D01*
G01X-2445100Y-566400D02*
X-2448600Y-565400D01*
G01D02*
X-2457800D01*
G01Y-232000D02*
Y-257700D01*
G01D02*
X-2439500D01*
G01X-2457800Y-244800D02*
X-2444900D01*
G01X-2439500Y-232000D02*
X-2457800D01*
G01Y71500D02*
Y97300D01*
G01Y84300D02*
X-2444900D01*
G01X-2457800Y97300D02*
X-2439500D01*
G01X-2455100Y408000D02*
X-2452900Y405800D01*
G01D02*
X-2450400Y405000D01*
G01D02*
X-2439500D01*
G01X-2455100Y427800D02*
X-2456700Y424200D01*
G01D02*
X-2457600Y420100D01*
G01D02*
Y415700D01*
G01D02*
X-2456700Y411400D01*
G01D02*
X-2455100Y408000D01*
G01X-2439500Y430700D02*
X-2450400D01*
G01D02*
X-2452900Y430000D01*
G01D02*
X-2455100Y427800D01*
G01X-2457800Y764100D02*
Y738400D01*
G01Y751300D02*
X-2439500D01*
G01X-2457800Y1079200D02*
X-2457000Y1076400D01*
G01D02*
X-2455100Y1074100D01*
G01D02*
X-2452200Y1072400D01*
G01D02*
X-2448600Y1072000D01*
G01D02*
X-2445100Y1072400D01*
G01X-2457800Y1433200D02*
Y1407500D01*
G01Y1418500D02*
X-2439500Y1433200D01*
G01X-2451400Y1423600D02*
X-2439500Y1407500D01*
G01X-2445100Y-1257600D02*
X-2442100Y-1256000D01*
G01D02*
X-2440100Y-1253600D01*
G01D02*
X-2439500Y-1250800D01*
G01D02*
X-2440100Y-1248000D01*
G01D02*
X-2442100Y-1245500D01*
G01D02*
X-2445100Y-1244000D01*
G01X-2445400Y-1242800D02*
X-2442900Y-1241300D01*
G01D02*
X-2441400Y-1239100D01*
G01D02*
Y-1236600D01*
G01D02*
X-2442900Y-1234400D01*
G01D02*
X-2445400Y-1232900D01*
G01X-2445100Y-590200D02*
X-2442100Y-587400D01*
G01D02*
X-2440100Y-583300D01*
G01D02*
X-2439500Y-578400D01*
G01D02*
X-2440100Y-573400D01*
G01D02*
X-2442100Y-569200D01*
G01D02*
X-2445100Y-566400D01*
G01X-2439500Y405000D02*
Y417900D01*
G01D02*
X-2446700D01*
G01X-2439500Y764100D02*
Y738400D01*
G01X-2445100Y1072400D02*
X-2442100Y1074100D01*
G01D02*
X-2440100Y1076400D01*
G01D02*
X-2439500Y1079200D01*
G01D02*
Y1097700D01*
G01X-2426900Y-1749600D02*
X2056300D01*
G01X-2426900Y1589100D02*
Y-1749600D01*
G01Y-1646700D02*
X-1914400D01*
G01X-2426900Y1589100D02*
X2056300D01*
G01X-2412400Y-1667400D02*
X-2405000D01*
G01D02*
X-2402700Y-1666800D01*
G01X-2412400Y-1657700D02*
Y-1674800D01*
G01X-2402700Y-1666800D02*
X-2400900Y-1665100D01*
G01D02*
X-2400200Y-1662600D01*
G01D02*
X-2400900Y-1660200D01*
G01D02*
X-2402700Y-1658400D01*
G01D02*
X-2405000Y-1657700D01*
G01D02*
X-2412400D01*
G01X-2389100D02*
X-2383000Y-1674800D01*
G01X-2395300D02*
X-2389100Y-1657700D01*
G01X-2394000Y-1671100D02*
X-2384400D01*
G01X-2378200Y-1667400D02*
X-2370800D01*
G01D02*
X-2368300Y-1666800D01*
G01X-2378200Y-1657700D02*
Y-1674800D01*
G01X-2365900D02*
X-2370800Y-1667400D01*
G01X-2361000Y-1657700D02*
X-2348800D01*
G01X-2368300Y-1666800D02*
X-2366500Y-1665100D01*
G01D02*
X-2365900Y-1662600D01*
G01D02*
X-2366500Y-1660200D01*
G01D02*
X-2368300Y-1658400D01*
G01D02*
X-2370800Y-1657700D01*
G01D02*
X-2378200D01*
G01X-2354800D02*
Y-1674800D01*
G01X-2325400D02*
Y-1657700D01*
G01D02*
X-2315700Y-1674800D01*
G01D02*
Y-1657700D01*
G01X-2309500Y-1662600D02*
Y-1671100D01*
G01Y-1669900D02*
X-2308600Y-1672400D01*
G01D02*
X-2306400Y-1674200D01*
G01Y-1658400D02*
X-2308600Y-1660200D01*
G01D02*
X-2309500Y-1662600D01*
G01X-2303400Y-1674800D02*
X-2300300Y-1674200D01*
G01D02*
X-2298100Y-1672400D01*
G01D02*
X-2297200Y-1669900D01*
G01D02*
Y-1661400D01*
G01X-2306400Y-1674200D02*
X-2303400Y-1674800D01*
G01X-2297200Y-1662600D02*
X-2298100Y-1660200D01*
G01D02*
X-2300300Y-1658400D01*
G01D02*
X-2303400Y-1657700D01*
G01D02*
X-2306400Y-1658400D01*
G01X-2284400Y-1673000D02*
X-2285100Y-1671600D01*
G01D02*
X-2286600Y-1671300D01*
G01D02*
X-2287900Y-1672200D01*
G01D02*
Y-1673800D01*
G01D02*
X-2286600Y-1674800D01*
G01D02*
X-2285100Y-1674500D01*
G01D02*
X-2284400Y-1673000D01*
G01X-2202600Y-1760400D02*
X-2206300Y-1762300D01*
G01X-2202600Y1625700D02*
X-2206300Y1623800D01*
G01X-2202600Y-1786000D02*
Y-1760400D01*
G01Y1600000D02*
Y1625700D01*
G01X-2176900Y-1786000D02*
Y-1760400D01*
G01D02*
X-2180600Y-1762300D01*
G01X-2176900Y1600000D02*
Y1625700D01*
G01D02*
X-2180600Y1623800D01*
G01X-2021500Y-1646700D02*
Y-1749600D01*
G01X-1996100Y-1672900D02*
X-2000500Y-1666400D01*
G01X-2007000Y-1657700D02*
Y-1672900D01*
G01X-1998300Y-1658300D02*
X-2000500Y-1657700D01*
G01X-1996700Y-1659900D02*
X-1998300Y-1658300D01*
G01X-1996100Y-1662100D02*
X-1996700Y-1659900D01*
G01Y-1664200D02*
X-1996100Y-1662100D01*
G01X-1998300Y-1665800D02*
X-1996700Y-1664200D01*
G01X-2000500Y-1666400D02*
X-1998300Y-1665800D01*
G01X-2000500Y-1657700D02*
X-2007000D01*
G01Y-1666400D02*
X-2000500D01*
G01X-1978200Y-1755800D02*
Y-1788700D01*
G01X-1991000Y-1657700D02*
Y-1672900D01*
G01D02*
X-1980100D01*
G01X-1991000Y-1665400D02*
X-1983300D01*
G01X-1980100Y-1657700D02*
X-1991000D01*
G01X-1978200Y1628200D02*
Y1595300D01*
G01X-1969600Y-1672900D02*
X-1964200Y-1657700D01*
G01X-1975100D02*
X-1969600Y-1672900D01*
G01X-1914400Y-1646700D02*
Y-1749600D01*
G01X-1751800Y-1786000D02*
Y-1760400D01*
G01D02*
X-1755500Y-1762300D01*
G01X-1751800Y1600000D02*
Y1625700D01*
G01D02*
X-1755500Y1623800D01*
G01X-1735000Y-1770500D02*
Y-1775900D01*
G01D02*
X-1733500Y-1780700D01*
G01D02*
X-1730700Y-1784400D01*
G01Y-1762100D02*
X-1733500Y-1765700D01*
G01D02*
X-1735000Y-1770500D01*
G01Y1615500D02*
Y1610200D01*
G01D02*
X-1733500Y1605200D01*
G01D02*
X-1730700Y1601600D01*
G01Y1623900D02*
X-1733500Y1620400D01*
G01D02*
X-1735000Y1615500D01*
G01X-1716800Y-1773200D02*
X-1717700Y-1768000D01*
G01X-1730700Y-1784400D02*
X-1727000Y-1786000D01*
G01D02*
X-1723200Y-1785500D01*
G01D02*
X-1719900Y-1782800D01*
G01D02*
X-1717700Y-1778500D01*
G01D02*
X-1716800Y-1773200D01*
G01X-1717700Y-1768000D02*
X-1719900Y-1763600D01*
G01D02*
X-1723200Y-1760900D01*
G01D02*
X-1727000Y-1760500D01*
G01D02*
X-1730700Y-1762100D01*
G01Y1601600D02*
X-1727000Y1600000D01*
G01D02*
X-1723200Y1600600D01*
G01D02*
X-1719900Y1603300D01*
G01D02*
X-1717700Y1607500D01*
G01D02*
X-1716800Y1612900D01*
G01D02*
X-1717700Y1618000D01*
G01D02*
X-1719900Y1622300D01*
G01D02*
X-1723200Y1625100D01*
G01D02*
X-1727000Y1625600D01*
G01D02*
X-1730700Y1623900D01*
G01X-1525300Y-1755800D02*
Y-1788700D01*
G01Y1628200D02*
Y1595300D01*
G01X-1302700Y-1786000D02*
X-1299000D01*
G01D02*
X-1296600Y-1785500D01*
G01X-1307400Y-1770400D02*
X-1305500Y-1771900D01*
G01D02*
X-1302500Y-1772900D01*
G01D02*
X-1299000Y-1773200D01*
G01D02*
X-1295400Y-1772900D01*
G01Y-1760800D02*
X-1299000Y-1760400D01*
G01D02*
X-1302500Y-1760800D01*
G01D02*
X-1305500Y-1762300D01*
G01D02*
X-1307400Y-1764300D01*
G01D02*
X-1308100Y-1766900D01*
G01D02*
Y-1768600D01*
G01D02*
X-1307400Y-1770400D01*
G01X-1302700Y1600000D02*
X-1299000D01*
G01Y1599900D02*
X-1296600Y1600600D01*
G01X-1295400Y1625100D02*
X-1299000Y1625700D01*
G01D02*
X-1302500Y1625100D01*
G01D02*
X-1305500Y1623800D01*
G01D02*
X-1307400Y1621700D01*
G01D02*
X-1308100Y1619200D01*
G01D02*
Y1617400D01*
G01D02*
X-1307400Y1615700D01*
G01D02*
X-1305500Y1614200D01*
G01D02*
X-1302500Y1613100D01*
G01D02*
X-1299000Y1612900D01*
G01D02*
X-1295400Y1613100D01*
G01X-1296600Y-1785500D02*
X-1294400Y-1783700D01*
G01D02*
X-1292500Y-1781000D01*
G01D02*
X-1291000Y-1777300D01*
G01D02*
X-1290100Y-1773200D01*
G01D02*
X-1289800Y-1768600D01*
G01X-1295400Y-1772900D02*
X-1292500Y-1771900D01*
G01D02*
X-1290400Y-1770400D01*
G01X-1289800Y-1768600D02*
Y-1766900D01*
G01D02*
X-1290400Y-1764300D01*
G01D02*
X-1292500Y-1762300D01*
G01D02*
X-1295400Y-1760800D01*
G01X-1290400Y-1770400D02*
X-1289800Y-1768600D01*
G01X-1296600Y1600600D02*
X-1294400Y1602200D01*
G01D02*
X-1292500Y1605000D01*
G01D02*
X-1291000Y1608700D01*
G01D02*
X-1290100Y1612900D01*
G01D02*
X-1289800Y1617400D01*
G01D02*
Y1619200D01*
G01D02*
X-1290400Y1621700D01*
G01D02*
X-1292500Y1623800D01*
G01D02*
X-1295400Y1625100D01*
G01Y1613100D02*
X-1292500Y1614200D01*
G01D02*
X-1290400Y1615700D01*
G01D02*
X-1289800Y1617400D01*
G01X-1072500Y-1755800D02*
Y-1788700D01*
G01Y1628200D02*
Y1595300D01*
G01X-848900Y-1771400D02*
X-851100Y-1772600D01*
G01D02*
X-853900Y-1774800D01*
G01D02*
X-855300Y-1777800D01*
G01D02*
X-854800Y-1780900D01*
G01D02*
X-853100Y-1783500D01*
G01D02*
X-850000Y-1785500D01*
G01D02*
X-846100Y-1786000D01*
G01D02*
X-842300Y-1785500D01*
G01X-848900Y-1771400D02*
X-843300D01*
G01X-842700Y-1760900D02*
X-846100Y-1760400D01*
G01D02*
X-849500Y-1760900D01*
G01D02*
X-852200Y-1762700D01*
G01D02*
X-853400Y-1765200D01*
G01D02*
X-852900Y-1767900D01*
G01D02*
X-851000Y-1770100D01*
G01D02*
X-848900Y-1771400D01*
G01X-853900Y1611200D02*
X-855300Y1608300D01*
G01D02*
X-854800Y1605200D01*
G01D02*
X-853100Y1602500D01*
G01D02*
X-850000Y1600600D01*
G01D02*
X-846100Y1600000D01*
G01D02*
X-842300Y1600600D01*
G01X-848900Y1614600D02*
X-843300D01*
G01X-842700Y1625000D02*
X-846100Y1625700D01*
G01D02*
X-849500Y1625000D01*
G01D02*
X-852200Y1623300D01*
G01D02*
X-853400Y1620800D01*
G01D02*
X-852900Y1618200D01*
G01D02*
X-851000Y1616000D01*
G01D02*
X-848900Y1614600D01*
G01D02*
X-851100Y1613400D01*
G01D02*
X-853900Y1611200D01*
G01X-842300Y-1785500D02*
X-839200Y-1783500D01*
G01D02*
X-837300Y-1780900D01*
G01D02*
X-837000Y-1777800D01*
G01D02*
X-838300Y-1774800D01*
G01D02*
X-841100Y-1772600D01*
G01D02*
X-843300Y-1771400D01*
G01D02*
X-841200Y-1770100D01*
G01D02*
X-839200Y-1767900D01*
G01D02*
X-838700Y-1765200D01*
G01D02*
X-840100Y-1762700D01*
G01D02*
X-842700Y-1760900D01*
G01X-842300Y1600600D02*
X-839200Y1602500D01*
G01D02*
X-837300Y1605200D01*
G01D02*
X-837000Y1608300D01*
G01D02*
X-838300Y1611200D01*
G01X-843300Y1614600D02*
X-841200Y1616000D01*
G01D02*
X-839200Y1618200D01*
G01D02*
X-838700Y1620800D01*
G01D02*
X-840100Y1623300D01*
G01D02*
X-842700Y1625000D01*
G01X-838300Y1611200D02*
X-841100Y1613400D01*
G01D02*
X-843300Y1614600D01*
G01X-619600Y-1755800D02*
Y-1788700D01*
G01Y1628200D02*
Y1595300D01*
G01X-384100Y-1760400D02*
X-393300Y-1782400D01*
G01D02*
Y-1786000D01*
G01X-402400Y-1760400D02*
X-384100D01*
G01Y1625700D02*
X-393300Y1603600D01*
G01D02*
Y1600000D01*
G01X-402400Y1625700D02*
X-384100D01*
G01X-368600Y1379100D02*
Y1589100D01*
G01Y1379100D02*
X2056300D01*
G01X1545800Y1420300D02*
X-368600D01*
G01X1545800Y1461500D02*
X-368600D01*
G01X1545800Y1502700D02*
X-368600D01*
G01X1545800Y1543900D02*
X-368600D01*
G01X-345900Y1573000D02*
Y1555900D01*
G01Y1563200D02*
X-338500D01*
G01Y1573000D02*
X-345900D01*
G01X-333600Y1555900D02*
X-338500Y1563200D01*
G01X-328700Y1573000D02*
Y1555900D01*
G01D02*
X-316500D01*
G01X-338500Y1563200D02*
X-336000Y1563800D01*
G01D02*
X-334200Y1565600D01*
G01D02*
X-333600Y1568100D01*
G01D02*
X-334200Y1570600D01*
G01D02*
X-336000Y1572400D01*
G01D02*
X-338500Y1573000D01*
G01X-328700Y1564400D02*
X-320200D01*
G01X-316500Y1573000D02*
X-328700D01*
G01X-311600D02*
Y1555900D01*
G01D02*
X-299400D01*
G01X-277300D02*
Y1573000D01*
G01Y1564400D02*
X-268700D01*
G01X-277300Y1573000D02*
X-265000D01*
G01X-259300Y1558400D02*
X-257100Y1556400D01*
G01D02*
X-254000Y1555900D01*
G01D02*
X-251000Y1556400D01*
G01Y1572400D02*
X-254000Y1573000D01*
G01D02*
X-257100Y1572400D01*
G01D02*
X-259300Y1570600D01*
G01D02*
X-260200Y1568100D01*
G01D02*
Y1559600D01*
G01Y1560700D02*
X-259300Y1558400D01*
G01X-251000Y1556400D02*
X-248800Y1558400D01*
G01X-243000Y1573000D02*
Y1555900D01*
G01X-247900Y1568100D02*
X-248800Y1570600D01*
G01D02*
X-251000Y1572400D01*
G01X-248800Y1558400D02*
X-247900Y1560700D01*
G01D02*
Y1569300D01*
G01X-243000Y1563200D02*
X-235700D01*
G01D02*
X-233100Y1563800D01*
G01Y1572400D02*
X-235700Y1573000D01*
G01D02*
X-243000D01*
G01X-230800Y1555900D02*
X-235700Y1563200D01*
G01X-233100Y1563800D02*
X-231400Y1565600D01*
G01D02*
X-230800Y1568100D01*
G01D02*
X-231400Y1570600D01*
G01D02*
X-233100Y1572400D01*
G01X-208600Y1555900D02*
X-202600Y1573000D01*
G01D02*
X-196400Y1555900D01*
G01X-207500Y1559600D02*
X-197700D01*
G01X-187500Y-1755800D02*
Y-1798900D01*
G01X-191500Y1555900D02*
X-185500D01*
G01D02*
X-182400Y1556400D01*
G01D02*
X-180100Y1557900D01*
G01X-179300Y1573000D02*
X-185500D01*
G01D02*
X-188400Y1572400D01*
G01D02*
X-190800Y1570900D01*
G01D02*
X-191500Y1568700D01*
G01D02*
X-190800Y1566600D01*
G01D02*
X-188400Y1565000D01*
G01D02*
X-185500Y1564400D01*
G01X-180100Y1562400D02*
X-182400Y1563800D01*
G01D02*
X-185500Y1564400D01*
G01Y1638500D02*
Y1595300D01*
G01X-180100Y1557900D02*
X-179300Y1560100D01*
G01X-174400Y1555900D02*
Y1573000D01*
G01X-179300Y1560100D02*
X-180100Y1562400D01*
G01X-174400Y1573000D02*
X-168300Y1559600D01*
G01D02*
X-162100Y1573000D01*
G01D02*
Y1555900D01*
G01X-120900Y-1749600D02*
Y-1407900D01*
G01X916500Y-1663000D02*
X-120900D01*
G01X2056300Y-1619900D02*
X-120900D01*
G01X916500Y-1576700D02*
X-120900D01*
G01X916500Y-1533400D02*
X-120900D01*
G01X916500Y-1490100D02*
X-120900D01*
G01X916500Y-1449100D02*
X-120900D01*
G01Y-1407900D02*
X2056300D01*
G01X-115500Y1589100D02*
Y1379100D01*
G01X-107900Y-1703100D02*
X-97000D01*
G01X-102500D02*
Y-1718300D01*
G01X-107900Y-1684000D02*
X-107200Y-1685900D01*
G01D02*
X-105100Y-1687300D01*
G01D02*
X-102500Y-1687900D01*
G01X-107900Y-1695400D02*
X-102500D01*
G01D02*
X-99800Y-1694900D01*
G01D02*
X-97700Y-1693500D01*
G01D02*
X-97000Y-1691500D01*
G01D02*
X-97700Y-1689800D01*
G01D02*
X-99800Y-1688300D01*
G01D02*
X-102500Y-1687900D01*
G01X-97000Y-1680200D02*
X-102500D01*
G01D02*
X-105100Y-1680800D01*
G01D02*
X-107200Y-1682100D01*
G01D02*
X-107900Y-1684000D01*
G01Y-1634800D02*
Y-1650200D01*
G01X-97000Y-1634800D02*
Y-1650200D01*
G01X-107900Y-1642500D02*
X-97000D01*
G01X-107900Y-1597000D02*
Y-1605800D01*
G01D02*
X-107500Y-1606900D01*
G01D02*
X-106300Y-1608000D01*
G01D02*
X-104500Y-1608700D01*
G01D02*
X-102500Y-1609000D01*
G01D02*
X-97000D01*
G01Y-1593800D02*
X-102500D01*
G01D02*
X-104500Y-1593900D01*
G01D02*
X-106300Y-1594700D01*
G01D02*
X-107500Y-1595700D01*
G01D02*
X-107900Y-1597000D01*
G01Y-1522500D02*
Y-1507300D01*
G01D02*
X-102500Y-1519200D01*
G01D02*
X-97000Y-1507300D01*
G01D02*
Y-1522500D01*
G01X-107900Y-1436100D02*
Y-1420900D01*
G01D02*
X-102500Y-1432900D01*
G01D02*
X-97000Y-1420900D01*
G01D02*
Y-1436100D01*
G01X-92700Y-1711800D02*
X-86100D01*
G01D02*
X-84000Y-1711200D01*
G01D02*
X-82400Y-1709600D01*
G01D02*
X-81800Y-1707300D01*
G01D02*
X-82400Y-1705300D01*
G01D02*
X-84000Y-1703700D01*
G01D02*
X-86100Y-1703100D01*
G01D02*
X-92700D01*
G01D02*
Y-1718300D01*
G01X-81800D02*
X-86100Y-1711800D01*
G01X-77400Y-1710600D02*
X-69800D01*
G01X-66600Y-1703100D02*
X-77400D01*
G01D02*
Y-1718300D01*
G01D02*
X-66600D01*
G01X-92700Y-1680200D02*
Y-1691100D01*
G01D02*
X-92000Y-1693200D01*
G01D02*
X-89900Y-1694800D01*
G01D02*
X-87300Y-1695400D01*
G01D02*
X-84500Y-1694800D01*
G01D02*
X-82500Y-1693200D01*
G01D02*
X-81800Y-1691100D01*
G01D02*
Y-1680200D01*
G01X-77400Y-1688900D02*
X-70900D01*
G01X-77400Y-1680200D02*
Y-1695400D01*
G01X-70900Y-1680200D02*
X-77400D01*
G01X-92700Y-1650200D02*
X-87300Y-1634800D01*
G01D02*
X-81800Y-1650200D01*
G01X-77400Y-1634800D02*
Y-1650200D01*
G01X-91500Y-1646800D02*
X-83000D01*
G01X-77400Y-1643600D02*
X-70900D01*
G01Y-1634800D02*
X-77400D01*
G01X-92700Y-1609000D02*
X-87300Y-1593800D01*
G01D02*
X-81800Y-1609000D01*
G01X-91500Y-1605800D02*
X-83000D01*
G01X-76800Y-1595600D02*
X-77400Y-1597500D01*
G01D02*
X-76800Y-1599400D01*
G01X-77400Y-1609000D02*
X-72100D01*
G01X-92700Y-1522500D02*
X-87300Y-1507300D01*
G01D02*
X-81800Y-1522500D01*
G01X-91500Y-1519200D02*
X-83000D01*
G01X-77400Y-1507300D02*
X-66600D01*
G01X-92700Y-1436100D02*
X-87300Y-1420900D01*
G01D02*
X-81800Y-1436100D01*
G01X-91500Y-1432900D02*
X-83000D01*
G01X-77400Y-1420900D02*
X-66600D01*
G01X-87900Y1558400D02*
X-85500Y1556400D01*
G01D02*
X-82500Y1555900D01*
G01D02*
X-79400Y1556400D01*
G01D02*
X-77200Y1558400D01*
G01X-82500Y1561900D02*
X-75200Y1554700D01*
G01X-77200Y1570600D02*
X-79400Y1572400D01*
G01D02*
X-82500Y1573000D01*
G01D02*
X-85500Y1572400D01*
G01D02*
X-87900Y1570600D01*
G01D02*
X-88600Y1568100D01*
G01D02*
Y1560700D01*
G01D02*
X-87900Y1558400D01*
G01X-62200Y-1718300D02*
X-56700Y-1703100D01*
G01X-61000Y-1715000D02*
X-52600D01*
G01X-70900Y-1688900D02*
X-68800Y-1688300D01*
G01D02*
X-67200Y-1686700D01*
G01D02*
X-66600Y-1684600D01*
G01D02*
X-67200Y-1682400D01*
G01X-66600Y-1695400D02*
X-70900Y-1688900D01*
G01X-62200Y-1687900D02*
X-54600D01*
G01X-62200Y-1695400D02*
Y-1680200D01*
G01X-67200Y-1682400D02*
X-68800Y-1680800D01*
G01D02*
X-70900Y-1680200D01*
G01X-62200D02*
X-51400D01*
G01X-66600Y-1650200D02*
X-70900Y-1643600D01*
G01X-62200Y-1650200D02*
X-56700D01*
G01X-62200Y-1634800D02*
Y-1650200D01*
G01X-70900Y-1643600D02*
X-68800Y-1643000D01*
G01D02*
X-67200Y-1641500D01*
G01D02*
X-66600Y-1639300D01*
G01D02*
X-67200Y-1637100D01*
G01D02*
X-68800Y-1635400D01*
G01D02*
X-70900Y-1634800D01*
G01X-56700D02*
X-62200D01*
G01X-76800Y-1599400D02*
X-74700Y-1600900D01*
G01D02*
X-72100Y-1601300D01*
G01Y-1609000D02*
X-69300Y-1608400D01*
G01D02*
X-67300Y-1607100D01*
G01D02*
X-66600Y-1605200D01*
G01D02*
X-67300Y-1603200D01*
G01D02*
X-69300Y-1601900D01*
G01D02*
X-72100Y-1601300D01*
G01X-62200D02*
X-54600D01*
G01X-62200Y-1593800D02*
Y-1609000D01*
G01D02*
X-51400D01*
G01X-66600Y-1593800D02*
X-72100D01*
G01D02*
X-74700Y-1594200D01*
G01D02*
X-76800Y-1595600D01*
G01X-51400Y-1593800D02*
X-62200D01*
G01X-72100Y-1507300D02*
Y-1522500D01*
G01Y-1420900D02*
Y-1436100D01*
G01X-62200Y-1428400D02*
X-54600D01*
G01X-62200Y-1420900D02*
Y-1436100D01*
G01D02*
X-51400D01*
G01Y-1420900D02*
X-62200D01*
G01X-65400Y1573000D02*
Y1555900D01*
G01X-76300Y1568100D02*
X-77200Y1570600D01*
G01Y1558400D02*
X-76300Y1560700D01*
G01D02*
Y1568100D01*
G01X-71500Y1573000D02*
X-59200D01*
G01X-56700Y-1703100D02*
X-51400Y-1718300D01*
G01X-47000Y-1703100D02*
X-36000D01*
G01X-47000Y-1695400D02*
X-41500Y-1680200D01*
G01X-45800Y-1692100D02*
X-37200D01*
G01X-56700Y-1650200D02*
X-54300Y-1649300D01*
G01X-45900Y-1650200D02*
Y-1634800D01*
G01X-54300Y-1649300D02*
X-52600Y-1647300D01*
G01D02*
X-51500Y-1644200D01*
G01D02*
Y-1640800D01*
G01D02*
X-52600Y-1637800D01*
G01D02*
X-54300Y-1635600D01*
G01D02*
X-56700Y-1634800D01*
G01X-45900D02*
X-37200Y-1650200D01*
G01X-57900Y-1512700D02*
X-55400Y-1506200D01*
G01X-47000Y-1507300D02*
Y-1522500D01*
G01D02*
X-36000D01*
G01X-47000Y-1429500D02*
X-40500D01*
G01X-47000Y-1420900D02*
Y-1436100D01*
G01X-40500Y-1420900D02*
X-47000D01*
G01X-48100Y1564400D02*
Y1555900D01*
G01X-54300Y1573000D02*
X-48100Y1564400D01*
G01D02*
X-42100Y1573000D01*
G01X-41500Y-1703100D02*
Y-1718300D01*
G01X-31700D02*
Y-1703100D01*
G01D02*
X-26300Y-1715000D01*
G01D02*
X-20800Y-1703100D01*
G01X-41500Y-1680200D02*
X-36000Y-1695400D01*
G01X-31700Y-1683400D02*
Y-1692100D01*
G01D02*
X-31300Y-1693500D01*
G01D02*
X-30100Y-1694500D01*
G01D02*
X-28400Y-1695200D01*
G01D02*
X-26300Y-1695400D01*
G01D02*
X-20800D01*
G01Y-1680200D02*
X-26300D01*
G01D02*
X-28400Y-1680500D01*
G01D02*
X-30100Y-1681200D01*
G01D02*
X-31300Y-1682200D01*
G01D02*
X-31700Y-1683400D01*
G01X-37200Y-1650200D02*
Y-1634800D01*
G01X-31700D02*
Y-1650200D01*
G01D02*
X-20800D01*
G01X-31700Y-1642500D02*
X-24100D01*
G01X-20800Y-1634800D02*
X-31700D01*
G01Y-1609000D02*
X-26300D01*
G01D02*
X-23900Y-1608300D01*
G01X-31700Y-1593800D02*
Y-1609000D01*
G01X-23900Y-1594500D02*
X-26300Y-1593800D01*
G01D02*
X-31700D01*
G01X-40500Y-1429500D02*
X-38200Y-1429000D01*
G01D02*
X-36600Y-1427400D01*
G01D02*
X-36000Y-1425200D01*
G01D02*
X-36600Y-1423000D01*
G01D02*
X-38200Y-1421300D01*
G01X-36000Y-1436100D02*
X-40500Y-1429500D01*
G01X-26300Y-1420900D02*
Y-1436100D01*
G01X-29500D02*
X-23000D01*
G01X-38200Y-1421300D02*
X-40500Y-1420900D01*
G01X-29500D02*
X-23000D01*
G01X-20800Y-1703100D02*
Y-1718300D01*
G01X-16500Y-1710600D02*
X-8900D01*
G01X-5600Y-1703100D02*
X-16500D01*
G01D02*
Y-1718300D01*
G01D02*
X-5600D01*
G01X-16500Y-1687900D02*
X-8900D01*
G01X-16500Y-1680200D02*
Y-1695400D01*
G01D02*
X-5600D01*
G01Y-1680200D02*
X-16500D01*
G01Y-1650200D02*
X-11100D01*
G01D02*
X-8400Y-1649600D01*
G01D02*
X-6300Y-1648300D01*
G01X-5600Y-1634800D02*
X-11100D01*
G01D02*
X-13700Y-1635400D01*
G01D02*
X-15800Y-1636800D01*
G01D02*
X-16500Y-1638700D01*
G01D02*
X-15800Y-1640600D01*
G01D02*
X-13700Y-1642100D01*
G01D02*
X-11100Y-1642500D01*
G01X-6300Y-1644400D02*
X-8400Y-1643000D01*
G01D02*
X-11100Y-1642500D01*
G01X-23900Y-1608300D02*
X-22000Y-1606100D01*
G01D02*
X-21000Y-1603100D01*
G01D02*
Y-1599700D01*
G01D02*
X-22000Y-1596600D01*
G01X-16500Y-1601300D02*
X-8900D01*
G01X-16500Y-1593800D02*
Y-1609000D01*
G01D02*
X-5600D01*
G01X-22000Y-1596600D02*
X-23900Y-1594500D01*
G01X-5600Y-1593800D02*
X-16500D01*
G01Y-1522500D02*
X-11100Y-1507300D01*
G01D02*
X-5600Y-1522500D01*
G01X-15400Y-1519200D02*
X-6800D01*
G01X-16500Y-1436100D02*
X-11100Y-1420900D01*
G01D02*
X-5600Y-1436100D01*
G01X-15400Y-1432900D02*
X-6800D01*
G01X-16700Y1589100D02*
Y1379100D01*
G01X-100Y-1718300D02*
Y-1703100D01*
G01D02*
X8600Y-1718300D01*
G01D02*
Y-1703100D01*
G01X-1300Y-1650200D02*
X4100D01*
G01D02*
X6900Y-1649600D01*
G01D02*
X8900Y-1648300D01*
G01X-6300D02*
X-5600Y-1646400D01*
G01D02*
X-6300Y-1644400D01*
G01X9600Y-1634800D02*
X4100D01*
G01D02*
X1500Y-1635400D01*
G01D02*
X-600Y-1636800D01*
G01D02*
X-1300Y-1638700D01*
G01D02*
X-600Y-1640600D01*
G01D02*
X1500Y-1642100D01*
G01D02*
X4100Y-1642500D01*
G01X8900Y-1648300D02*
X9600Y-1646400D01*
G01D02*
X8900Y-1644400D01*
G01D02*
X6900Y-1643000D01*
G01D02*
X4100Y-1642500D01*
G01X-1300Y-1602500D02*
X5300D01*
G01D02*
X7400Y-1601900D01*
G01D02*
X9000Y-1600300D01*
G01D02*
X9600Y-1598100D01*
G01D02*
X9000Y-1595900D01*
G01X-1300Y-1593800D02*
Y-1609000D01*
G01X9000Y-1595900D02*
X7400Y-1594400D01*
G01D02*
X5300Y-1593800D01*
G01D02*
X-1300D01*
G01Y-1507300D02*
Y-1522500D01*
G01D02*
X9600D01*
G01X-1300Y-1420900D02*
Y-1436100D01*
G01D02*
X9600D01*
G01X-5800Y1474200D02*
Y1489900D01*
G01D02*
X-100Y1477600D01*
G01D02*
X5500Y1489900D01*
G01D02*
Y1474200D01*
G01X9900D02*
X15500Y1489900D01*
G01X-5800Y1531100D02*
Y1515400D01*
G01D02*
X5500D01*
G01X9900Y1531100D02*
Y1515400D01*
G01D02*
X21100D01*
G01X-5800Y1523200D02*
X2100D01*
G01X5500Y1531100D02*
X-5800D01*
G01X8100Y1573000D02*
Y1555900D01*
G01X1900Y1573000D02*
X14200D01*
G01X14500Y-1769100D02*
X13600Y-1773300D01*
G01D02*
X13300Y-1777800D01*
G01D02*
Y-1779700D01*
G01D02*
X14000Y-1782100D01*
G01D02*
X15900Y-1784300D01*
G01D02*
X18900Y-1785600D01*
G01D02*
X22400Y-1786000D01*
G01D02*
X26000Y-1785600D01*
G01D02*
X28900Y-1784300D01*
G01Y-1773300D02*
X26000Y-1771900D01*
G01D02*
X22400Y-1771400D01*
G01D02*
X18900Y-1771900D01*
G01D02*
X15900Y-1773300D01*
G01D02*
X14000Y-1775400D01*
G01D02*
X13300Y-1777800D01*
G01X26100Y-1760400D02*
X22400D01*
G01D02*
X20100Y-1760900D01*
G01D02*
X17900Y-1762700D01*
G01D02*
X15900Y-1765500D01*
G01D02*
X14500Y-1769100D01*
G01X13900Y-1703100D02*
X24800D01*
G01X19300D02*
Y-1718300D01*
G01Y-1593800D02*
Y-1609000D01*
G01X13900Y-1593800D02*
X24800D01*
G01X19300Y-1507300D02*
Y-1522500D01*
G01X13900Y-1507300D02*
X24800D01*
G01X15500Y1489900D02*
X21100Y1474200D01*
G01X11100Y1477600D02*
X19900D01*
G01X25500Y1489900D02*
X36800D01*
G01X25500Y1531100D02*
Y1515400D01*
G01D02*
X36800D01*
G01X25500Y1523200D02*
X33400D01*
G01X36800Y1531100D02*
X25500D01*
G01X19000Y1573000D02*
Y1555900D01*
G01D02*
X31300D01*
G01X19000Y1564400D02*
X27600D01*
G01X31300Y1573000D02*
X19000D01*
G01X13600Y1612700D02*
X13300Y1608300D01*
G01D02*
Y1606400D01*
G01D02*
X14000Y1603800D01*
G01D02*
X15900Y1601800D01*
G01D02*
X18900Y1600500D01*
G01D02*
X22400Y1600000D01*
G01D02*
X26000Y1600500D01*
G01D02*
X28900Y1601800D01*
G01X14000Y1610600D02*
X13300Y1608300D01*
G01X26100Y1625700D02*
X22400D01*
G01D02*
X20100Y1625100D01*
G01D02*
X17900Y1623300D01*
G01D02*
X15900Y1620500D01*
G01D02*
X14500Y1617000D01*
G01D02*
X13600Y1612700D01*
G01X28900D02*
X26000Y1614200D01*
G01D02*
X22400Y1614600D01*
G01D02*
X18900Y1614200D01*
G01D02*
X15900Y1612700D01*
G01D02*
X14000Y1610600D01*
G01X28900Y-1784300D02*
X31000Y-1782100D01*
G01D02*
X31700Y-1779700D01*
G01D02*
Y-1777800D01*
G01D02*
X31000Y-1775400D01*
G01D02*
X28900Y-1773300D01*
G01X29200Y-1593800D02*
Y-1609000D01*
G01Y-1601300D02*
X40000D01*
G01Y-1593800D02*
Y-1609000D01*
G01X29200Y-1515000D02*
X36800D01*
G01X29200Y-1507300D02*
Y-1522500D01*
G01D02*
X40000D01*
G01X44400Y-1516000D02*
X50900D01*
G01X44400Y-1507300D02*
Y-1522500D01*
G01X40000Y-1507300D02*
X29200D01*
G01X50900D02*
X44400D01*
G01X30300Y-1436100D02*
Y-1420900D01*
G01D02*
X39000Y-1436100D01*
G01D02*
Y-1420900D01*
G01X45200Y-1423000D02*
X44400Y-1425200D01*
G01D02*
Y-1432900D01*
G01Y-1431700D02*
X45200Y-1433900D01*
G01X31200Y1489900D02*
Y1474200D01*
G01X41200Y1482000D02*
X49000D01*
G01X41200Y1489900D02*
Y1474200D01*
G01D02*
X52400D01*
G01Y1489900D02*
X41200D01*
G01Y1527700D02*
Y1518800D01*
G01D02*
X41600Y1517500D01*
G01D02*
X42800Y1516400D01*
G01D02*
X44600Y1515700D01*
G01D02*
X46800Y1515400D01*
G01Y1531100D02*
X44600Y1530800D01*
G01D02*
X42800Y1530200D01*
G01D02*
X41600Y1529000D01*
G01D02*
X41200Y1527700D01*
G01X36800Y1558100D02*
X38100Y1556900D01*
G01D02*
X40000Y1556200D01*
G01D02*
X42400Y1555900D01*
G01D02*
X48600D01*
G01Y1573000D02*
X42400D01*
G01D02*
X40000Y1572700D01*
G01D02*
X38100Y1572000D01*
G01D02*
X36800Y1570800D01*
G01D02*
X36300Y1569300D01*
G01D02*
Y1559600D01*
G01D02*
X36800Y1558100D01*
G01X28900Y1601800D02*
X31000Y1603800D01*
G01D02*
X31700Y1606400D01*
G01D02*
Y1608300D01*
G01D02*
X31000Y1610600D01*
G01D02*
X28900Y1612700D01*
G01X49900Y-1576700D02*
Y-1749600D01*
G01X397800Y-1706300D02*
X49900D01*
G01X50900Y-1516000D02*
X53200Y-1515400D01*
G01D02*
X54800Y-1513800D01*
G01D02*
X55200Y-1511700D01*
G01D02*
X54800Y-1509500D01*
G01X55200Y-1522500D02*
X50900Y-1516000D01*
G01X60700Y-1522500D02*
Y-1507300D01*
G01X54800Y-1509500D02*
X53200Y-1507900D01*
G01D02*
X50900Y-1507300D01*
G01X60700D02*
X69400Y-1522500D01*
G01X55200Y-1425200D02*
X54600Y-1423000D01*
G01D02*
X52600Y-1421300D01*
G01X47100D02*
X45200Y-1423000D01*
G01Y-1433900D02*
X47100Y-1435500D01*
G01D02*
X49900Y-1436100D01*
G01D02*
X52600Y-1435500D01*
G01D02*
X54600Y-1433900D01*
G01D02*
X55200Y-1431700D01*
G01D02*
Y-1424100D01*
G01X52600Y-1421300D02*
X49900Y-1420900D01*
G01D02*
X47100Y-1421300D01*
G01X56800Y1481000D02*
X63500D01*
G01X56800Y1489900D02*
Y1474200D01*
G01X63500Y1489900D02*
X56800D01*
G01X46800Y1515400D02*
X52400D01*
G01Y1531100D02*
X46800D01*
G01X56800D02*
X68100D01*
G01X53500Y1573000D02*
Y1555900D01*
G01Y1564400D02*
X65700D01*
G01X62900Y-1683400D02*
Y-1692100D01*
G01D02*
X63300Y-1693500D01*
G01D02*
X64500Y-1694500D01*
G01D02*
X66300Y-1695200D01*
G01D02*
X68400Y-1695400D01*
G01D02*
X73800D01*
G01X78800Y-1682400D02*
X78100Y-1684600D01*
G01D02*
Y-1692100D01*
G01Y-1691100D02*
X78800Y-1693300D01*
G01D02*
X80900Y-1694800D01*
G01X73800Y-1680200D02*
X68400D01*
G01D02*
X66300Y-1680500D01*
G01D02*
X64500Y-1681200D01*
G01D02*
X63300Y-1682200D01*
G01D02*
X62900Y-1683400D01*
G01X80900Y-1680800D02*
X78800Y-1682400D01*
G01X69400Y-1522500D02*
Y-1507300D01*
G01X74900Y-1522500D02*
X80300Y-1507300D01*
G01X76000Y-1519200D02*
X84600D01*
G01X66700Y-1434500D02*
X65900Y-1433000D01*
G01D02*
X64200D01*
G01D02*
X63500Y-1434500D01*
G01D02*
X64200Y-1435800D01*
G01D02*
X65900D01*
G01D02*
X66700Y-1434500D01*
G01X63500Y1481000D02*
X65700Y1481600D01*
G01D02*
X67300Y1483200D01*
G01D02*
X68100Y1485400D01*
G01D02*
X67300Y1487600D01*
G01D02*
X65700Y1489300D01*
G01X68100Y1474200D02*
X63500Y1481000D01*
G01X78100Y1489900D02*
Y1474200D01*
G01X74700D02*
X81400D01*
G01X65700Y1489300D02*
X63500Y1489900D01*
G01X74700D02*
X81400D01*
G01X62500Y1531100D02*
Y1515400D01*
G01X72500Y1522200D02*
X79100D01*
G01D02*
X81400Y1522800D01*
G01X72500Y1531100D02*
Y1515400D01*
G01X83600D02*
X79100Y1522200D01*
G01X81400Y1530500D02*
X79100Y1531100D01*
G01D02*
X72500D01*
G01X65700Y1573000D02*
Y1555900D01*
G01X71800D02*
Y1573000D01*
G01D02*
X81700Y1555900D01*
G01X89000Y-1684600D02*
X88300Y-1682400D01*
G01X80900Y-1694800D02*
X83600Y-1695400D01*
G01D02*
X86400Y-1694800D01*
G01D02*
X88300Y-1693300D01*
G01D02*
X89000Y-1691100D01*
G01D02*
Y-1683400D01*
G01X93500Y-1695400D02*
X98800D01*
G01X93500Y-1680200D02*
Y-1695400D01*
G01X88300Y-1682400D02*
X86400Y-1680800D01*
G01D02*
X83600Y-1680200D01*
G01D02*
X80900Y-1680800D01*
G01X98800Y-1680200D02*
X93500D01*
G01X80300Y-1507300D02*
X85800Y-1522500D01*
G01X95500Y-1507300D02*
Y-1522500D01*
G01X90100Y-1507300D02*
X101000D01*
G01X88200Y1474200D02*
X93800Y1489900D01*
G01D02*
X99200Y1474200D01*
G01X89300Y1477600D02*
X98000D01*
G01X81400Y1522800D02*
X83000Y1524400D01*
G01X93800Y1531100D02*
Y1515400D01*
G01X90400D02*
X97000D01*
G01X83000Y1524400D02*
X83600Y1526600D01*
G01D02*
X83000Y1528800D01*
G01D02*
X81400Y1530500D01*
G01X90400Y1531100D02*
X97000D01*
G01X81700Y1555900D02*
Y1573000D01*
G01X93900D02*
Y1555900D01*
G01X90200D02*
X97500D01*
G01X90200Y1573000D02*
X97500D01*
G01X98800Y-1695400D02*
X101100Y-1694600D01*
G01D02*
X103100Y-1692600D01*
G01D02*
X104100Y-1689500D01*
G01D02*
Y-1686100D01*
G01D02*
X103100Y-1683000D01*
G01X108700Y-1687900D02*
X116200D01*
G01X108700Y-1680200D02*
Y-1695400D01*
G01D02*
X119500D01*
G01X103100Y-1683000D02*
X101100Y-1680900D01*
G01D02*
X98800Y-1680200D01*
G01X119500D02*
X108700D01*
G01X105300Y-1515000D02*
X113000D01*
G01X105300Y-1507300D02*
Y-1522500D01*
G01D02*
X116200D01*
G01Y-1507300D02*
X105300D01*
G01X103800Y1489900D02*
Y1474200D01*
G01D02*
X114900D01*
G01X103800Y1527700D02*
Y1518800D01*
G01D02*
X104200Y1517500D01*
G01D02*
X105400Y1516400D01*
G01D02*
X107200Y1515700D01*
G01D02*
X109400Y1515400D01*
G01D02*
X114900D01*
G01Y1531100D02*
X109400D01*
G01D02*
X107200Y1530800D01*
G01D02*
X105400Y1530200D01*
G01D02*
X104200Y1529000D01*
G01D02*
X103800Y1527700D01*
G01X105300Y1558100D02*
X106600Y1556900D01*
G01D02*
X108700Y1556200D01*
G01D02*
X111000Y1555900D01*
G01D02*
X117100D01*
G01Y1573000D02*
X111000D01*
G01D02*
X108700Y1572700D01*
G01D02*
X106600Y1572000D01*
G01D02*
X105300Y1570800D01*
G01D02*
X104800Y1569300D01*
G01D02*
Y1559600D01*
G01D02*
X105300Y1558100D01*
G01X119500Y1515400D02*
X124900Y1531100D01*
G01D02*
X130500Y1515400D01*
G01X120600Y1518800D02*
X129300D01*
G01X122000Y1555900D02*
X128200Y1573000D01*
G01D02*
X134200Y1555900D01*
G01X123300Y1559600D02*
X133000D01*
G01X140100Y-1695400D02*
Y-1680200D01*
G01D02*
X148800Y-1695400D01*
G01D02*
Y-1680200D01*
G01X136900Y-1522500D02*
Y-1507300D01*
G01D02*
X145600Y-1522500D01*
G01D02*
Y-1507300D01*
G01X135100Y1531100D02*
Y1515400D01*
G01D02*
X146200D01*
G01X139200Y1573000D02*
Y1555900D01*
G01D02*
X151500D01*
G01X165200Y-1684600D02*
X164500Y-1682400D01*
G01X155000D02*
X154300Y-1684600D01*
G01D02*
Y-1692100D01*
G01Y-1691100D02*
X155000Y-1693300D01*
G01D02*
X157100Y-1694800D01*
G01D02*
X159800Y-1695400D01*
G01D02*
X162600Y-1694800D01*
G01D02*
X164500Y-1693300D01*
G01D02*
X165200Y-1691100D01*
G01D02*
Y-1683400D01*
G01X164500Y-1682400D02*
X162600Y-1680800D01*
G01D02*
X159800Y-1680200D01*
G01D02*
X157100Y-1680800D01*
G01D02*
X155000Y-1682400D01*
G01X162000Y-1511700D02*
X161200Y-1509500D01*
G01X151800D02*
X151100Y-1511700D01*
G01D02*
Y-1519200D01*
G01Y-1518200D02*
X151800Y-1520300D01*
G01D02*
X153700Y-1521900D01*
G01D02*
X156500Y-1522500D01*
G01D02*
X159200Y-1521900D01*
G01D02*
X161200Y-1520300D01*
G01D02*
X162000Y-1518200D01*
G01D02*
Y-1510500D01*
G01X161200Y-1509500D02*
X159200Y-1507900D01*
G01D02*
X156500Y-1507300D01*
G01D02*
X153700Y-1507900D01*
G01D02*
X151800Y-1509500D01*
G01X156200Y1543900D02*
Y1379100D01*
G01X176600Y-1693800D02*
X175900Y-1692400D01*
G01D02*
X174200D01*
G01D02*
X173300Y-1693800D01*
G01D02*
X174200Y-1695200D01*
G01D02*
X175900D01*
G01D02*
X176600Y-1693800D01*
G01X173300Y-1520900D02*
X172500Y-1519500D01*
G01D02*
X170800D01*
G01D02*
X170100Y-1520900D01*
G01D02*
X170800Y-1522300D01*
G01D02*
X172500D01*
G01D02*
X173300Y-1520900D01*
G01X173500Y1555900D02*
X179500Y1573000D01*
G01D02*
X185800Y1555900D01*
G01X174800Y1559600D02*
X184400D01*
G01X190600Y1573000D02*
Y1555900D01*
G01Y1563200D02*
X198000D01*
G01D02*
X200500Y1563800D01*
G01D02*
X202300Y1565600D01*
G01Y1570600D02*
X200500Y1572400D01*
G01D02*
X198000Y1573000D01*
G01D02*
X190600D01*
G01X207800D02*
Y1555900D01*
G01X202300Y1565600D02*
X202900Y1568100D01*
G01D02*
X202300Y1570600D01*
G01X207800Y1563200D02*
X215100D01*
G01D02*
X217600Y1563800D01*
G01D02*
X219400Y1565600D01*
G01Y1570600D02*
X217600Y1572400D01*
G01D02*
X215100Y1573000D01*
G01D02*
X207800D01*
G01X225000D02*
Y1555900D01*
G01X237100D02*
X232300Y1563200D01*
G01X219400Y1565600D02*
X220000Y1568100D01*
G01D02*
X219400Y1570600D01*
G01X225000Y1563200D02*
X232300D01*
G01D02*
X234800Y1563800D01*
G01D02*
X236500Y1565600D01*
G01D02*
X237100Y1568100D01*
G01D02*
X236500Y1570600D01*
G01D02*
X234800Y1572400D01*
G01D02*
X232300Y1573000D01*
G01D02*
X225000D01*
G01X248900Y-1755800D02*
Y-1788700D01*
G01X242900Y1558400D02*
X245100Y1556400D01*
G01D02*
X248200Y1555900D01*
G01D02*
X251300Y1556400D01*
G01D02*
X253500Y1558400D01*
G01X254400Y1568100D02*
X253500Y1570600D01*
G01D02*
X251300Y1572400D01*
G01D02*
X248200Y1573000D01*
G01D02*
X245100Y1572400D01*
G01D02*
X242900Y1570600D01*
G01D02*
X242200Y1568100D01*
G01D02*
Y1559600D01*
G01Y1560700D02*
X242900Y1558400D01*
G01X253500D02*
X254400Y1560700D01*
G01X248900Y1628200D02*
Y1595300D01*
G01X259300Y1573000D02*
X265300Y1555900D01*
G01D02*
X271500Y1573000D01*
G01X254400Y1560700D02*
Y1569300D01*
G01X276400Y1555900D02*
X282600Y1573000D01*
G01D02*
X288700Y1555900D01*
G01X277700Y1559600D02*
X287300D01*
G01X293500Y1573000D02*
Y1555900D01*
G01D02*
X305800D01*
G01X325100Y1543900D02*
Y1379100D01*
G01X397800Y-1749600D02*
Y-1407900D01*
G01X412100Y-1708100D02*
Y-1724600D01*
G01D02*
X418000D01*
G01D02*
X420800Y-1724000D01*
G01D02*
X423000Y-1722300D01*
G01D02*
X423800Y-1719900D01*
G01D02*
X423000Y-1717500D01*
G01D02*
X420800Y-1715800D01*
G01D02*
X418000Y-1715200D01*
G01D02*
X412100D01*
G01X418000D02*
X420200Y-1714700D01*
G01D02*
X422000Y-1713400D01*
G01D02*
X422600Y-1711600D01*
G01D02*
X422000Y-1709900D01*
G01D02*
X420200Y-1708700D01*
G01D02*
X418000Y-1708100D01*
G01D02*
X412100D01*
G01X410900Y-1685500D02*
X417900D01*
G01X410900Y-1678600D02*
Y-1692400D01*
G01D02*
X420800D01*
G01X425000D02*
X429800D01*
G01X425000Y-1678600D02*
Y-1692400D01*
G01X420800Y-1678600D02*
X410900D01*
G01X429800D02*
X425000D01*
G01X412800Y-1642500D02*
X419500D01*
G01D02*
X421600Y-1641900D01*
G01D02*
X423200Y-1640500D01*
G01D02*
X423800Y-1638200D01*
G01D02*
X423200Y-1636000D01*
G01D02*
X421600Y-1634400D01*
G01D02*
X419500Y-1633800D01*
G01D02*
X412800D01*
G01D02*
Y-1649200D01*
G01X423800D02*
X419500Y-1642500D01*
G01X428100Y-1649200D02*
X433500Y-1633800D01*
G01X412800Y-1605900D02*
X418300Y-1590700D01*
G01D02*
X423800Y-1605900D01*
G01X414000Y-1602700D02*
X422600D01*
G01X412800Y-1547400D02*
Y-1562600D01*
G01D02*
X423800D01*
G01X418300Y-1504600D02*
Y-1519100D01*
G01X427600Y-1508800D02*
Y-1516000D01*
G01Y-1515000D02*
X428300Y-1517000D01*
G01X413100Y-1504600D02*
X423500D01*
G01X428300Y-1506700D02*
X427600Y-1508800D01*
G01X413100Y-1437700D02*
Y-1423300D01*
G01D02*
X418300Y-1434600D01*
G01D02*
X423500Y-1423300D01*
G01D02*
Y-1437700D01*
G01X427600Y-1423300D02*
Y-1433600D01*
G01D02*
X428300Y-1435700D01*
G01X428500Y-1708100D02*
Y-1724600D01*
G01X440300D02*
X435600Y-1717500D01*
G01X445000Y-1708100D02*
Y-1724600D01*
G01D02*
X456700D01*
G01X428500Y-1717500D02*
X435600D01*
G01D02*
X437900Y-1716900D01*
G01D02*
X439700Y-1715200D01*
G01D02*
X440300Y-1712800D01*
G01D02*
X439700Y-1710400D01*
G01D02*
X437900Y-1708800D01*
G01D02*
X435600Y-1708100D01*
G01D02*
X428500D01*
G01X445000Y-1716400D02*
X453200D01*
G01X456700Y-1708100D02*
X445000D01*
G01X429800Y-1692400D02*
X432300Y-1691500D01*
G01D02*
X434300Y-1689000D01*
G01D02*
X434800Y-1685500D01*
G01D02*
X434300Y-1681900D01*
G01X439000Y-1683900D02*
Y-1687100D01*
G01D02*
X439700Y-1689900D01*
G01D02*
X441200Y-1691800D01*
G01D02*
X442800Y-1692400D01*
G01D02*
X448900D01*
G01Y-1685500D02*
X444900D01*
G01X434300Y-1681900D02*
X432300Y-1679400D01*
G01D02*
X429800Y-1678600D01*
G01X448900D02*
X442800D01*
G01D02*
X441200Y-1679100D01*
G01D02*
X439700Y-1681100D01*
G01D02*
X439000Y-1683900D01*
G01X433500Y-1633800D02*
X439000Y-1649200D01*
G01X429200Y-1645800D02*
X437800D01*
G01X443400Y-1649200D02*
X448700D01*
G01Y-1633800D02*
X443400D01*
G01D02*
Y-1649200D01*
G01X429200Y-1605900D02*
Y-1590700D01*
G01D02*
X437900Y-1605900D01*
G01D02*
Y-1590700D01*
G01X443400Y-1596600D02*
Y-1600000D01*
G01D02*
X444300Y-1603000D01*
G01D02*
X445800Y-1605200D01*
G01Y-1591400D02*
X444300Y-1593500D01*
G01D02*
X443400Y-1596600D01*
G01X433500Y-1547400D02*
Y-1562600D01*
G01X430300D02*
X436800D01*
G01X444400D02*
Y-1547400D01*
G01X430300D02*
X436800D01*
G01X444400D02*
X453200Y-1562600D01*
G01X428300Y-1517000D02*
X430100Y-1518500D01*
G01D02*
X432800Y-1519100D01*
G01D02*
X435300Y-1518500D01*
G01D02*
X437200Y-1517000D01*
G01D02*
X437900Y-1515000D01*
G01D02*
Y-1507700D01*
G01X441900Y-1504600D02*
Y-1519100D01*
G01D02*
X452300D01*
G01X437900Y-1508800D02*
X437200Y-1506700D01*
G01D02*
X435300Y-1505200D01*
G01D02*
X432800Y-1504600D01*
G01D02*
X430100Y-1505200D01*
G01D02*
X428300Y-1506700D01*
G01Y-1435700D02*
X430100Y-1437100D01*
G01D02*
X432800Y-1437700D01*
G01D02*
X435300Y-1437100D01*
G01D02*
X437200Y-1435700D01*
G01D02*
X437900Y-1433600D01*
G01D02*
Y-1423300D01*
G01X447100D02*
X444600Y-1423900D01*
G01D02*
X442700Y-1425000D01*
G01D02*
X441900Y-1427000D01*
G01D02*
X442700Y-1428700D01*
G01D02*
X444600Y-1430100D01*
G01D02*
X447100Y-1430500D01*
G01X441900Y-1437700D02*
X447100D01*
G01X461400Y-1724600D02*
X467300Y-1708100D01*
G01X462800Y-1721100D02*
X471900D01*
G01X448900Y-1692400D02*
Y-1685500D01*
G01X452900D02*
X459900D01*
G01X452900Y-1678600D02*
Y-1692400D01*
G01D02*
X462900D01*
G01Y-1678600D02*
X452900D01*
G01X448700Y-1649200D02*
X451100Y-1648300D01*
G01D02*
X453000Y-1646200D01*
G01D02*
X454000Y-1643100D01*
G01D02*
Y-1639900D01*
G01D02*
X453000Y-1636800D01*
G01D02*
X451100Y-1634700D01*
G01D02*
X448700Y-1633800D01*
G01X460800D02*
X467300D01*
G01X460800Y-1649200D02*
X467300D01*
G01X445800Y-1605200D02*
X447700Y-1605900D01*
G01D02*
X454200D01*
G01D02*
Y-1598200D01*
G01D02*
X449900D01*
G01X458600Y-1590700D02*
Y-1605900D01*
G01D02*
X469400D01*
G01X454200Y-1590700D02*
X447700D01*
G01D02*
X445800Y-1591400D01*
G01X453200Y-1562600D02*
Y-1547400D01*
G01X458600D02*
Y-1562600D01*
G01D02*
X469400D01*
G01X458600Y-1555000D02*
X466100D01*
G01X469400Y-1547400D02*
X458600D01*
G01X456400Y-1511900D02*
X463600D01*
G01X456400Y-1504600D02*
Y-1519100D01*
G01D02*
X466700D01*
G01Y-1504600D02*
X456400D01*
G01X452300Y-1423300D02*
X447100D01*
G01Y-1437700D02*
X449800Y-1437300D01*
G01D02*
X451500Y-1436000D01*
G01D02*
X452300Y-1434000D01*
G01D02*
X451500Y-1432300D01*
G01D02*
X449800Y-1430900D01*
G01D02*
X447100Y-1430500D01*
G01X456400Y-1423300D02*
X466700D01*
G01X461600D02*
Y-1437700D01*
G01X469800Y-1788000D02*
X480800Y-1783200D01*
G01X481800Y-1773100D02*
X478800Y-1771900D01*
G01D02*
X475300Y-1771400D01*
G01D02*
X466100D01*
G01D02*
X467900Y-1760400D01*
G01D02*
X482700D01*
G01X467300Y-1708100D02*
X473200Y-1724600D01*
G01X478000Y-1708100D02*
Y-1724600D01*
G01Y-1717500D02*
X489600Y-1708100D01*
G01X466900Y-1692400D02*
X476900Y-1678600D01*
G01X464100Y-1633800D02*
Y-1649200D01*
G01X476000Y-1633800D02*
X482500D01*
G01X479300D02*
Y-1649200D01*
G01X476000D02*
X482500D01*
G01X473800Y-1598200D02*
X481400D01*
G01X473800Y-1590700D02*
Y-1605900D01*
G01D02*
X484800D01*
G01Y-1590700D02*
X473800D01*
G01Y-1562600D02*
X479300Y-1547400D01*
G01D02*
X484800Y-1562600D01*
G01X475000Y-1559400D02*
X483600D01*
G01X470900Y-1512900D02*
X476900D01*
G01D02*
X479400Y-1512000D01*
G01D02*
X480900Y-1509900D01*
G01X470900Y-1504600D02*
Y-1519100D01*
G01X481100D02*
X476900Y-1512900D01*
G01X480900Y-1507400D02*
X479400Y-1505400D01*
G01D02*
X476900Y-1504600D01*
G01D02*
X470900D01*
G01X469800Y1598100D02*
X480800Y1602800D01*
G01X481800Y1613000D02*
X478800Y1614200D01*
G01D02*
X475300Y1614600D01*
G01D02*
X466100D01*
G01D02*
X467900Y1625700D01*
G01D02*
X482700D01*
G01X480800Y-1783200D02*
X482800Y-1781900D01*
G01D02*
X484200Y-1780400D01*
G01D02*
X484600Y-1778800D01*
G01D02*
Y-1776900D01*
G01D02*
X483900Y-1774800D01*
G01D02*
X481800Y-1773100D01*
G01X481900Y-1714300D02*
X489600Y-1724600D01*
G01X494400D02*
X500300D01*
G01Y-1708100D02*
X497300Y-1708700D01*
G01D02*
X495200Y-1710200D01*
G01D02*
X494400Y-1712200D01*
G01D02*
X495200Y-1714300D01*
G01D02*
X497300Y-1715800D01*
G01D02*
X500300Y-1716400D01*
G01X480900Y-1681500D02*
Y-1689500D01*
G01D02*
X481500Y-1691000D01*
G01D02*
X483400Y-1692100D01*
G01D02*
X485900Y-1692400D01*
G01D02*
X490800D01*
G01X494800Y-1682500D02*
Y-1689500D01*
G01Y-1688400D02*
X495500Y-1690500D01*
G01D02*
X497300Y-1692000D01*
G01D02*
X499800Y-1692400D01*
G01X490800Y-1678600D02*
X485900D01*
G01D02*
X483400Y-1678800D01*
G01D02*
X481500Y-1680000D01*
G01D02*
X480900Y-1681500D01*
G01X499800Y-1678600D02*
X497300Y-1679000D01*
G01D02*
X495500Y-1680500D01*
G01D02*
X494800Y-1682500D01*
G01X489800Y-1596300D02*
X491700Y-1597800D01*
G01D02*
X494500Y-1598200D01*
G01X489000Y-1605900D02*
X494500D01*
G01D02*
X497200Y-1605300D01*
G01D02*
X499200Y-1604000D01*
G01Y-1600100D02*
X497200Y-1598800D01*
G01D02*
X494500Y-1598200D01*
G01X500000Y-1590700D02*
X494500D01*
G01D02*
X491700Y-1591100D01*
G01D02*
X489800Y-1592600D01*
G01D02*
X489000Y-1594400D01*
G01D02*
X489800Y-1596300D01*
G01X489000Y-1547400D02*
Y-1562600D01*
G01Y-1556100D02*
X495500D01*
G01D02*
X497700Y-1555600D01*
G01D02*
X499400Y-1553900D01*
G01Y-1549700D02*
X497700Y-1548000D01*
G01D02*
X495500Y-1547400D01*
G01D02*
X489000D01*
G01X500000Y-1562600D02*
X495500Y-1556100D01*
G01X485200Y-1519100D02*
X490400Y-1504600D01*
G01D02*
X495500Y-1519100D01*
G01X486400Y-1516000D02*
X494400D01*
G01X480900Y-1509900D02*
Y-1507400D01*
G01X495500Y-1423300D02*
X490400D01*
G01D02*
X487900Y-1423700D01*
G01D02*
X485900Y-1424900D01*
G01D02*
X485200Y-1426400D01*
G01D02*
Y-1434600D01*
G01D02*
X485900Y-1436100D01*
G01D02*
X487900Y-1437300D01*
G01D02*
X490400Y-1437700D01*
G01D02*
X495500D01*
G01X480800Y1602800D02*
X482800Y1604000D01*
G01D02*
X484200Y1605600D01*
G01D02*
X484600Y1607200D01*
G01D02*
Y1609200D01*
G01D02*
X483900Y1611200D01*
G01D02*
X481800Y1613000D01*
G01X500300Y-1724600D02*
X503200Y-1724000D01*
G01D02*
X505400Y-1722600D01*
G01D02*
X506200Y-1720500D01*
G01D02*
X505400Y-1718400D01*
G01X506200Y-1708100D02*
X500300D01*
G01X505400Y-1718400D02*
X503200Y-1716900D01*
G01D02*
X500300Y-1716400D01*
G01X499800Y-1692400D02*
X502300Y-1692000D01*
G01D02*
X504200Y-1690500D01*
G01D02*
X504800Y-1688400D01*
G01D02*
Y-1681500D01*
G01X508800Y-1686500D02*
X514900D01*
G01D02*
X517200Y-1685800D01*
G01X508800Y-1678600D02*
Y-1692400D01*
G01X518900D02*
X514900Y-1686500D01*
G01X504800Y-1682500D02*
X504200Y-1680500D01*
G01D02*
X502300Y-1679000D01*
G01D02*
X499800Y-1678600D01*
G01X517200Y-1679300D02*
X514900Y-1678600D01*
G01D02*
X508800D01*
G01X504200Y-1633800D02*
Y-1644700D01*
G01D02*
X505000Y-1647000D01*
G01D02*
X507000Y-1648600D01*
G01D02*
X509700Y-1649200D01*
G01D02*
X512400Y-1648600D01*
G01D02*
X514400Y-1647000D01*
G01D02*
X515200Y-1644700D01*
G01D02*
Y-1633800D01*
G01X499200Y-1604000D02*
X500000Y-1602100D01*
G01D02*
X499200Y-1600100D01*
G01X499400Y-1553900D02*
X500000Y-1551700D01*
G01D02*
X499400Y-1549700D01*
G01X500700Y-1519100D02*
Y-1504600D01*
G01D02*
X509000Y-1519100D01*
G01D02*
Y-1504600D01*
G01X514000Y-1507700D02*
Y-1516000D01*
G01D02*
X514700Y-1517500D01*
G01D02*
X516600Y-1518600D01*
G01Y-1505100D02*
X514700Y-1506100D01*
G01D02*
X514000Y-1507700D01*
G01X509900Y-1427400D02*
X509300Y-1425300D01*
G01D02*
X507300Y-1423900D01*
G01D02*
X504800Y-1423300D01*
G01D02*
X502200Y-1423900D01*
G01D02*
X500300Y-1425300D01*
G01D02*
X499700Y-1427400D01*
G01D02*
Y-1434600D01*
G01Y-1433600D02*
X500300Y-1435700D01*
G01D02*
X502200Y-1437100D01*
G01D02*
X504800Y-1437700D01*
G01D02*
X507300Y-1437100D01*
G01D02*
X509300Y-1435700D01*
G01D02*
X509900Y-1433600D01*
G01D02*
Y-1426400D01*
G01X515000Y-1437700D02*
Y-1423300D01*
G01D02*
X523300Y-1437700D01*
G01X504100Y1589100D02*
Y1379100D01*
G01X517200Y-1685800D02*
X518700Y-1683700D01*
G01X523900Y-1692400D02*
Y-1678600D01*
G01D02*
X531900Y-1692400D01*
G01D02*
Y-1678600D01*
G01X518700Y-1683700D02*
Y-1681200D01*
G01D02*
X517200Y-1679300D01*
G01X520600Y-1649200D02*
Y-1633800D01*
G01D02*
X529300Y-1649200D01*
G01D02*
Y-1633800D01*
G01X524900Y-1590700D02*
Y-1602700D01*
G01X530400Y-1604700D02*
X519500D01*
G01Y-1597200D02*
X530400D01*
G01X524900Y-1547400D02*
Y-1559400D01*
G01X530400Y-1561600D02*
X519500D01*
G01Y-1553900D02*
X530400D01*
G01X516600Y-1518600D02*
X519200Y-1519100D01*
G01D02*
X524300D01*
G01X528500Y-1511900D02*
X535700D01*
G01X528500Y-1504600D02*
Y-1519100D01*
G01D02*
X538800D01*
G01X524300Y-1504600D02*
X519200D01*
G01D02*
X516600Y-1505100D01*
G01X538800Y-1504600D02*
X528500D01*
G01X523300Y-1437700D02*
Y-1423300D01*
G01X528500Y-1430500D02*
X535700D01*
G01X528500Y-1437700D02*
Y-1423300D01*
G01D02*
X538800D01*
G01X536900Y-1685500D02*
X543800D01*
G01X536900Y-1678600D02*
Y-1692400D01*
G01D02*
X546900D01*
G01Y-1678600D02*
X536900D01*
G01X534800Y-1633800D02*
Y-1649200D01*
G01D02*
X545600D01*
G01X550000Y-1641500D02*
X557500D01*
G01X560800Y-1633800D02*
X550000D01*
G01D02*
Y-1649200D01*
G01D02*
X560800D01*
G01X542900Y-1508200D02*
X543500Y-1510100D01*
G01D02*
X545400Y-1511300D01*
G01D02*
X547900Y-1511900D01*
G01X542900Y-1519100D02*
X547900D01*
G01D02*
X550600Y-1518500D01*
G01Y-1512300D02*
X547900Y-1511900D01*
G01X553100Y-1504600D02*
X547900D01*
G01D02*
X545400Y-1505100D01*
G01D02*
X543500Y-1506400D01*
G01D02*
X542900Y-1508200D01*
G01X550600Y-1423900D02*
X547900Y-1423300D01*
G01D02*
X545400Y-1423900D01*
G01D02*
X543500Y-1425300D01*
G01D02*
X542900Y-1427400D01*
G01D02*
Y-1434600D01*
G01Y-1433600D02*
X543500Y-1435700D01*
G01D02*
X545400Y-1437100D01*
G01D02*
X547900Y-1437700D01*
G01D02*
X550600Y-1437100D01*
G01X550900Y-1686500D02*
X556800D01*
G01D02*
X559200Y-1685800D01*
G01D02*
X560600Y-1683700D01*
G01X550900Y-1678600D02*
Y-1692400D01*
G01X560800D02*
X556800Y-1686500D01*
G01X560600Y-1683700D02*
Y-1681200D01*
G01D02*
X559200Y-1679300D01*
G01D02*
X556800Y-1678600D01*
G01D02*
X550900D01*
G01X567900Y-1634400D02*
X566000Y-1635700D01*
G01D02*
X565200Y-1637700D01*
G01D02*
X566000Y-1639600D01*
G01D02*
X567900Y-1641000D01*
G01X565200Y-1649200D02*
X570700D01*
G01X550600Y-1518500D02*
X552500Y-1517200D01*
G01D02*
X553100Y-1515400D01*
G01D02*
X552500Y-1513600D01*
G01D02*
X550600Y-1512300D01*
G01X553100Y-1427400D02*
X552500Y-1425300D01*
G01D02*
X550600Y-1423900D01*
G01Y-1437100D02*
X552500Y-1435700D01*
G01D02*
X553100Y-1433600D01*
G01D02*
Y-1426400D01*
G01X557300Y-1431500D02*
X563500D01*
G01D02*
X565800Y-1430800D01*
G01D02*
X567300Y-1428700D01*
G01D02*
Y-1426200D01*
G01D02*
X565800Y-1424100D01*
G01D02*
X563500Y-1423300D01*
G01D02*
X557300D01*
G01D02*
Y-1437700D01*
G01X567600D02*
X563500Y-1431500D01*
G01X570700Y-1663000D02*
Y-1749600D01*
G01X585000Y-1717700D02*
Y-1731700D01*
G01X581900D02*
X588000D01*
G01X916500Y-1706300D02*
X570700D01*
G01X581900Y-1717700D02*
X588000D01*
G01X578100Y-1681700D02*
Y-1688700D01*
G01Y-1687700D02*
X578700Y-1689800D01*
G01D02*
X580400Y-1691300D01*
G01D02*
X582900Y-1691700D01*
G01D02*
X585500Y-1691300D01*
G01Y-1678300D02*
X582900Y-1677700D01*
G01D02*
X580400Y-1678300D01*
G01D02*
X578700Y-1679700D01*
G01D02*
X578100Y-1681700D01*
G01X576200Y-1633800D02*
X570700D01*
G01D02*
X567900Y-1634400D01*
G01Y-1641000D02*
X570700Y-1641500D01*
G01Y-1649200D02*
X573300Y-1648600D01*
G01D02*
X575400Y-1647300D01*
G01D02*
X576200Y-1645300D01*
G01D02*
X575400Y-1643400D01*
G01D02*
X573300Y-1641900D01*
G01D02*
X570700Y-1641500D01*
G01X585900Y-1633800D02*
X583100Y-1634400D01*
G01D02*
X581200Y-1635700D01*
G01D02*
X580400Y-1637700D01*
G01D02*
X581200Y-1639600D01*
G01D02*
X583100Y-1641000D01*
G01D02*
X585900Y-1641500D01*
G01X580400Y-1649200D02*
X585900D01*
G01X571700Y-1504600D02*
Y-1515000D01*
G01D02*
X572300Y-1517000D01*
G01D02*
X574200Y-1518500D01*
G01D02*
X576900Y-1519100D01*
G01D02*
X579400Y-1518500D01*
G01D02*
X581300Y-1517000D01*
G01D02*
X581900Y-1515000D01*
G01D02*
Y-1504600D01*
G01X571700Y-1437700D02*
Y-1423300D01*
G01D02*
X576900Y-1434600D01*
G01D02*
X581900Y-1423300D01*
G01D02*
Y-1437700D01*
G01X578200Y1589100D02*
Y1379100D01*
G01X594900Y-1731700D02*
Y-1717700D01*
G01D02*
X603000Y-1731700D01*
G01X585500Y-1691300D02*
X587400Y-1689800D01*
G01D02*
X588000Y-1687700D01*
G01D02*
Y-1680800D01*
G01X592000Y-1677700D02*
Y-1687700D01*
G01D02*
X592700Y-1689800D01*
G01D02*
X594500Y-1691300D01*
G01D02*
X597000Y-1691700D01*
G01D02*
X599500Y-1691300D01*
G01D02*
X601400Y-1689800D01*
G01D02*
X602000Y-1687700D01*
G01D02*
Y-1677700D01*
G01X588000Y-1681700D02*
X587400Y-1679700D01*
G01D02*
X585500Y-1678300D01*
G01X591400Y-1633800D02*
X585900D01*
G01Y-1649200D02*
X588600Y-1648600D01*
G01D02*
X590600Y-1647300D01*
G01D02*
X591400Y-1645300D01*
G01D02*
X590600Y-1643400D01*
G01D02*
X588600Y-1641900D01*
G01D02*
X585900Y-1641500D01*
G01X587100Y-1519100D02*
Y-1504600D01*
G01D02*
X595300Y-1519100D01*
G01D02*
Y-1504600D01*
G01X600500D02*
Y-1519100D01*
G01D02*
X610900D01*
G01X600500Y-1423300D02*
X610900D01*
G01X588600Y1555900D02*
X594800D01*
G01D02*
X597400Y1556700D01*
G01D02*
X599500Y1559100D01*
G01X588600Y1573000D02*
Y1555900D01*
G01X599500Y1559100D02*
X600700Y1562500D01*
G01D02*
Y1566300D01*
G01D02*
X599500Y1569700D01*
G01D02*
X597400Y1572100D01*
G01D02*
X594800Y1573000D01*
G01D02*
X588600D01*
G01X603000Y-1731700D02*
Y-1717700D01*
G01X610400Y-1718300D02*
X608600Y-1719500D01*
G01D02*
X607900Y-1721200D01*
G01D02*
X608600Y-1723000D01*
G01D02*
X610400Y-1724300D01*
G01D02*
X612900Y-1724800D01*
G01X607900Y-1731700D02*
X612900D01*
G01D02*
X615400Y-1731300D01*
G01D02*
X617300Y-1729900D01*
G01D02*
X617900Y-1728200D01*
G01D02*
X617300Y-1726500D01*
G01D02*
X615400Y-1725200D01*
G01D02*
X612900Y-1724800D01*
G01X617900Y-1717700D02*
X612900D01*
G01D02*
X610400Y-1718300D01*
G01X611000Y-1677700D02*
Y-1691700D01*
G01X620000D02*
X625000D01*
G01X606000Y-1677700D02*
X616000D01*
G01X620600Y-1679400D02*
X620000Y-1681200D01*
G01D02*
X620600Y-1683000D01*
G01X612000Y-1649200D02*
Y-1633800D01*
G01D02*
X620700Y-1649200D01*
G01X614800Y-1511900D02*
X622100D01*
G01X614800Y-1504600D02*
Y-1519100D01*
G01D02*
X625200D01*
G01Y-1504600D02*
X614800D01*
G01X605700Y-1423300D02*
Y-1437700D01*
G01X622700Y-1423900D02*
X620000Y-1423300D01*
G01D02*
X617500Y-1423900D01*
G01D02*
X615600Y-1425300D01*
G01D02*
X614800Y-1427400D01*
G01D02*
Y-1434600D01*
G01Y-1433600D02*
X615600Y-1435700D01*
G01D02*
X617500Y-1437100D01*
G01D02*
X620000Y-1437700D01*
G01D02*
X622700Y-1437100D01*
G01X605800Y1555900D02*
X611900Y1573000D01*
G01D02*
X618100Y1555900D01*
G01X607000Y1559600D02*
X616800D01*
G01X626900Y-1717700D02*
Y-1731700D01*
G01X624000D02*
X629900D01*
G01X636000D02*
X641000D01*
G01X636000Y-1717700D02*
Y-1731700D01*
G01X624000Y-1717700D02*
X629900D01*
G01X641000D02*
X636000D01*
G01X620600Y-1683000D02*
X622500Y-1684300D01*
G01D02*
X625000Y-1684800D01*
G01Y-1691700D02*
X627500Y-1691300D01*
G01D02*
X629300Y-1689900D01*
G01D02*
X630000Y-1688200D01*
G01D02*
X629300Y-1686500D01*
G01D02*
X627500Y-1685200D01*
G01D02*
X625000Y-1684800D01*
G01X636000Y-1691700D02*
X642000D01*
G01X630000Y-1677700D02*
X625000D01*
G01D02*
X622500Y-1678300D01*
G01D02*
X620600Y-1679400D01*
G01X636000Y-1677700D02*
X642000D01*
G01X620700Y-1649200D02*
Y-1633800D01*
G01X637000Y-1638200D02*
X636200Y-1636000D01*
G01D02*
X634300Y-1634400D01*
G01D02*
X631500Y-1633800D01*
G01D02*
X628900Y-1634400D01*
G01D02*
X626800Y-1636000D01*
G01D02*
X626100Y-1638200D01*
G01D02*
Y-1645800D01*
G01Y-1644700D02*
X626800Y-1647000D01*
G01D02*
X628900Y-1648600D01*
G01D02*
X631500Y-1649200D01*
G01D02*
X634300Y-1648600D01*
G01D02*
X636200Y-1647000D01*
G01D02*
X637000Y-1644700D01*
G01D02*
Y-1637200D01*
G01X629300Y-1508200D02*
X630000Y-1510100D01*
G01D02*
X631800Y-1511300D01*
G01D02*
X634500Y-1511900D01*
G01X629300Y-1519100D02*
X634500D01*
G01D02*
X637000Y-1518500D01*
G01D02*
X638900Y-1517200D01*
G01Y-1513600D02*
X637000Y-1512300D01*
G01D02*
X634500Y-1511900D01*
G01X639600Y-1504600D02*
X634500D01*
G01D02*
X631800Y-1505100D01*
G01D02*
X630000Y-1506400D01*
G01D02*
X629300Y-1508200D01*
G01X625200Y-1427400D02*
X624400Y-1425300D01*
G01D02*
X622700Y-1423900D01*
G01Y-1437100D02*
X624400Y-1435700D01*
G01D02*
X625200Y-1433600D01*
G01D02*
Y-1426400D01*
G01X629000Y1573000D02*
Y1555900D01*
G01X623000Y1573000D02*
X635200D01*
G01X641000Y-1731700D02*
X643500Y-1730800D01*
G01D02*
X645300Y-1728200D01*
G01D02*
X646000Y-1724800D01*
G01D02*
X645300Y-1721200D01*
G01D02*
X643500Y-1718700D01*
G01X650000Y-1724800D02*
X656900D01*
G01X650000Y-1717700D02*
Y-1731700D01*
G01D02*
X659900D01*
G01X643500Y-1718700D02*
X641000Y-1717700D01*
G01X659900D02*
X650000D01*
G01X639100Y-1677700D02*
Y-1691700D01*
G01X648100D02*
X652900D01*
G01D02*
X655400Y-1690800D01*
G01X648100Y-1677700D02*
Y-1691700D01*
G01X655400Y-1678700D02*
X652900Y-1677700D01*
G01D02*
X648100D01*
G01X641400Y-1633800D02*
X652200D01*
G01X646700D02*
Y-1649200D01*
G01X638900Y-1517200D02*
X639600Y-1515400D01*
G01D02*
X638900Y-1513600D01*
G01X643800Y-1508200D02*
X644400Y-1510100D01*
G01D02*
X646300Y-1511300D01*
G01D02*
X648800Y-1511900D01*
G01X643800Y-1519100D02*
X648800D01*
G01D02*
X651500Y-1518500D01*
G01D02*
X653400Y-1517200D01*
G01D02*
X654000Y-1515400D01*
G01D02*
X653400Y-1513600D01*
G01D02*
X651500Y-1512300D01*
G01D02*
X648800Y-1511900D01*
G01X654000Y-1504600D02*
X648800D01*
G01D02*
X646300Y-1505100D01*
G01D02*
X644400Y-1506400D01*
G01D02*
X643800Y-1508200D01*
G01Y-1430500D02*
X650900D01*
G01X654000Y-1423300D02*
X643800D01*
G01D02*
Y-1437700D01*
G01D02*
X654000D01*
G01X640100Y1573000D02*
Y1555900D01*
G01D02*
X652300D01*
G01X640100Y1564400D02*
X648700D01*
G01X652300Y1573000D02*
X640100D01*
G01X655400Y-1690800D02*
X657400Y-1688200D01*
G01D02*
X658000Y-1684800D01*
G01D02*
X657400Y-1681200D01*
G01X661900Y-1684800D02*
X669000D01*
G01X661900Y-1677700D02*
Y-1691700D01*
G01D02*
X672000D01*
G01X657400Y-1681200D02*
X655400Y-1678700D01*
G01X672000Y-1677700D02*
X661900D01*
G01X656600Y-1641500D02*
X664200D01*
G01X667400Y-1633800D02*
X656600D01*
G01D02*
Y-1649200D01*
G01D02*
X667400D01*
G01X671800D02*
X677300D01*
G01Y-1633800D02*
X671800D01*
G01D02*
Y-1649200D01*
G01X659100Y-1437700D02*
Y-1423300D01*
G01D02*
X667400Y-1437700D01*
G01D02*
Y-1423300D01*
G01X677900Y-1731700D02*
Y-1717700D01*
G01D02*
X682900Y-1728800D01*
G01D02*
X687900Y-1717700D01*
G01D02*
Y-1731700D01*
G01X677300Y-1649200D02*
X679700Y-1648300D01*
G01D02*
X681600Y-1646200D01*
G01D02*
X682600Y-1643100D01*
G01D02*
Y-1639900D01*
G01D02*
X681600Y-1636800D01*
G01D02*
X679700Y-1634700D01*
G01D02*
X677300Y-1633800D01*
G01X673600Y-1519100D02*
Y-1504600D01*
G01D02*
X681700Y-1519100D01*
G01D02*
Y-1504600D01*
G01X686900Y-1508800D02*
Y-1516000D01*
G01Y-1515000D02*
X687600Y-1517000D01*
G01D02*
X689600Y-1518500D01*
G01D02*
X692100Y-1519100D01*
G01Y-1504600D02*
X689600Y-1505200D01*
G01D02*
X687600Y-1506700D01*
G01D02*
X686900Y-1508800D01*
G01X682800Y-1423300D02*
X676700D01*
G01D02*
X674900Y-1424000D01*
G01D02*
X673500Y-1426100D01*
G01D02*
X672600Y-1428900D01*
G01D02*
Y-1432100D01*
G01D02*
X673500Y-1434900D01*
G01D02*
X674900Y-1437000D01*
G01D02*
X676700Y-1437700D01*
G01D02*
X682800D01*
G01D02*
Y-1430500D01*
G01D02*
X678800D01*
G01X701800Y-1755800D02*
Y-1788700D01*
G01X691900Y-1731700D02*
X696900Y-1717700D01*
G01D02*
X702000Y-1731700D01*
G01X692900Y-1728800D02*
X700900D01*
G01X705900Y-1731700D02*
X716000Y-1717700D01*
G01Y-1731700D02*
X705900Y-1717700D01*
G01X690000Y-1691700D02*
Y-1677700D01*
G01D02*
X695000Y-1688700D01*
G01D02*
X700000Y-1677700D01*
G01D02*
Y-1691700D01*
G01X704000D02*
X709000Y-1677700D01*
G01X705100Y-1688700D02*
X712900D01*
G01X692100Y-1519100D02*
X694700Y-1518500D01*
G01D02*
X696500Y-1517000D01*
G01D02*
X697200Y-1515000D01*
G01D02*
Y-1507700D01*
G01X706500Y-1504600D02*
Y-1519100D01*
G01X697200Y-1508800D02*
X696500Y-1506700D01*
G01D02*
X694700Y-1505200D01*
G01D02*
X692100Y-1504600D01*
G01X701400D02*
X711700D01*
G01Y-1423300D02*
X706500D01*
G01D02*
X703900Y-1423900D01*
G01D02*
X702100Y-1425000D01*
G01D02*
X701400Y-1427000D01*
G01D02*
X702100Y-1428700D01*
G01D02*
X703900Y-1430100D01*
G01D02*
X706500Y-1430500D01*
G01X701400Y-1437700D02*
X706500D01*
G01D02*
X709000Y-1437300D01*
G01Y-1430900D02*
X706500Y-1430500D01*
G01X701800Y1628200D02*
Y1595300D01*
G01X709000Y-1677700D02*
X713900Y-1691700D01*
G01X717900D02*
X727900Y-1677700D01*
G01Y-1691700D02*
X717900Y-1677700D01*
G01X715700Y-1511900D02*
X722900D01*
G01X715700Y-1504600D02*
Y-1519100D01*
G01D02*
X726000D01*
G01Y-1504600D02*
X715700D01*
G01X709000Y-1437300D02*
X711000Y-1436000D01*
G01D02*
X711700Y-1434000D01*
G01D02*
X711000Y-1432300D01*
G01D02*
X709000Y-1430900D01*
G01X715700Y-1431500D02*
X721900D01*
G01D02*
X724400Y-1430800D01*
G01D02*
X725900Y-1428700D01*
G01Y-1426200D02*
X724400Y-1424100D01*
G01D02*
X721900Y-1423300D01*
G01D02*
X715700D01*
G01D02*
Y-1437700D01*
G01X730200Y-1519100D02*
X735300D01*
G01D02*
X737800Y-1518100D01*
G01D02*
X739800Y-1515400D01*
G01D02*
X740500Y-1511900D01*
G01D02*
X739800Y-1508200D01*
G01X730200Y-1504600D02*
Y-1519100D01*
G01X739800Y-1508200D02*
X737800Y-1505500D01*
G01D02*
X735300Y-1504600D01*
G01D02*
X730200D01*
G01X725900Y-1428700D02*
Y-1426200D01*
G01X730200Y-1430500D02*
X737400D01*
G01X740500Y-1423300D02*
X730200D01*
G01D02*
Y-1437700D01*
G01D02*
X740500D01*
G01X743600Y-1533400D02*
Y-1749600D01*
G01X754800Y-1423300D02*
X749600D01*
G01D02*
X747100Y-1423700D01*
G01D02*
X745200Y-1424900D01*
G01D02*
X744600Y-1426400D01*
G01D02*
Y-1434600D01*
G01D02*
X745200Y-1436100D01*
G01D02*
X747100Y-1437300D01*
G01D02*
X749600Y-1437700D01*
G01D02*
X754800D01*
G01X759400Y1589100D02*
Y1379100D01*
G01X765700Y-1430500D02*
X764900Y-1429200D01*
G01D02*
X763400D01*
G01D02*
X762600Y-1430500D01*
G01D02*
X763400Y-1431800D01*
G01D02*
X764900D01*
G01D02*
X765700Y-1430500D01*
G01Y-1435700D02*
X764900Y-1434300D01*
G01D02*
X763400D01*
G01D02*
X762600Y-1435700D01*
G01D02*
X763400Y-1437000D01*
G01D02*
X764900D01*
G01D02*
X765700Y-1435700D01*
G01X769700Y1573000D02*
Y1555900D01*
G01D02*
X782000D01*
G01X769700Y1564400D02*
X778300D01*
G01X782000Y1573000D02*
X769700D01*
G01X787400Y1558100D02*
X788800Y1556900D01*
G01D02*
X790700Y1556200D01*
G01D02*
X793100Y1555900D01*
G01D02*
X799100D01*
G01Y1573000D02*
X793100D01*
G01D02*
X790700Y1572700D01*
G01D02*
X788800Y1572000D01*
G01D02*
X787400Y1570800D01*
G01D02*
X786900Y1569300D01*
G01D02*
Y1559600D01*
G01D02*
X787400Y1558100D01*
G01X822400Y1555900D02*
Y1573000D01*
G01D02*
X832200Y1555900D01*
G01D02*
Y1573000D01*
G01X839100Y1558400D02*
X841500Y1556400D01*
G01D02*
X844400Y1555900D01*
G01D02*
X847500Y1556400D01*
G01Y1572400D02*
X844400Y1573000D01*
G01D02*
X841500Y1572400D01*
G01D02*
X839100Y1570600D01*
G01D02*
X838400Y1568100D01*
G01D02*
Y1559600D01*
G01Y1560700D02*
X839100Y1558400D01*
G01X847500Y1556400D02*
X849800Y1558400D01*
G01X863500Y1557600D02*
X862800Y1559100D01*
G01X859900Y1558500D02*
Y1556900D01*
G01D02*
X861300Y1555900D01*
G01D02*
X862800Y1556300D01*
G01D02*
X863500Y1557600D01*
G01X850600Y1568100D02*
X849800Y1570600D01*
G01D02*
X847500Y1572400D01*
G01X849800Y1558400D02*
X850600Y1560700D01*
G01D02*
Y1569300D01*
G01X862800Y1559100D02*
X861300Y1559600D01*
G01D02*
X859900Y1558500D01*
G01X931900Y-1786000D02*
Y-1760400D01*
G01X919000Y-1764000D02*
Y-1776900D01*
G01D02*
X937500D01*
G01X916500Y-1749600D02*
Y-1407900D01*
G01X930400Y-1721200D02*
X934200D01*
G01X930400Y-1710900D02*
Y-1721200D01*
G01Y-1705700D02*
Y-1695400D01*
G01D02*
X934200Y-1703500D01*
G01Y-1710900D02*
X930400D01*
G01Y-1685200D02*
X935700D01*
G01X930400Y-1690200D02*
Y-1680000D01*
G01Y-1674900D02*
X934200Y-1664500D01*
G01X931300Y-1672600D02*
X937200D01*
G01X930400Y-1680000D02*
X938100D01*
G01X932000Y-1659400D02*
X936400D01*
G01X930400Y-1633700D02*
X938100D01*
G01X932000Y-1649200D02*
X936400D01*
G01X931900Y1600000D02*
Y1625700D01*
G01X919000Y1622000D02*
Y1609200D01*
G01D02*
X937500D01*
G01X934200Y-1721200D02*
X936100Y-1720500D01*
G01D02*
X937500Y-1718600D01*
G01X941000Y-1710900D02*
Y-1721200D01*
G01D02*
X948500D01*
G01X934200Y-1703500D02*
X938100Y-1695400D01*
G01D02*
Y-1705700D01*
G01X941700Y-1695400D02*
Y-1702800D01*
G01D02*
X942500Y-1704500D01*
G01D02*
X944400Y-1705600D01*
G01D02*
X946800D01*
G01D02*
X948500Y-1704500D01*
G01D02*
X949300Y-1702800D01*
G01D02*
Y-1695400D01*
G01X937500Y-1718600D02*
X938100Y-1716100D01*
G01D02*
X937500Y-1713400D01*
G01D02*
X936100Y-1711600D01*
G01D02*
X934200Y-1710900D01*
G01X941000Y-1716100D02*
X946300D01*
G01X948500Y-1710900D02*
X941000D01*
G01X941500Y-1683000D02*
Y-1688200D01*
G01Y-1687400D02*
X942200Y-1689000D01*
G01D02*
X944100Y-1690100D01*
G01D02*
X946500D01*
G01D02*
X948400Y-1689000D01*
G01D02*
X949100Y-1687400D01*
G01D02*
Y-1682200D01*
G01X934200Y-1664500D02*
X938100Y-1674900D01*
G01X949100Y-1683000D02*
X948400Y-1681200D01*
G01D02*
X946500Y-1680200D01*
G01D02*
X944100D01*
G01D02*
X942200Y-1681200D01*
G01D02*
X941500Y-1683000D01*
G01X934200Y-1649200D02*
Y-1659400D01*
G01X947100Y-1649200D02*
Y-1659400D01*
G01X934200Y-1633700D02*
Y-1644000D01*
G01X941000Y-1633700D02*
Y-1644000D01*
G01Y-1638800D02*
X948500D01*
G01Y-1633700D02*
Y-1644000D01*
G01X943200Y-1649200D02*
X950800D01*
G01X951600Y-1710900D02*
Y-1721200D01*
G01X962300D02*
X966000Y-1710900D01*
G01X953100Y-1705700D02*
X956800D01*
G01D02*
X959200Y-1705300D01*
G01D02*
X960500Y-1704000D01*
G01D02*
Y-1702300D01*
G01D02*
X959200Y-1701000D01*
G01X968200Y-1695400D02*
Y-1705700D01*
G01X951600Y-1716800D02*
X956200D01*
G01D02*
X958000Y-1716200D01*
G01D02*
X959000Y-1714700D01*
G01D02*
Y-1713000D01*
G01D02*
X958000Y-1711500D01*
G01D02*
X956200Y-1710900D01*
G01D02*
X951600D01*
G01X966000D02*
X969800Y-1721200D01*
G01X963000Y-1719000D02*
X968900D01*
G01X952500Y-1685900D02*
X957100D01*
G01D02*
X958900Y-1685300D01*
G01D02*
X960100Y-1683900D01*
G01X952500Y-1680000D02*
Y-1690200D01*
G01X960200D02*
X957100Y-1685900D01*
G01X963600Y-1690200D02*
Y-1680000D01*
G01D02*
X967400Y-1688200D01*
G01D02*
X971300Y-1680000D01*
G01X960600Y-1695400D02*
X956800D01*
G01D02*
X954600Y-1696000D01*
G01D02*
X953300Y-1697200D01*
G01D02*
Y-1698800D01*
G01D02*
X954600Y-1700100D01*
G01D02*
X956800Y-1700600D01*
G01X959200Y-1701000D02*
X956800Y-1700600D01*
G01X964500Y-1695400D02*
X972000D01*
G01X956100Y-1670400D02*
X960600D01*
G01D02*
X962400Y-1669800D01*
G01D02*
X963500Y-1668400D01*
G01D02*
Y-1666600D01*
G01X956100Y-1664500D02*
Y-1674900D01*
G01X963600D02*
X960600Y-1670400D01*
G01X960100Y-1683900D02*
Y-1682100D01*
G01D02*
X958900Y-1680600D01*
G01D02*
X957100Y-1680000D01*
G01D02*
X952500D01*
G01X959900Y-1649200D02*
X957700Y-1649600D01*
G01D02*
X956200Y-1650900D01*
G01D02*
Y-1652400D01*
G01D02*
X957700Y-1653700D01*
G01D02*
X959900Y-1654300D01*
G01X956100Y-1659400D02*
X959900D01*
G01D02*
X962100Y-1658900D01*
G01D02*
X963500Y-1657600D01*
G01D02*
Y-1656100D01*
G01D02*
X962100Y-1654800D01*
G01D02*
X959900Y-1654300D01*
G01X963500Y-1666600D02*
X962400Y-1665100D01*
G01D02*
X960600Y-1664500D01*
G01D02*
X956100D01*
G01X953100Y-1633700D02*
X957700D01*
G01X955300D02*
Y-1644000D01*
G01X953100D02*
X957700D01*
G01X969800Y-1633700D02*
X966000D01*
G01D02*
X963700Y-1634100D01*
G01D02*
X962400Y-1635400D01*
G01D02*
Y-1637100D01*
G01D02*
X963700Y-1638400D01*
G01D02*
X966000Y-1638800D01*
G01X962300Y-1644000D02*
X966000D01*
G01D02*
X968200Y-1643400D01*
G01D02*
X969700Y-1642200D01*
G01Y-1640600D02*
X968200Y-1639300D01*
G01D02*
X966000Y-1638800D01*
G01X963600Y-1649200D02*
X959900D01*
G01X972800Y-1710900D02*
Y-1721200D01*
G01X980400D02*
X977300Y-1716800D01*
G01X972800D02*
X977300D01*
G01D02*
X979100Y-1716200D01*
G01D02*
X980300Y-1714700D01*
G01D02*
Y-1713000D01*
G01D02*
X979100Y-1711500D01*
G01D02*
X977300Y-1710900D01*
G01D02*
X972800D01*
G01X983400D02*
X990900D01*
G01X971300Y-1680000D02*
Y-1690200D01*
G01X974700D02*
X978500Y-1680000D01*
G01D02*
X982400Y-1690200D01*
G01X975600Y-1688200D02*
X981500D01*
G01X968900Y-1669700D02*
X974200D01*
G01X968900Y-1664500D02*
Y-1674900D01*
G01D02*
X976400D01*
G01X982500Y-1665700D02*
X981800Y-1667500D01*
G01D02*
Y-1671900D01*
G01D02*
X982500Y-1673700D01*
G01D02*
X984400Y-1674700D01*
G01D02*
X986600D01*
G01X985500Y-1671200D02*
X990000Y-1675600D01*
G01X981800Y-1649200D02*
Y-1656400D01*
G01D02*
X982500Y-1658200D01*
G01D02*
X984400Y-1659200D01*
G01D02*
X986600D01*
G01X976400Y-1664500D02*
X968900D01*
G01X986600Y-1664700D02*
X984400D01*
G01D02*
X982500Y-1665700D01*
G01X969700Y-1642200D02*
Y-1640600D01*
G01X983400Y-1644000D02*
X987200D01*
G01Y-1633700D02*
X983400D01*
G01D02*
Y-1644000D01*
G01X987200Y-1710900D02*
Y-1721200D01*
G01X994000D02*
Y-1710900D01*
G01X1001500D02*
Y-1721200D01*
G01X987100Y-1695400D02*
Y-1705700D01*
G01D02*
X990900D01*
G01D02*
X993100Y-1705100D01*
G01D02*
X994500Y-1703700D01*
G01D02*
Y-1701900D01*
G01D02*
X993100Y-1700400D01*
G01X998400Y-1695400D02*
Y-1705700D01*
G01D02*
X1006000D01*
G01X994000Y-1710900D02*
X997900Y-1719000D01*
G01D02*
X1001500Y-1710900D01*
G01X986600Y-1690200D02*
Y-1680000D01*
G01D02*
X992700Y-1690200D01*
G01D02*
Y-1680000D01*
G01X997000Y-1682200D02*
Y-1688200D01*
G01D02*
X997400Y-1689200D01*
G01D02*
X998700Y-1689900D01*
G01D02*
X1000700Y-1690200D01*
G01D02*
X1004500D01*
G01X993100Y-1700400D02*
X990900Y-1699800D01*
G01D02*
X987100D01*
G01X990900D02*
X992700Y-1699400D01*
G01D02*
X993700Y-1698300D01*
G01D02*
Y-1697000D01*
G01D02*
X992700Y-1695800D01*
G01D02*
X990900Y-1695400D01*
G01D02*
X987100D01*
G01X998400Y-1700600D02*
X1003800D01*
G01X1006000Y-1695400D02*
X998400D01*
G01X989300Y-1667500D02*
X988600Y-1665700D01*
G01X986600Y-1674700D02*
X988600Y-1673700D01*
G01D02*
X989300Y-1671900D01*
G01D02*
Y-1667500D01*
G01X994600Y-1664500D02*
Y-1671900D01*
G01D02*
X995300Y-1673700D01*
G01D02*
X997100Y-1674700D01*
G01D02*
X999500D01*
G01D02*
X1001400Y-1673700D01*
G01D02*
X1002100Y-1671900D01*
G01D02*
Y-1664500D01*
G01X1004500Y-1680000D02*
X1000700D01*
G01D02*
X998700Y-1680300D01*
G01D02*
X997400Y-1681100D01*
G01D02*
X997000Y-1682200D01*
G01X986600Y-1659200D02*
X988600Y-1658200D01*
G01D02*
X989300Y-1656400D01*
G01D02*
Y-1649200D01*
G01X998300D02*
X996100Y-1649600D01*
G01D02*
X994800Y-1650900D01*
G01D02*
Y-1652400D01*
G01D02*
X996100Y-1653700D01*
G01D02*
X998300Y-1654300D01*
G01X994600Y-1659400D02*
X998300D01*
G01D02*
X1000500Y-1658900D01*
G01D02*
X1002000Y-1657600D01*
G01D02*
Y-1656100D01*
G01D02*
X1000500Y-1654800D01*
G01D02*
X998300Y-1654300D01*
G01X988600Y-1665700D02*
X986600Y-1664700D01*
G01X987200Y-1644000D02*
X989100Y-1643300D01*
G01D02*
X990500Y-1641300D01*
G01D02*
X990900Y-1638800D01*
G01D02*
X990500Y-1636300D01*
G01D02*
X989100Y-1634400D01*
G01D02*
X987200Y-1633700D01*
G01X1001500Y-1636600D02*
X1000800Y-1634800D01*
G01D02*
X998900Y-1633800D01*
G01D02*
X996700D01*
G01D02*
X994800Y-1634800D01*
G01D02*
X994000Y-1636600D01*
G01D02*
Y-1641800D01*
G01Y-1641000D02*
X994800Y-1642800D01*
G01D02*
X996700Y-1643900D01*
G01D02*
X998900D01*
G01D02*
X1000800Y-1642800D01*
G01D02*
X1001500Y-1641000D01*
G01D02*
Y-1635900D01*
G01X1002100Y-1649200D02*
X998300D01*
G01X989300Y-1507900D02*
X1084500D01*
G01X989300Y-1416200D02*
Y-1507900D01*
G01X1001100Y-1477000D02*
X1001500Y-1480400D01*
G01D02*
X1002600Y-1483500D01*
G01D02*
X1004400Y-1486500D01*
G01X1001100Y-1477000D02*
X1011700D01*
G01X1001800Y-1455200D02*
X1002900Y-1458400D01*
G01D02*
X1004600Y-1461200D01*
G01X1004900Y-1437600D02*
X1003200Y-1440400D01*
G01D02*
X1002000Y-1443500D01*
G01D02*
X1001700Y-1446700D01*
G01X1001500Y-1451800D02*
X1001800Y-1455200D01*
G01X1001500Y-1451800D02*
X1001700Y-1446700D01*
G01X1084500Y-1416200D02*
X989300D01*
G01X1004600Y-1710900D02*
Y-1721200D01*
G01D02*
X1012200D01*
G01X1016000D02*
Y-1710900D01*
G01D02*
X1022100Y-1721200D01*
G01X1004600Y-1716100D02*
X1010000D01*
G01X1012200Y-1710900D02*
X1004600D01*
G01X1008000Y-1685200D02*
X1013200D01*
G01X1008000Y-1680000D02*
Y-1690200D01*
G01D02*
X1015600D01*
G01X1007500Y-1669700D02*
X1012600D01*
G01X1007500Y-1664500D02*
Y-1674900D01*
G01D02*
X1015000D01*
G01X1020400Y-1666300D02*
Y-1667900D01*
G01D02*
X1021800Y-1669300D01*
G01X1020200Y-1674900D02*
X1024000D01*
G01X1015600Y-1680000D02*
X1008000D01*
G01X1007500Y-1654300D02*
X1012600D01*
G01X1007500Y-1649200D02*
Y-1659400D01*
G01D02*
X1015000D01*
G01Y-1664500D02*
X1007500D01*
G01X1021800Y-1665100D02*
X1020400Y-1666300D01*
G01X1012200Y-1633700D02*
X1008300D01*
G01D02*
X1006400Y-1634000D01*
G01D02*
X1005100Y-1634800D01*
G01D02*
X1004600Y-1635900D01*
G01D02*
Y-1641800D01*
G01D02*
X1005100Y-1642800D01*
G01D02*
X1006400Y-1643700D01*
G01D02*
X1008300Y-1644000D01*
G01D02*
X1012200D01*
G01X1015100Y-1633700D02*
Y-1641000D01*
G01D02*
X1015900Y-1642800D01*
G01D02*
X1017800Y-1643900D01*
G01D02*
X1020200D01*
G01D02*
X1022100Y-1642800D01*
G01X1015000Y-1649200D02*
X1007500D01*
G01X1016000Y-1492100D02*
X1039500D01*
G01X1016000Y-1481400D02*
X1039900D01*
G01X1011700Y-1477000D02*
X1012000Y-1478800D01*
G01D02*
X1012900Y-1480100D01*
G01D02*
X1014400Y-1481100D01*
G01D02*
X1016000Y-1481400D01*
G01X1004400Y-1486500D02*
X1006700Y-1488800D01*
G01D02*
X1009700Y-1490600D01*
G01D02*
X1012800Y-1491600D01*
G01D02*
X1016000Y-1492100D01*
G01X1016500Y-1467000D02*
X1039500D01*
G01X1004600Y-1461200D02*
X1007000Y-1463600D01*
G01D02*
X1010000Y-1465500D01*
G01D02*
X1013100Y-1466500D01*
G01D02*
X1016500Y-1467000D01*
G01Y-1456800D02*
X1039500D01*
G01X1016500Y-1442200D02*
X1039600D01*
G01X1016500D02*
X1014700Y-1442500D01*
G01D02*
X1013100Y-1443500D01*
G01D02*
X1012000Y-1445100D01*
G01D02*
X1011700Y-1446900D01*
G01Y-1452100D02*
Y-1446900D01*
G01Y-1452100D02*
X1012000Y-1453800D01*
G01D02*
X1013100Y-1455400D01*
G01D02*
X1014700Y-1456500D01*
G01D02*
X1016500Y-1456800D01*
G01X1016600Y-1432100D02*
X1041900D01*
G01X1016600D02*
X1013400Y-1432400D01*
G01D02*
X1010100Y-1433600D01*
G01D02*
X1007300Y-1435200D01*
G01D02*
X1004900Y-1437600D01*
G01X1022100Y-1721200D02*
Y-1710900D01*
G01X1029600D02*
Y-1721200D01*
G01X1021000Y-1695400D02*
Y-1705700D01*
G01X1028700D02*
X1025600Y-1701300D01*
G01X1032400Y-1695400D02*
Y-1705700D01*
G01D02*
X1039900D01*
G01X1025800Y-1710900D02*
X1033300D01*
G01X1030200Y-1683000D02*
Y-1688200D01*
G01Y-1687400D02*
X1030800Y-1689000D01*
G01D02*
X1032700Y-1690100D01*
G01D02*
X1035100D01*
G01D02*
X1037000Y-1689000D01*
G01D02*
X1037700Y-1687400D01*
G01D02*
Y-1682200D01*
G01X1021000Y-1701300D02*
X1025600D01*
G01D02*
X1027400Y-1700700D01*
G01D02*
X1028600Y-1699200D01*
G01D02*
Y-1697500D01*
G01D02*
X1027400Y-1696000D01*
G01D02*
X1025600Y-1695400D01*
G01D02*
X1021000D01*
G01X1032400Y-1700600D02*
X1037700D01*
G01X1039900Y-1695400D02*
X1032400D01*
G01X1021800Y-1669300D02*
X1024000Y-1669700D01*
G01Y-1674900D02*
X1026200Y-1674400D01*
G01D02*
X1027500Y-1673100D01*
G01D02*
Y-1671500D01*
G01D02*
X1026200Y-1670100D01*
G01D02*
X1024000Y-1669700D01*
G01X1036800Y-1664500D02*
Y-1674900D01*
G01X1037700Y-1683000D02*
X1037000Y-1681200D01*
G01D02*
X1035100Y-1680200D01*
G01D02*
X1032700D01*
G01D02*
X1030800Y-1681200D01*
G01D02*
X1030200Y-1683000D01*
G01X1036800Y-1649200D02*
Y-1659400D01*
G01X1034600D02*
X1039100D01*
G01X1027800Y-1664500D02*
X1024000D01*
G01D02*
X1021800Y-1665100D01*
G01X1033000Y-1664500D02*
X1040700D01*
G01X1022100Y-1642800D02*
X1022800Y-1641000D01*
G01D02*
Y-1633700D01*
G01X1025800Y-1644000D02*
Y-1633700D01*
G01D02*
X1029600Y-1641800D01*
G01D02*
X1033300Y-1633700D01*
G01D02*
Y-1644000D01*
G01X1036400Y-1638800D02*
X1041700D01*
G01X1043900Y-1633700D02*
X1036400D01*
G01D02*
Y-1644000D01*
G01D02*
X1043900D01*
G01X1034600Y-1649200D02*
X1039100D01*
G01X1025000Y1379100D02*
Y1589100D01*
G01X1041300Y-1720000D02*
X1040700Y-1719200D01*
G01D02*
X1039600D01*
G01D02*
X1039100Y-1720000D01*
G01D02*
X1039600Y-1721100D01*
G01D02*
X1040700D01*
G01D02*
X1041300Y-1720000D01*
G01X1043800Y-1705700D02*
Y-1695400D01*
G01X1055100D02*
Y-1705700D01*
G01D02*
X1062700D01*
G01X1041300Y-1685200D02*
X1046400D01*
G01X1041300Y-1690200D02*
Y-1680000D01*
G01X1043800Y-1700600D02*
X1049100D01*
G01X1043800Y-1695400D02*
X1051300D01*
G01X1055100Y-1700600D02*
X1060500D01*
G01X1062700Y-1695400D02*
X1055100D01*
G01X1041300Y-1680000D02*
X1048800D01*
G01X1049700Y-1649200D02*
X1047500Y-1649600D01*
G01D02*
X1046000Y-1650900D01*
G01D02*
Y-1652400D01*
G01D02*
X1047500Y-1653700D01*
G01D02*
X1049700Y-1654300D01*
G01X1045800Y-1659400D02*
X1049700D01*
G01D02*
X1051900Y-1658900D01*
G01D02*
X1053200Y-1657600D01*
G01D02*
Y-1656100D01*
G01D02*
X1051900Y-1654800D01*
G01D02*
X1049700Y-1654300D01*
G01X1047800Y-1644000D02*
Y-1633700D01*
G01D02*
X1053800Y-1644000D01*
G01D02*
Y-1633700D01*
G01X1053400Y-1649200D02*
X1049700D01*
G01X1054600Y-1471700D02*
Y-1477000D01*
G01X1044400Y-1471700D02*
Y-1477000D01*
G01X1039500Y-1492100D02*
X1042900Y-1491600D01*
G01D02*
X1046000Y-1490600D01*
G01D02*
X1048900Y-1488800D01*
G01D02*
X1051300Y-1486500D01*
G01D02*
X1053100Y-1483500D01*
G01D02*
X1054100Y-1480400D01*
G01D02*
X1054600Y-1477000D01*
G01X1039900Y-1481400D02*
X1041700Y-1481100D01*
G01D02*
X1043000Y-1480100D01*
G01D02*
X1044100Y-1478800D01*
G01D02*
X1044400Y-1477000D01*
G01X1054600Y-1471700D02*
X1054100Y-1468400D01*
G01D02*
X1053100Y-1465200D01*
G01D02*
X1051300Y-1462400D01*
G01D02*
X1048900Y-1460000D01*
G01D02*
X1046000Y-1458300D01*
G01D02*
X1042900Y-1457200D01*
G01X1044400Y-1471700D02*
X1044100Y-1469900D01*
G01D02*
X1042900Y-1468300D01*
G01D02*
X1041400Y-1467300D01*
G01D02*
X1039500Y-1467000D01*
G01X1044500Y-1449000D02*
X1054600D01*
G01Y-1444800D02*
Y-1449000D01*
G01Y-1444800D02*
X1053700Y-1441700D01*
G01D02*
X1052300Y-1438800D01*
G01X1044500Y-1446900D02*
X1044100Y-1445100D01*
G01D02*
X1043000Y-1443500D01*
G01D02*
X1041600Y-1442500D01*
G01D02*
X1039600Y-1442200D01*
G01X1044500Y-1446900D02*
Y-1449000D01*
G01X1042900Y-1457200D02*
X1039500Y-1456800D01*
G01X1052300Y-1438800D02*
X1050300Y-1436300D01*
G01D02*
X1047800Y-1434300D01*
G01D02*
X1045000Y-1432900D01*
G01D02*
X1041900Y-1432100D01*
G01X1066500Y-1695400D02*
Y-1705700D01*
G01X1074000D02*
X1070900Y-1701300D01*
G01X1063400Y-1680000D02*
X1064200Y-1690200D01*
G01D02*
X1067100Y-1682200D01*
G01D02*
X1070200Y-1690200D01*
G01D02*
X1070900Y-1680000D01*
G01X1066500Y-1701300D02*
X1070900D01*
G01D02*
X1072700Y-1700700D01*
G01D02*
X1073900Y-1699200D01*
G01Y-1697500D02*
X1072700Y-1696000D01*
G01D02*
X1070900Y-1695400D01*
G01D02*
X1066500D01*
G01X1058700Y-1669700D02*
X1064000D01*
G01X1058700Y-1674900D02*
Y-1664500D01*
G01X1072300Y-1665700D02*
X1071500Y-1667500D01*
G01D02*
Y-1672600D01*
G01Y-1671900D02*
X1072300Y-1673700D01*
G01D02*
X1074200Y-1674700D01*
G01X1071500Y-1659400D02*
X1075400Y-1649200D01*
G01X1072300Y-1657100D02*
X1078300D01*
G01X1058700Y-1664500D02*
X1066200D01*
G01X1074200Y-1664700D02*
X1072300Y-1665700D01*
G01X1057500Y-1633700D02*
X1065200D01*
G01X1061300D02*
Y-1644000D01*
G01X1061600Y-1492100D02*
X1072100D01*
G01X1061600Y-1432100D02*
Y-1492100D01*
G01X1072100D02*
Y-1432100D01*
G01D02*
X1061600D01*
G01X1077700Y-1695400D02*
Y-1705700D01*
G01X1085400D02*
X1082300Y-1701300D01*
G01X1089100Y-1695400D02*
Y-1705700D01*
G01D02*
X1096600D01*
G01X1074500Y-1683000D02*
Y-1688200D01*
G01Y-1687400D02*
X1075200Y-1689000D01*
G01D02*
X1077000Y-1690100D01*
G01D02*
X1079400D01*
G01D02*
X1081300Y-1689000D01*
G01D02*
X1082000Y-1687400D01*
G01D02*
Y-1682200D01*
G01X1085600Y-1685900D02*
X1090000D01*
G01D02*
X1091900Y-1685300D01*
G01X1085600Y-1680000D02*
Y-1690200D01*
G01X1093100D02*
X1090000Y-1685900D01*
G01X1073900Y-1699200D02*
Y-1697500D01*
G01X1077700Y-1701300D02*
X1082300D01*
G01D02*
X1084100Y-1700700D01*
G01D02*
X1085300Y-1699200D01*
G01D02*
Y-1697500D01*
G01D02*
X1084100Y-1696000D01*
G01D02*
X1082300Y-1695400D01*
G01D02*
X1077700D01*
G01X1089100Y-1700600D02*
X1094400D01*
G01X1096600Y-1695400D02*
X1089100D01*
G01X1079100Y-1667500D02*
X1078300Y-1665700D01*
G01X1074200Y-1674700D02*
X1076400D01*
G01D02*
X1078300Y-1673700D01*
G01D02*
X1079100Y-1671900D01*
G01D02*
Y-1666700D01*
G01X1084400Y-1670400D02*
X1089000D01*
G01D02*
X1090700Y-1669800D01*
G01D02*
X1091800Y-1668400D01*
G01X1084400Y-1664500D02*
Y-1674900D01*
G01X1091900D02*
X1089000Y-1670400D01*
G01X1082000Y-1683000D02*
X1081300Y-1681200D01*
G01D02*
X1079400Y-1680200D01*
G01D02*
X1077000D01*
G01D02*
X1075200Y-1681200D01*
G01D02*
X1074500Y-1683000D01*
G01X1091900Y-1680600D02*
X1090000Y-1680000D01*
G01D02*
X1085600D01*
G01X1075400Y-1649200D02*
X1079100Y-1659400D01*
G01X1084400Y-1649200D02*
Y-1656400D01*
G01D02*
X1085100Y-1658200D01*
G01D02*
X1087000Y-1659200D01*
G01D02*
X1089300D01*
G01D02*
X1091200Y-1658200D01*
G01X1078300Y-1665700D02*
X1076400Y-1664700D01*
G01D02*
X1074200D01*
G01X1091800Y-1666600D02*
X1090700Y-1665100D01*
G01D02*
X1089000Y-1664500D01*
G01D02*
X1084400D01*
G01X1080200Y-1633700D02*
X1084800D01*
G01X1082600D02*
Y-1644000D01*
G01X1080200D02*
X1084800D01*
G01X1090900Y-1634100D02*
X1089600Y-1635400D01*
G01D02*
Y-1637100D01*
G01D02*
X1090900Y-1638400D01*
G01X1089400Y-1644000D02*
X1093100D01*
G01X1084500Y-1507900D02*
Y-1416200D01*
G01X1100500Y-1705700D02*
X1104200D01*
G01D02*
X1106100Y-1705000D01*
G01D02*
X1107600Y-1703200D01*
G01D02*
X1108000Y-1700600D01*
G01X1100500Y-1695400D02*
Y-1705700D01*
G01X1091900Y-1685300D02*
X1092900Y-1683900D01*
G01X1096600Y-1680000D02*
Y-1690200D01*
G01Y-1685900D02*
X1104200Y-1680000D01*
G01X1099100Y-1683900D02*
X1104200Y-1690200D01*
G01X1108000Y-1700600D02*
X1107600Y-1698000D01*
G01D02*
X1106100Y-1696100D01*
G01D02*
X1104200Y-1695400D01*
G01D02*
X1100500D01*
G01X1091800Y-1668400D02*
Y-1666600D01*
G01X1092900Y-1683900D02*
Y-1682100D01*
G01D02*
X1091900Y-1680600D01*
G01X1091200Y-1658200D02*
X1091900Y-1656400D01*
G01D02*
Y-1649200D01*
G01X1100900D02*
Y-1659400D01*
G01X1096900Y-1633700D02*
X1093100D01*
G01D02*
X1090900Y-1634100D01*
G01Y-1638400D02*
X1093100Y-1638800D01*
G01Y-1644000D02*
X1095300Y-1643400D01*
G01D02*
X1096800Y-1642200D01*
G01D02*
Y-1640600D01*
G01D02*
X1095300Y-1639300D01*
G01D02*
X1093100Y-1638800D01*
G01X1097200Y-1649200D02*
X1104800D01*
G01X1099000Y1589100D02*
Y1379100D01*
G01X1118800Y-1685200D02*
X1124100D01*
G01X1118800Y-1690200D02*
Y-1680000D01*
G01X1123100Y-1695400D02*
X1130700D01*
G01X1117600Y-1667500D02*
X1116900Y-1665700D01*
G01X1110700D02*
X1110100Y-1667500D01*
G01D02*
Y-1671900D01*
G01D02*
X1110700Y-1673700D01*
G01D02*
X1112600Y-1674700D01*
G01D02*
X1114900D01*
G01D02*
X1116900Y-1673700D01*
G01D02*
X1117600Y-1671900D01*
G01D02*
Y-1667500D01*
G01X1113800Y-1671200D02*
X1118300Y-1675600D01*
G01X1122800Y-1664500D02*
Y-1671900D01*
G01D02*
X1123500Y-1673700D01*
G01D02*
X1125400Y-1674700D01*
G01D02*
X1127800D01*
G01X1118800Y-1680000D02*
X1126300D01*
G01X1110100Y-1649200D02*
Y-1659400D01*
G01Y-1654300D02*
X1117600D01*
G01Y-1649200D02*
Y-1659400D01*
G01X1125400Y-1649300D02*
X1123500Y-1650400D01*
G01D02*
X1122800Y-1652100D01*
G01D02*
Y-1657100D01*
G01Y-1656400D02*
X1123500Y-1658200D01*
G01D02*
X1125400Y-1659200D01*
G01D02*
X1127800D01*
G01X1116900Y-1665700D02*
X1114900Y-1664700D01*
G01D02*
X1112600D01*
G01D02*
X1110700Y-1665700D01*
G01X1110500Y-1633700D02*
X1118200D01*
G01X1114400D02*
Y-1644000D01*
G01X1121100Y-1633700D02*
Y-1644000D01*
G01Y-1638800D02*
X1128700D01*
G01X1127800Y-1649300D02*
X1125400D01*
G01X1109300Y1555900D02*
X1115500D01*
G01D02*
X1118200Y1556700D01*
G01D02*
X1120300Y1559100D01*
G01X1109300Y1573000D02*
Y1555900D01*
G01X1120300Y1559100D02*
X1121400Y1562500D01*
G01D02*
Y1566300D01*
G01D02*
X1120300Y1569700D01*
G01D02*
X1118200Y1572100D01*
G01D02*
X1115500Y1573000D01*
G01D02*
X1109300D01*
G01X1126900Y-1695400D02*
Y-1705700D01*
G01X1134400Y-1698300D02*
Y-1703500D01*
G01Y-1702800D02*
X1135200Y-1704500D01*
G01D02*
X1137100Y-1705600D01*
G01D02*
X1139500D01*
G01D02*
X1141400Y-1704500D01*
G01D02*
X1142000Y-1702800D01*
G01D02*
Y-1697600D01*
G01X1129900Y-1683000D02*
Y-1688200D01*
G01Y-1687400D02*
X1130600Y-1689000D01*
G01D02*
X1132500Y-1690100D01*
G01D02*
X1134700D01*
G01D02*
X1136700Y-1689000D01*
G01D02*
X1137400Y-1687400D01*
G01D02*
Y-1682200D01*
G01X1140900Y-1685900D02*
X1145500D01*
G01X1140900Y-1680000D02*
Y-1690200D01*
G01X1142000Y-1698300D02*
X1141400Y-1696700D01*
G01D02*
X1139500Y-1695500D01*
G01D02*
X1137100D01*
G01D02*
X1135200Y-1696700D01*
G01D02*
X1134400Y-1698300D01*
G01X1127800Y-1674700D02*
X1129700Y-1673700D01*
G01D02*
X1130500Y-1671900D01*
G01D02*
Y-1664500D01*
G01X1136400Y-1665700D02*
X1135600Y-1667500D01*
G01D02*
Y-1672600D01*
G01Y-1671900D02*
X1136400Y-1673700D01*
G01D02*
X1138300Y-1674700D01*
G01D02*
X1140600D01*
G01D02*
X1142600Y-1673700D01*
G01D02*
X1143300Y-1671900D01*
G01X1137400Y-1683000D02*
X1136700Y-1681200D01*
G01D02*
X1134700Y-1680200D01*
G01D02*
X1132500D01*
G01D02*
X1130600Y-1681200D01*
G01D02*
X1129900Y-1683000D01*
G01X1145500Y-1680000D02*
X1140900D01*
G01X1130500Y-1652100D02*
X1129700Y-1650400D01*
G01D02*
X1127800Y-1649300D01*
G01Y-1659200D02*
X1129700Y-1658200D01*
G01D02*
X1130500Y-1656400D01*
G01D02*
Y-1651400D01*
G01X1135600Y-1654900D02*
X1140200D01*
G01D02*
X1142000Y-1654500D01*
G01D02*
X1143200Y-1653000D01*
G01Y-1651100D02*
X1142000Y-1649600D01*
G01D02*
X1140200Y-1649200D01*
G01X1135600D02*
Y-1659400D01*
G01X1143300D02*
X1140200Y-1654900D01*
G01X1143300Y-1667500D02*
X1142600Y-1665700D01*
G01D02*
X1140600Y-1664700D01*
G01D02*
X1138300D01*
G01D02*
X1136400Y-1665700D01*
G01X1128700Y-1633700D02*
Y-1644000D01*
G01X1131800Y-1638800D02*
X1137100D01*
G01X1139300Y-1633700D02*
X1131800D01*
G01D02*
Y-1644000D01*
G01D02*
X1139300D01*
G01X1140200Y-1649200D02*
X1135600D01*
G01X1126600Y1555900D02*
X1132700Y1573000D01*
G01D02*
X1138900Y1555900D01*
G01X1127800Y1559600D02*
X1137500D01*
G01X1154700Y-1755800D02*
Y-1788700D01*
G01X1145500Y-1685900D02*
X1147300Y-1685300D01*
G01D02*
X1148300Y-1683900D01*
G01X1148500Y-1690200D02*
X1145500Y-1685900D01*
G01X1157200Y-1695400D02*
X1164700D01*
G01X1143300Y-1671900D02*
Y-1666700D01*
G01X1152300Y-1664500D02*
Y-1674900D01*
G01X1148300Y-1683900D02*
Y-1682100D01*
G01D02*
X1147300Y-1680600D01*
G01D02*
X1145500Y-1680000D01*
G01X1143200Y-1653000D02*
Y-1651100D01*
G01X1152300Y-1649200D02*
Y-1659400D01*
G01X1149900D02*
X1154500D01*
G01X1148500Y-1664500D02*
X1156000D01*
G01X1152900Y-1639600D02*
X1157500D01*
G01D02*
X1159200Y-1639000D01*
G01D02*
X1160400Y-1637500D01*
G01D02*
Y-1635700D01*
G01D02*
X1159200Y-1634300D01*
G01D02*
X1157500Y-1633700D01*
G01D02*
X1152900D01*
G01D02*
Y-1644000D01*
G01X1149900Y-1649200D02*
X1154500D01*
G01X1159400Y-1407900D02*
Y-1619900D01*
G01X1435200Y-1453100D02*
X1159400D01*
G01X1149800Y1573000D02*
Y1555900D01*
G01X1143700Y1573000D02*
X1156000D01*
G01X1154700Y1628200D02*
Y1595300D01*
G01X1160900Y-1695400D02*
Y-1705700D01*
G01X1168400Y-1695400D02*
Y-1705700D01*
G01X1176100Y-1695400D02*
Y-1705700D01*
G01X1163100Y-1682200D02*
Y-1688200D01*
G01D02*
X1163500Y-1689200D01*
G01D02*
X1165000Y-1689900D01*
G01D02*
X1166900Y-1690200D01*
G01D02*
X1170600D01*
G01X1174200Y-1685200D02*
X1179500D01*
G01X1174200Y-1680000D02*
Y-1690200D01*
G01D02*
X1181700D01*
G01X1168400Y-1700600D02*
X1176100D01*
G01X1161300Y-1674900D02*
X1165200Y-1664500D01*
G01D02*
X1168800Y-1674900D01*
G01X1162200Y-1672600D02*
X1168100D01*
G01X1170600Y-1680000D02*
X1166900D01*
G01D02*
X1165000Y-1680300D01*
G01D02*
X1163500Y-1681100D01*
G01D02*
X1163100Y-1682200D01*
G01X1181700Y-1680000D02*
X1174200D01*
G01X1168800Y-1649200D02*
X1161300Y-1659400D01*
G01D02*
X1168800D01*
G01X1174200Y-1654300D02*
X1179500D01*
G01X1174200Y-1649200D02*
Y-1659400D01*
G01D02*
X1181700D01*
G01X1174200Y-1664500D02*
X1181700D01*
G01X1163500Y-1639600D02*
X1168100D01*
G01D02*
X1169900Y-1639000D01*
G01D02*
X1170900Y-1637500D01*
G01D02*
Y-1635700D01*
G01D02*
X1169900Y-1634300D01*
G01D02*
X1168100Y-1633700D01*
G01D02*
X1163500D01*
G01D02*
Y-1644000D01*
G01X1171100D02*
X1168100Y-1639600D01*
G01X1179000Y-1633800D02*
X1176800D01*
G01D02*
X1174900Y-1634800D01*
G01D02*
X1174200Y-1636600D01*
G01D02*
Y-1641800D01*
G01Y-1641000D02*
X1174900Y-1642800D01*
G01D02*
X1176800Y-1643900D01*
G01D02*
X1179000D01*
G01X1161300Y-1649200D02*
X1168800D01*
G01X1181700D02*
X1174200D01*
G01X1175800Y-1422800D02*
X1173100Y-1423400D01*
G01D02*
X1171100Y-1424700D01*
G01D02*
X1170500Y-1426700D01*
G01D02*
X1171100Y-1428600D01*
G01D02*
X1173100Y-1430100D01*
G01D02*
X1175800Y-1430500D01*
G01X1170500Y-1438200D02*
X1175800D01*
G01D02*
X1178600Y-1437600D01*
G01Y-1430900D02*
X1175800Y-1430500D01*
G01X1181200Y-1422800D02*
X1175800D01*
G01X1160900Y1573000D02*
Y1555900D01*
G01D02*
X1173100D01*
G01X1160900Y1564400D02*
X1169400D01*
G01X1173100Y1573000D02*
X1160900D01*
G01X1179800Y-1695400D02*
Y-1705700D01*
G01D02*
X1187300D01*
G01X1185200Y-1680000D02*
Y-1690200D01*
G01D02*
X1192800D01*
G01X1179800Y-1700600D02*
X1185100D01*
G01X1187300Y-1695400D02*
X1179800D01*
G01X1178000Y-1664500D02*
Y-1674900D01*
G01X1190700Y-1664500D02*
Y-1674900D01*
G01X1188500D02*
X1193100D01*
G01X1187000Y-1659400D02*
X1190700D01*
G01D02*
X1192600Y-1658800D01*
G01D02*
X1194100Y-1656800D01*
G01D02*
X1194500Y-1654300D01*
G01D02*
X1194100Y-1651700D01*
G01D02*
X1192600Y-1649800D01*
G01D02*
X1190700Y-1649200D01*
G01X1187000D02*
Y-1659400D01*
G01X1188500Y-1664500D02*
X1193100D01*
G01X1181700Y-1636600D02*
X1180900Y-1634800D01*
G01D02*
X1179000Y-1633800D01*
G01Y-1643900D02*
X1180900Y-1642800D01*
G01D02*
X1181700Y-1641000D01*
G01D02*
Y-1635900D01*
G01X1184800Y-1639600D02*
X1189200D01*
G01D02*
X1191000Y-1639000D01*
G01D02*
X1192200Y-1637500D01*
G01D02*
Y-1635700D01*
G01D02*
X1191000Y-1634300D01*
G01D02*
X1189200Y-1633700D01*
G01D02*
X1184800D01*
G01D02*
Y-1644000D01*
G01X1190700Y-1649200D02*
X1187000D01*
G01X1184800Y-1527500D02*
X1192200D01*
G01X1188500D02*
Y-1537800D01*
G01X1195100Y-1527500D02*
Y-1537800D01*
G01Y-1532700D02*
X1202500D01*
G01X1178600Y-1437600D02*
X1180500Y-1436300D01*
G01D02*
X1181200Y-1434300D01*
G01D02*
X1180500Y-1432400D01*
G01D02*
X1178600Y-1430900D01*
G01X1191100Y-1422800D02*
X1188900Y-1423100D01*
G01D02*
X1187300Y-1423900D01*
G01D02*
X1186100Y-1424900D01*
G01D02*
X1185700Y-1426200D01*
G01D02*
Y-1434900D01*
G01D02*
X1186100Y-1436100D01*
G01D02*
X1187300Y-1437100D01*
G01D02*
X1188900Y-1437900D01*
G01D02*
X1191100Y-1438200D01*
G01D02*
X1196500D01*
G01Y-1422800D02*
X1191100D01*
G01X1202500Y-1697600D02*
Y-1703500D01*
G01D02*
X1203000Y-1704700D01*
G01D02*
X1204400Y-1705400D01*
G01D02*
X1206200Y-1705700D01*
G01D02*
X1210000D01*
G01X1196300Y-1685200D02*
X1201600D01*
G01X1196300Y-1680000D02*
Y-1690200D01*
G01D02*
X1203800D01*
G01X1207500Y-1683400D02*
X1209000Y-1684600D01*
G01D02*
X1211200Y-1685200D01*
G01X1207400Y-1690200D02*
X1211200D01*
G01D02*
X1213400Y-1689800D01*
G01Y-1685600D02*
X1211200Y-1685200D01*
G01X1210000Y-1695400D02*
X1206200D01*
G01D02*
X1204400Y-1695700D01*
G01D02*
X1203000Y-1696600D01*
G01D02*
X1202500Y-1697600D01*
G01X1207400Y-1667500D02*
X1206600Y-1665700D01*
G01X1200600D02*
X1199800Y-1667500D01*
G01D02*
Y-1672600D01*
G01Y-1671900D02*
X1200600Y-1673700D01*
G01D02*
X1202400Y-1674700D01*
G01D02*
X1204700D01*
G01D02*
X1206600Y-1673700D01*
G01D02*
X1207400Y-1671900D01*
G01D02*
Y-1666700D01*
G01X1203800Y-1680000D02*
X1196300D01*
G01X1214900D02*
X1211200D01*
G01D02*
X1209000Y-1680500D01*
G01D02*
X1207500Y-1681800D01*
G01D02*
Y-1683400D01*
G01X1212700Y-1654300D02*
X1217900D01*
G01X1212700Y-1659400D02*
Y-1649200D01*
G01X1206600Y-1665700D02*
X1204700Y-1664700D01*
G01D02*
X1202400D01*
G01D02*
X1200600Y-1665700D01*
G01X1195300Y-1638800D02*
X1200600D01*
G01X1203000Y-1633700D02*
X1195300D01*
G01D02*
Y-1644000D01*
G01D02*
X1203000D01*
G01X1205900Y-1639600D02*
X1210500D01*
G01D02*
X1212300Y-1639000D01*
G01D02*
X1213300Y-1637500D01*
G01Y-1635700D02*
X1212300Y-1634300D01*
G01D02*
X1210500Y-1633700D01*
G01D02*
X1205900D01*
G01D02*
Y-1644000D01*
G01X1213400D02*
X1210500Y-1639600D01*
G01X1212700Y-1649200D02*
X1220200D01*
G01X1202500Y-1527500D02*
Y-1537800D01*
G01X1206900Y-1527500D02*
X1211400D01*
G01X1209200D02*
Y-1537800D01*
G01X1206900D02*
X1211400D01*
G01X1200900Y-1438200D02*
X1206300Y-1422800D01*
G01D02*
X1211800Y-1438200D01*
G01X1202100Y-1434900D02*
X1210600D01*
G01X1213900Y-1695400D02*
Y-1705700D01*
G01D02*
X1221400D01*
G01X1225100Y-1695400D02*
Y-1705700D01*
G01D02*
X1232800D01*
G01X1213400Y-1689800D02*
X1214800Y-1688400D01*
G01D02*
Y-1687000D01*
G01D02*
X1213400Y-1685600D01*
G01X1222300Y-1680000D02*
Y-1690200D01*
G01X1213900Y-1700600D02*
X1219000D01*
G01X1221400Y-1695400D02*
X1213900D01*
G01X1213400Y-1674900D02*
Y-1664500D01*
G01D02*
X1219500Y-1674900D01*
G01D02*
Y-1664500D01*
G01X1218500Y-1680000D02*
X1226000D01*
G01X1228100Y-1649300D02*
X1226100Y-1650400D01*
G01D02*
X1225400Y-1652100D01*
G01D02*
Y-1657100D01*
G01Y-1656400D02*
X1226100Y-1658200D01*
G01D02*
X1228100Y-1659200D01*
G01D02*
X1230400D01*
G01X1213300Y-1637500D02*
Y-1635700D01*
G01X1216500Y-1633700D02*
X1224100D01*
G01X1220400D02*
Y-1644000D01*
G01X1227200Y-1633700D02*
X1230900Y-1638800D01*
G01X1230400Y-1649300D02*
X1228100D01*
G01X1227500Y-1575800D02*
X1228200Y-1579900D01*
G01D02*
X1229800Y-1583900D01*
G01D02*
X1232200Y-1587600D01*
G01Y-1559500D02*
X1229800Y-1563200D01*
G01D02*
X1228200Y-1567200D01*
G01D02*
X1227500Y-1571400D01*
G01D02*
Y-1575800D01*
G01X1236600Y-1573600D02*
X1223200D01*
G01X1215600Y-1533400D02*
X1220100D01*
G01D02*
X1221900Y-1532800D01*
G01D02*
X1222900Y-1531300D01*
G01D02*
Y-1529600D01*
G01D02*
X1221900Y-1528100D01*
G01D02*
X1220100Y-1527500D01*
G01D02*
X1215600D01*
G01D02*
Y-1537800D01*
G01X1223000D02*
X1220100Y-1533400D01*
G01X1226000Y-1537800D02*
X1229700D01*
G01D02*
X1231400Y-1537100D01*
G01Y-1528200D02*
X1229700Y-1527500D01*
G01D02*
X1226000D01*
G01D02*
Y-1537800D01*
G01X1216100Y-1422800D02*
Y-1438200D01*
G01D02*
X1227000D01*
G01X1236500Y-1695400D02*
Y-1705700D01*
G01D02*
X1244000D01*
G01X1233400Y-1680000D02*
Y-1690200D01*
G01X1231000D02*
X1235600D01*
G01X1240600Y-1682200D02*
Y-1688200D01*
G01D02*
X1241200Y-1689200D01*
G01D02*
X1242500Y-1689900D01*
G01D02*
X1244400Y-1690200D01*
G01D02*
X1248100D01*
G01X1236500Y-1700600D02*
X1241800D01*
G01X1244000Y-1695400D02*
X1236500D01*
G01X1245900Y-1667500D02*
X1245200Y-1665700D01*
G01X1239000D02*
X1238200Y-1667500D01*
G01D02*
Y-1672600D01*
G01Y-1671900D02*
X1239000Y-1673700D01*
G01D02*
X1240900Y-1674700D01*
G01D02*
X1243300D01*
G01D02*
X1245200Y-1673700D01*
G01D02*
X1245900Y-1671900D01*
G01D02*
Y-1666700D01*
G01X1231000Y-1680000D02*
X1235600D01*
G01X1248100D02*
X1244400D01*
G01D02*
X1242500Y-1680300D01*
G01D02*
X1241200Y-1681100D01*
G01D02*
X1240600Y-1682200D01*
G01X1233100Y-1652100D02*
X1232300Y-1650400D01*
G01D02*
X1230400Y-1649300D01*
G01Y-1659200D02*
X1232300Y-1658200D01*
G01D02*
X1233100Y-1656400D01*
G01D02*
Y-1651400D01*
G01X1238200Y-1654900D02*
X1242800D01*
G01D02*
X1244600Y-1654500D01*
G01D02*
X1245800Y-1653000D01*
G01D02*
Y-1651100D01*
G01D02*
X1244600Y-1649600D01*
G01D02*
X1242800Y-1649200D01*
G01X1238200D02*
Y-1659400D01*
G01X1245900D02*
X1242800Y-1654900D01*
G01X1245200Y-1665700D02*
X1243300Y-1664700D01*
G01D02*
X1240900D01*
G01D02*
X1239000Y-1665700D01*
G01X1230900Y-1638800D02*
Y-1644000D01*
G01Y-1638800D02*
X1234700Y-1633700D01*
G01X1242800Y-1649200D02*
X1238200D01*
G01X1232200Y-1587600D02*
X1235100Y-1590700D01*
G01D02*
X1238700Y-1593200D01*
G01D02*
X1242500Y-1595000D01*
G01D02*
X1246700Y-1596000D01*
G01D02*
X1251100Y-1596200D01*
G01X1234000Y-1577300D02*
X1235100Y-1580700D01*
G01D02*
X1237100Y-1583800D01*
G01D02*
X1239700Y-1586400D01*
G01D02*
X1242800Y-1588300D01*
G01D02*
X1246200Y-1589700D01*
G01D02*
X1249900Y-1590000D01*
G01X1239700Y-1560700D02*
X1237100Y-1563200D01*
G01D02*
X1235100Y-1566500D01*
G01D02*
X1234000Y-1569900D01*
G01D02*
X1233500Y-1573600D01*
G01D02*
X1234000Y-1577300D01*
G01X1255700Y-1573600D02*
X1244300D01*
G01X1251100Y-1551000D02*
X1246700Y-1551100D01*
G01D02*
X1242500Y-1552200D01*
G01D02*
X1238700Y-1553900D01*
G01D02*
X1235100Y-1556400D01*
G01D02*
X1232200Y-1559500D01*
G01X1249900Y-1557000D02*
X1246200Y-1557500D01*
G01D02*
X1242800Y-1558700D01*
G01D02*
X1239700Y-1560700D01*
G01X1231400Y-1537100D02*
X1232900Y-1535300D01*
G01D02*
X1233400Y-1532700D01*
G01D02*
X1232900Y-1530200D01*
G01D02*
X1231400Y-1528200D01*
G01X1246700Y-1537800D02*
X1250200Y-1527500D01*
G01X1247400Y-1535600D02*
X1253200D01*
G01X1244400Y-1505700D02*
Y-1493200D01*
G01Y-1505700D02*
X1347400D01*
G01X1248900Y-1477300D02*
X1247000Y-1474600D01*
G01X1241800D02*
X1239900Y-1477300D01*
G01D02*
X1239300Y-1481000D01*
G01D02*
X1239900Y-1484500D01*
G01D02*
X1241800Y-1487200D01*
G01D02*
X1244400Y-1488100D01*
G01D02*
X1247000Y-1487200D01*
G01D02*
X1248900Y-1484500D01*
G01X1247000Y-1474600D02*
X1244400Y-1473800D01*
G01D02*
X1241800Y-1474600D01*
G01X1231300Y-1430500D02*
X1239000D01*
G01X1231300Y-1422800D02*
Y-1438200D01*
G01D02*
X1242200D01*
G01Y-1422800D02*
X1231300D01*
G01X1247800Y-1705700D02*
X1251500D01*
G01D02*
X1253900Y-1705300D01*
G01D02*
X1255200Y-1704000D01*
G01D02*
Y-1702300D01*
G01D02*
X1253900Y-1701000D01*
G01X1262900Y-1695400D02*
Y-1705700D01*
G01X1251700Y-1690200D02*
X1255500Y-1680000D01*
G01D02*
X1259200Y-1690200D01*
G01X1252600Y-1688200D02*
X1258500D01*
G01X1255400Y-1695400D02*
X1251500D01*
G01D02*
X1249300Y-1696000D01*
G01D02*
X1248000Y-1697200D01*
G01D02*
Y-1698800D01*
G01D02*
X1249300Y-1700100D01*
G01D02*
X1251500Y-1700600D01*
G01X1253900Y-1701000D02*
X1251500Y-1700600D01*
G01X1259200Y-1695400D02*
X1266700D01*
G01X1251100Y-1670400D02*
X1255700D01*
G01D02*
X1257400Y-1669800D01*
G01D02*
X1258500Y-1668400D01*
G01D02*
Y-1666600D01*
G01X1251100Y-1664500D02*
Y-1674900D01*
G01X1258600D02*
X1255700Y-1670400D01*
G01X1263900Y-1654900D02*
X1268500D01*
G01X1263900Y-1649200D02*
Y-1659400D01*
G01X1258500Y-1666600D02*
X1257400Y-1665100D01*
G01D02*
X1255700Y-1664500D01*
G01D02*
X1251100D01*
G01X1256000Y-1636600D02*
X1255200Y-1634800D01*
G01D02*
X1253300Y-1633800D01*
G01D02*
X1250900D01*
G01D02*
X1249000Y-1634800D01*
G01D02*
X1248300Y-1636600D01*
G01D02*
Y-1641800D01*
G01Y-1641000D02*
X1249000Y-1642800D01*
G01D02*
X1250900Y-1643900D01*
G01D02*
X1253300D01*
G01D02*
X1255200Y-1642800D01*
G01D02*
X1256000Y-1641000D01*
G01D02*
Y-1635900D01*
G01X1258900Y-1638800D02*
X1264200D01*
G01X1258900Y-1644000D02*
Y-1633700D01*
G01D02*
X1266400D01*
G01X1268500Y-1649200D02*
X1263900D01*
G01X1249900Y-1586900D02*
Y-1600300D01*
G01X1251100Y-1596200D02*
X1255200Y-1595600D01*
G01D02*
X1259400Y-1594100D01*
G01D02*
X1263000Y-1592000D01*
G01D02*
X1266300Y-1589200D01*
G01X1249900Y-1590000D02*
X1253600Y-1589700D01*
G01D02*
X1257100Y-1588300D01*
G01D02*
X1260200Y-1586400D01*
G01D02*
X1262900Y-1583800D01*
G01D02*
X1264800Y-1580700D01*
G01D02*
X1266000Y-1577300D01*
G01Y-1569900D02*
X1264800Y-1566500D01*
G01D02*
X1262900Y-1563200D01*
G01D02*
X1260200Y-1560700D01*
G01X1249900Y-1567800D02*
Y-1579300D01*
G01X1276800Y-1573600D02*
X1263300D01*
G01X1266300Y-1557900D02*
X1263000Y-1555100D01*
G01D02*
X1259400Y-1552900D01*
G01D02*
X1255200Y-1551600D01*
G01D02*
X1251100Y-1551000D01*
G01X1260200Y-1560700D02*
X1257100Y-1558700D01*
G01D02*
X1253600Y-1557500D01*
G01D02*
X1249900Y-1557000D01*
G01Y-1546800D02*
Y-1560300D01*
G01X1250200Y-1527500D02*
X1253900Y-1537800D01*
G01X1257600D02*
Y-1527500D01*
G01D02*
X1263500Y-1537800D01*
G01D02*
Y-1527500D01*
G01X1265000Y-1505700D02*
Y-1493200D01*
G01X1249600Y-1481000D02*
X1248900Y-1477300D01*
G01Y-1484500D02*
X1249600Y-1481000D01*
G01X1327400D02*
X1264200D01*
G01X1327400D02*
X1264200D01*
G01D02*
X1327400D01*
G01X1253600Y-1430500D02*
X1252900Y-1429000D01*
G01D02*
X1251200D01*
G01D02*
X1250300Y-1430500D01*
G01D02*
X1251200Y-1432000D01*
G01D02*
X1252900D01*
G01D02*
X1253600Y-1430500D01*
G01Y-1436000D02*
X1252900Y-1434500D01*
G01D02*
X1251200D01*
G01D02*
X1250300Y-1436000D01*
G01D02*
X1251200Y-1437300D01*
G01D02*
X1252900D01*
G01D02*
X1253600Y-1436000D01*
G01X1274300Y-1695400D02*
Y-1705700D01*
G01X1272100D02*
X1276500D01*
G01X1281800Y-1697600D02*
Y-1703500D01*
G01D02*
X1282400Y-1704700D01*
G01D02*
X1283700Y-1705400D01*
G01X1267600Y-1689200D02*
X1267200Y-1688300D01*
G01D02*
X1266000D01*
G01D02*
X1265400Y-1689200D01*
G01D02*
X1266000Y-1690100D01*
G01D02*
X1267200D01*
G01D02*
X1267600Y-1689200D01*
G01X1272100Y-1695400D02*
X1276500D01*
G01X1283700Y-1695700D02*
X1282400Y-1696600D01*
G01D02*
X1281800Y-1697600D01*
G01X1276800Y-1669700D02*
X1282100D01*
G01X1276800Y-1674900D02*
Y-1664500D01*
G01X1268500Y-1654900D02*
X1270300Y-1654500D01*
G01D02*
X1271300Y-1653000D01*
G01D02*
Y-1651100D01*
G01D02*
X1270300Y-1649600D01*
G01D02*
X1268500Y-1649200D01*
G01X1271500Y-1659400D02*
X1268500Y-1654900D01*
G01X1276800Y-1654300D02*
X1282100D01*
G01X1276800Y-1649200D02*
Y-1659400D01*
G01D02*
X1284300D01*
G01X1276800Y-1664500D02*
X1284300D01*
G01X1283900Y-1633700D02*
X1281900Y-1634000D01*
G01D02*
X1280600Y-1634800D01*
G01D02*
X1280200Y-1635900D01*
G01D02*
Y-1641800D01*
G01D02*
X1280600Y-1642800D01*
G01D02*
X1281900Y-1643700D01*
G01D02*
X1283900Y-1644000D01*
G01X1284300Y-1649200D02*
X1276800D01*
G01X1266300Y-1589200D02*
X1269000Y-1585800D01*
G01D02*
X1271000Y-1582000D01*
G01D02*
X1272200Y-1577900D01*
G01X1272600Y-1573600D02*
X1272200Y-1569300D01*
G01D02*
X1271000Y-1565200D01*
G01D02*
X1269000Y-1561300D01*
G01X1272200Y-1577900D02*
X1272600Y-1573600D01*
G01X1266400D02*
X1266000Y-1569900D01*
G01Y-1577300D02*
X1266400Y-1573600D01*
G01X1269000Y-1561300D02*
X1266300Y-1557900D01*
G01X1274600Y-1527500D02*
X1270100D01*
G01D02*
X1268700Y-1528200D01*
G01D02*
X1267600Y-1530200D01*
G01D02*
X1267200Y-1532700D01*
G01D02*
X1267600Y-1535300D01*
G01D02*
X1268700Y-1537100D01*
G01D02*
X1270100Y-1537800D01*
G01D02*
X1274600D01*
G01D02*
Y-1532700D01*
G01D02*
X1271600D01*
G01X1277500Y-1527500D02*
Y-1537800D01*
G01D02*
X1284800D01*
G01X1267300Y-1481000D02*
X1282800Y-1483700D01*
G01X1267300Y-1481000D02*
X1282800Y-1483700D01*
G01X1267300Y-1481000D02*
X1282800Y-1478200D01*
G01X1267300Y-1481000D02*
X1282800Y-1478200D01*
G01X1280200Y1589100D02*
Y1379100D01*
G01X1283700Y-1705400D02*
X1285600Y-1705700D01*
G01D02*
X1289300D01*
G01X1293200D02*
X1297000Y-1695400D01*
G01D02*
X1300700Y-1705700D01*
G01X1293900Y-1703500D02*
X1300000D01*
G01X1284900Y-1690200D02*
X1288700Y-1680000D01*
G01D02*
X1292400Y-1690200D01*
G01X1285800Y-1688200D02*
X1291700D01*
G01X1296000Y-1680000D02*
Y-1690200D01*
G01D02*
X1303700D01*
G01X1289300Y-1695400D02*
X1285600D01*
G01D02*
X1283700Y-1695700D01*
G01X1297200Y-1667500D02*
X1296400Y-1665700D01*
G01X1290400D02*
X1289600Y-1667500D01*
G01D02*
Y-1672600D01*
G01Y-1671900D02*
X1290400Y-1673700D01*
G01D02*
X1292100Y-1674700D01*
G01D02*
X1294500D01*
G01D02*
X1296400Y-1673700D01*
G01D02*
X1297200Y-1671900D01*
G01D02*
Y-1666700D01*
G01X1293300Y-1649200D02*
X1291100Y-1649600D01*
G01D02*
X1289800Y-1650900D01*
G01D02*
Y-1652400D01*
G01D02*
X1291100Y-1653700D01*
G01D02*
X1293300Y-1654300D01*
G01X1289600Y-1659400D02*
X1293300D01*
G01D02*
X1295500Y-1658900D01*
G01D02*
X1297000Y-1657600D01*
G01D02*
Y-1656100D01*
G01D02*
X1295500Y-1654800D01*
G01D02*
X1293300Y-1654300D01*
G01X1296400Y-1665700D02*
X1294500Y-1664700D01*
G01D02*
X1292100D01*
G01D02*
X1290400Y-1665700D01*
G01X1287700Y-1633700D02*
X1283900D01*
G01Y-1644000D02*
X1287700D01*
G01X1290700Y-1638800D02*
X1296000D01*
G01X1298300Y-1633700D02*
X1290700D01*
G01D02*
Y-1644000D01*
G01D02*
X1298300D01*
G01X1297200Y-1649200D02*
X1293300D01*
G01X1287700Y-1532700D02*
X1292900D01*
G01X1295100Y-1527500D02*
X1287700D01*
G01D02*
Y-1537800D01*
G01D02*
X1295100D01*
G01X1285500Y-1505700D02*
Y-1493200D01*
G01X1315800Y-1695400D02*
Y-1705700D01*
G01X1307000Y-1680000D02*
Y-1690200D01*
G01D02*
X1314700D01*
G01X1315800Y-1701300D02*
X1320300D01*
G01Y-1695400D02*
X1315800D01*
G01X1302500Y-1670400D02*
X1306900D01*
G01D02*
X1308700Y-1669800D01*
G01D02*
X1309900Y-1668400D01*
G01D02*
Y-1666600D01*
G01X1302500Y-1664500D02*
Y-1674900D01*
G01X1310000D02*
X1306900Y-1670400D01*
G01X1302500Y-1654900D02*
X1306900D01*
G01D02*
X1308700Y-1654500D01*
G01D02*
X1309900Y-1653000D01*
G01D02*
Y-1651100D01*
G01D02*
X1308700Y-1649600D01*
G01D02*
X1306900Y-1649200D01*
G01X1302500D02*
Y-1659400D01*
G01X1317800Y-1649300D02*
X1315900Y-1650400D01*
G01D02*
X1315200Y-1652100D01*
G01D02*
Y-1657100D01*
G01Y-1656400D02*
X1315900Y-1658200D01*
G01D02*
X1317800Y-1659200D01*
G01X1309900Y-1666600D02*
X1308700Y-1665100D01*
G01D02*
X1306900Y-1664500D01*
G01D02*
X1302500D01*
G01X1301300Y-1633700D02*
Y-1644000D01*
G01D02*
X1308800D01*
G01X1311900Y-1638800D02*
X1317200D01*
G01X1319500Y-1633700D02*
X1311900D01*
G01D02*
Y-1644000D01*
G01D02*
X1319500D01*
G01X1306900Y-1649200D02*
X1302500D01*
G01X1327900Y-1573600D02*
X1309900D01*
G01X1308400Y-1533400D02*
X1312800D01*
G01D02*
X1314400Y-1532800D01*
G01D02*
X1315600Y-1531300D01*
G01D02*
Y-1529600D01*
G01D02*
X1314400Y-1528100D01*
G01D02*
X1312800Y-1527500D01*
G01D02*
X1308400D01*
G01D02*
Y-1537800D01*
G01X1306200Y-1505700D02*
Y-1493200D01*
G01X1324300Y-1481000D02*
X1308800Y-1478200D01*
G01X1324300Y-1481000D02*
X1308800Y-1478200D01*
G01X1324300Y-1481000D02*
X1308800Y-1483700D01*
G01X1324300Y-1481000D02*
X1308800Y-1483700D01*
G01X1327100Y-1695400D02*
Y-1702800D01*
G01D02*
X1327900Y-1704500D01*
G01D02*
X1329800Y-1705600D01*
G01D02*
X1332100D01*
G01D02*
X1334100Y-1704500D01*
G01D02*
X1334700Y-1702800D01*
G01D02*
Y-1695400D01*
G01X1329200Y-1683000D02*
Y-1687400D01*
G01D02*
X1329900Y-1689000D01*
G01D02*
X1331900Y-1690100D01*
G01D02*
X1334200D01*
G01D02*
X1336100Y-1689000D01*
G01X1333000Y-1686700D02*
X1337600Y-1691000D01*
G01X1320300Y-1701300D02*
X1322100Y-1700700D01*
G01D02*
X1323300Y-1699200D01*
G01D02*
Y-1697500D01*
G01D02*
X1322100Y-1696000D01*
G01D02*
X1320300Y-1695400D01*
G01X1331900Y-1664500D02*
Y-1674900D01*
G01X1336100Y-1681200D02*
X1334200Y-1680200D01*
G01D02*
X1331900D01*
G01D02*
X1329900Y-1681200D01*
G01D02*
X1329200Y-1683000D01*
G01X1322800Y-1652100D02*
X1322100Y-1650400D01*
G01D02*
X1320200Y-1649300D01*
G01X1317800Y-1659200D02*
X1320200D01*
G01D02*
X1322100Y-1658200D01*
G01D02*
X1322800Y-1656400D01*
G01D02*
Y-1651400D01*
G01X1328800Y-1659400D02*
Y-1649200D01*
G01D02*
X1334800Y-1659400D01*
G01X1328000Y-1664500D02*
X1335700D01*
G01X1330100Y-1633700D02*
X1326200D01*
G01D02*
X1324000Y-1634100D01*
G01D02*
X1322700Y-1635400D01*
G01D02*
Y-1637100D01*
G01D02*
X1324000Y-1638400D01*
G01D02*
X1326200Y-1638800D01*
G01X1322600Y-1644000D02*
X1326200D01*
G01D02*
X1328500Y-1643400D01*
G01D02*
X1329900Y-1642200D01*
G01D02*
Y-1640600D01*
G01D02*
X1328500Y-1639300D01*
G01D02*
X1326200Y-1638800D01*
G01X1333000Y-1633700D02*
X1340700D01*
G01X1320200Y-1649300D02*
X1317800D01*
G01X1319900Y-1557000D02*
Y-1590000D01*
G01D02*
X1361100Y-1596200D01*
G01Y-1551000D02*
X1319900Y-1557000D01*
G01X1318600Y-1533400D02*
X1323000D01*
G01D02*
X1324800Y-1532800D01*
G01D02*
X1325800Y-1531300D01*
G01D02*
Y-1529600D01*
G01D02*
X1324800Y-1528100D01*
G01D02*
X1323000Y-1527500D01*
G01D02*
X1318600D01*
G01D02*
Y-1537800D01*
G01X1325900D02*
X1323000Y-1533400D01*
G01X1335500Y-1528700D02*
X1333800Y-1527700D01*
G01D02*
X1331400D01*
G01D02*
X1329600Y-1528700D01*
G01D02*
X1328900Y-1530500D01*
G01D02*
Y-1535600D01*
G01Y-1534900D02*
X1329600Y-1536700D01*
G01D02*
X1331400Y-1537700D01*
G01D02*
X1333800D01*
G01D02*
X1335500Y-1536700D01*
G01X1326700Y-1505700D02*
Y-1493200D01*
G01X1338500Y-1695400D02*
Y-1705700D01*
G01X1346000D02*
X1343100Y-1701300D01*
G01X1349900Y-1697600D02*
Y-1703500D01*
G01D02*
X1350300Y-1704700D01*
G01D02*
X1351800Y-1705400D01*
G01D02*
X1353600Y-1705700D01*
G01X1336100Y-1689000D02*
X1336900Y-1687400D01*
G01D02*
Y-1683000D01*
G01X1340300Y-1680000D02*
Y-1687400D01*
G01D02*
X1341000Y-1689000D01*
G01D02*
X1342900Y-1690100D01*
G01D02*
X1345300D01*
G01D02*
X1347200Y-1689000D01*
G01D02*
X1347900Y-1687400D01*
G01D02*
Y-1680000D01*
G01X1351300Y-1685200D02*
X1356700D01*
G01X1351300Y-1680000D02*
Y-1690200D01*
G01D02*
X1359000D01*
G01X1338500Y-1701300D02*
X1343100D01*
G01D02*
X1344800Y-1700700D01*
G01D02*
X1345900Y-1699200D01*
G01D02*
Y-1697500D01*
G01D02*
X1344800Y-1696000D01*
G01D02*
X1343100Y-1695400D01*
G01D02*
X1338500D01*
G01X1353600D02*
X1351800Y-1695700D01*
G01D02*
X1350300Y-1696600D01*
G01D02*
X1349900Y-1697600D01*
G01X1340900Y-1664500D02*
Y-1674900D01*
G01Y-1669700D02*
X1348400D01*
G01Y-1664500D02*
Y-1674900D01*
G01X1336900Y-1683000D02*
X1336100Y-1681200D01*
G01X1359000Y-1680000D02*
X1351300D01*
G01X1334800Y-1659400D02*
Y-1649200D01*
G01X1340900Y-1659400D02*
X1344700D01*
G01D02*
X1346600Y-1658800D01*
G01D02*
X1347900Y-1656800D01*
G01D02*
X1348400Y-1654300D01*
G01D02*
X1347900Y-1651700D01*
G01D02*
X1346600Y-1649800D01*
G01D02*
X1344700Y-1649200D01*
G01X1340900D02*
Y-1659400D01*
G01X1336900Y-1633700D02*
Y-1644000D01*
G01X1345100Y-1633700D02*
X1349700D01*
G01X1347500D02*
Y-1644000D01*
G01X1345100D02*
X1349700D01*
G01X1344700Y-1649200D02*
X1340900D01*
G01X1349100Y-1573600D02*
X1336400D01*
G01X1336300Y-1530500D02*
X1335500Y-1528700D01*
G01Y-1536700D02*
X1336300Y-1534900D01*
G01D02*
Y-1529700D01*
G01X1339200Y-1534900D02*
X1340000Y-1536700D01*
G01D02*
X1341700Y-1537700D01*
G01D02*
X1344000D01*
G01D02*
X1345900Y-1536700D01*
G01D02*
X1346600Y-1534900D01*
G01D02*
Y-1527500D01*
G01X1349600Y-1532700D02*
X1354600D01*
G01X1356800Y-1527500D02*
X1349600D01*
G01D02*
Y-1537800D01*
G01D02*
X1356800D01*
G01X1347400Y-1505700D02*
Y-1493200D01*
G01X1353600Y-1705700D02*
X1357400D01*
G01X1361200Y-1695400D02*
Y-1705700D01*
G01X1368800Y-1695400D02*
Y-1705700D01*
G01X1362700Y-1683400D02*
X1364000Y-1684600D01*
G01D02*
X1366300Y-1685200D01*
G01X1362400Y-1690200D02*
X1366300D01*
G01D02*
X1368500Y-1689800D01*
G01D02*
X1369800Y-1688400D01*
G01Y-1687000D02*
X1368500Y-1685600D01*
G01D02*
X1366300Y-1685200D01*
G01X1357400Y-1695400D02*
X1353600D01*
G01X1361200Y-1700600D02*
X1368800D01*
G01X1353700Y-1669700D02*
X1359000D01*
G01X1353700Y-1664500D02*
Y-1674900D01*
G01D02*
X1361200D01*
G01X1370100Y-1680000D02*
X1366300D01*
G01D02*
X1364000Y-1680500D01*
G01D02*
X1362700Y-1681800D01*
G01D02*
Y-1683400D01*
G01X1357500Y-1649200D02*
Y-1659400D01*
G01X1355200D02*
X1359800D01*
G01X1367300D02*
Y-1649200D01*
G01D02*
X1373300Y-1659400D01*
G01X1361200Y-1664500D02*
X1353700D01*
G01X1361800Y-1633700D02*
X1358100D01*
G01D02*
X1356200Y-1634000D01*
G01D02*
X1354700Y-1634800D01*
G01D02*
X1354300Y-1635900D01*
G01D02*
Y-1641800D01*
G01D02*
X1354700Y-1642800D01*
G01D02*
X1356200Y-1643700D01*
G01D02*
X1358100Y-1644000D01*
G01D02*
X1361800D01*
G01X1364900D02*
X1368600Y-1633700D01*
G01D02*
X1372500Y-1644000D01*
G01X1365700Y-1641800D02*
X1371600D01*
G01X1355200Y-1649200D02*
X1359800D01*
G01X1361100Y-1596200D02*
Y-1551000D01*
G01X1375600Y-1573600D02*
X1357500D01*
G01X1367100Y-1527500D02*
X1363500D01*
G01D02*
X1361700Y-1527800D01*
G01D02*
X1360400Y-1528700D01*
G01D02*
X1359800Y-1529700D01*
G01D02*
Y-1535600D01*
G01D02*
X1360400Y-1536800D01*
G01D02*
X1361700Y-1537500D01*
G01D02*
X1363500Y-1537800D01*
G01D02*
X1367100D01*
G01X1371900Y-1784300D02*
X1378500Y-1785800D01*
G01D02*
X1382400Y-1786000D01*
G01D02*
X1386000Y-1784900D01*
G01D02*
X1388800Y-1782600D01*
G01X1388000Y-1773900D02*
X1384900Y-1772000D01*
G01D02*
X1381000Y-1771400D01*
G01Y-1771300D02*
X1384600Y-1770400D01*
G01D02*
X1387200Y-1768600D01*
G01X1388000Y-1764200D02*
X1386000Y-1762100D01*
G01D02*
X1382900Y-1760800D01*
G01D02*
X1379300Y-1760400D01*
G01D02*
X1375400Y-1760800D01*
G01D02*
X1372300Y-1762300D01*
G01X1372500Y-1705700D02*
X1376300Y-1695400D01*
G01D02*
X1380100Y-1705700D01*
G01X1373300Y-1703500D02*
X1379300D01*
G01X1383800Y-1705700D02*
X1387700D01*
G01X1369800Y-1688400D02*
Y-1687000D01*
G01X1377300Y-1680000D02*
Y-1690200D01*
G01X1386200D02*
X1390600D01*
G01X1387700Y-1695400D02*
X1385500Y-1696000D01*
G01D02*
X1384000Y-1697200D01*
G01D02*
Y-1698800D01*
G01D02*
X1385500Y-1700100D01*
G01D02*
X1387700Y-1700600D01*
G01X1379400Y-1670400D02*
X1384000D01*
G01D02*
X1385700Y-1669800D01*
G01D02*
X1386800Y-1668400D01*
G01D02*
Y-1666600D01*
G01X1379400Y-1664500D02*
Y-1674900D01*
G01X1373500Y-1680000D02*
X1381200D01*
G01X1386200D02*
X1390600D01*
G01X1373300Y-1659400D02*
Y-1649200D01*
G01X1382400D02*
X1380900Y-1649800D01*
G01D02*
X1379800Y-1651700D01*
G01D02*
X1379400Y-1654300D01*
G01D02*
X1379800Y-1656800D01*
G01D02*
X1380900Y-1658800D01*
G01D02*
X1382400Y-1659400D01*
G01D02*
X1386900D01*
G01D02*
Y-1654300D01*
G01D02*
X1384000D01*
G01X1386800Y-1666600D02*
X1385700Y-1665100D01*
G01D02*
X1384000Y-1664500D01*
G01D02*
X1379400D01*
G01X1386900Y-1649200D02*
X1382400D01*
G01X1370100Y-1527500D02*
X1377500D01*
G01X1373800D02*
Y-1537800D01*
G01X1381900Y-1527500D02*
X1386200D01*
G01X1384100D02*
Y-1537800D01*
G01X1381900D02*
X1386200D01*
G01X1371900Y1601800D02*
X1378500Y1600200D01*
G01D02*
X1382400Y1600000D01*
G01D02*
X1386000Y1601200D01*
G01D02*
X1388800Y1603300D01*
G01X1381000Y1614800D02*
X1384600Y1615700D01*
G01D02*
X1387200Y1617400D01*
G01X1388000Y1621900D02*
X1386000Y1623800D01*
G01D02*
X1382900Y1625300D01*
G01D02*
X1379300Y1625700D01*
G01D02*
X1375400Y1625300D01*
G01D02*
X1372300Y1623800D01*
G01X1388000Y1612100D02*
X1384900Y1614000D01*
G01D02*
X1381000Y1614600D01*
G01X1388800Y-1782600D02*
X1390200Y-1779800D01*
G01D02*
X1389900Y-1776600D01*
G01D02*
X1388000Y-1773900D01*
G01X1387200Y-1768600D02*
X1388400Y-1766400D01*
G01D02*
X1388000Y-1764200D01*
G01X1387700Y-1705700D02*
X1389900Y-1705300D01*
G01D02*
X1391200Y-1704000D01*
G01D02*
Y-1702300D01*
G01D02*
X1389900Y-1701000D01*
G01X1398900Y-1695400D02*
Y-1705700D01*
G01X1396700D02*
X1401300D01*
G01X1388400Y-1680000D02*
Y-1690200D01*
G01X1395800Y-1683000D02*
Y-1688200D01*
G01Y-1687400D02*
X1396400Y-1689000D01*
G01D02*
X1398300Y-1690100D01*
G01D02*
X1400700D01*
G01D02*
X1402600Y-1689000D01*
G01D02*
X1403300Y-1687400D01*
G01D02*
Y-1682200D01*
G01X1391400Y-1695400D02*
X1387700D01*
G01X1389900Y-1701000D02*
X1387700Y-1700600D01*
G01X1396700Y-1695400D02*
X1401300D01*
G01X1392200Y-1669700D02*
X1397600D01*
G01X1392200Y-1664500D02*
Y-1674900D01*
G01D02*
X1399800D01*
G01X1403300Y-1683000D02*
X1402600Y-1681200D01*
G01D02*
X1400700Y-1680200D01*
G01D02*
X1398300D01*
G01D02*
X1396400Y-1681200D01*
G01D02*
X1395800Y-1683000D01*
G01X1399800Y-1664500D02*
X1392200D01*
G01X1387500Y-1633700D02*
X1392100D01*
G01X1389900D02*
Y-1644000D01*
G01X1387500D02*
X1392100D01*
G01X1397400D02*
Y-1633700D01*
G01D02*
X1403500Y-1644000D01*
G01D02*
Y-1633700D01*
G01X1398000Y-1530500D02*
X1397300Y-1528700D01*
G01D02*
X1395500Y-1527700D01*
G01D02*
X1393300D01*
G01D02*
X1391400Y-1528700D01*
G01D02*
X1390600Y-1530500D01*
G01D02*
Y-1535600D01*
G01Y-1534900D02*
X1391400Y-1536700D01*
G01D02*
X1393300Y-1537700D01*
G01D02*
X1395500D01*
G01D02*
X1397300Y-1536700D01*
G01D02*
X1398000Y-1534900D01*
G01D02*
Y-1529700D01*
G01X1401700Y-1537800D02*
Y-1527500D01*
G01D02*
X1407600Y-1537800D01*
G01X1388800Y1603300D02*
X1390200Y1606200D01*
G01D02*
X1389900Y1609300D01*
G01D02*
X1388000Y1612100D01*
G01X1387200Y1617400D02*
X1388400Y1619500D01*
G01D02*
X1388000Y1621900D01*
G01X1407300Y-1705700D02*
Y-1695400D01*
G01D02*
X1413400Y-1705700D01*
G01D02*
Y-1695400D01*
G01X1417800Y-1700600D02*
X1418200Y-1703200D01*
G01D02*
X1419400Y-1705000D01*
G01D02*
X1420900Y-1705700D01*
G01D02*
X1425500D01*
G01X1407600Y-1690200D02*
Y-1680000D01*
G01D02*
X1413700Y-1690200D01*
G01D02*
Y-1680000D01*
G01X1418100Y-1683400D02*
X1419400Y-1684600D01*
G01D02*
X1421600Y-1685200D01*
G01X1417900Y-1690200D02*
X1421600D01*
G01D02*
X1423800Y-1689800D01*
G01Y-1685600D02*
X1421600Y-1685200D01*
G01X1425500Y-1695400D02*
X1420900D01*
G01D02*
X1419400Y-1696100D01*
G01D02*
X1418200Y-1698000D01*
G01D02*
X1417800Y-1700600D01*
G01X1405100Y-1670400D02*
X1409500D01*
G01D02*
X1411300Y-1669800D01*
G01D02*
X1412500Y-1668400D01*
G01D02*
Y-1666600D01*
G01X1405100Y-1664500D02*
Y-1674900D01*
G01X1412600D02*
X1409500Y-1670400D01*
G01X1418700Y-1669700D02*
X1424700D01*
G01X1425500Y-1680000D02*
X1421600D01*
G01D02*
X1419400Y-1680500D01*
G01D02*
X1418100Y-1681800D01*
G01D02*
Y-1683400D01*
G01X1408800Y-1649200D02*
Y-1659400D01*
G01X1420400Y-1649300D02*
X1418500Y-1650400D01*
G01D02*
X1417800Y-1652100D01*
G01D02*
Y-1657100D01*
G01Y-1656400D02*
X1418500Y-1658200D01*
G01D02*
X1420400Y-1659200D01*
G01D02*
X1422800D01*
G01X1412500Y-1666600D02*
X1411300Y-1665100D01*
G01D02*
X1409500Y-1664500D01*
G01D02*
X1405100D01*
G01X1414800Y-1633700D02*
X1411000D01*
G01D02*
X1409200Y-1634000D01*
G01D02*
X1407700Y-1634800D01*
G01D02*
X1407300Y-1635900D01*
G01D02*
Y-1641800D01*
G01D02*
X1407700Y-1642800D01*
G01D02*
X1409200Y-1643700D01*
G01D02*
X1411000Y-1644000D01*
G01D02*
X1414800D01*
G01X1422200Y-1641900D02*
X1421000D01*
G01D02*
X1420400Y-1642800D01*
G01D02*
X1421000Y-1643900D01*
G01D02*
X1422200D01*
G01X1405100Y-1649200D02*
X1412600D01*
G01X1422800Y-1649300D02*
X1420400D01*
G01X1407600Y-1537800D02*
Y-1527500D01*
G01X1435200Y-1749600D02*
Y-1407900D01*
G01Y-1702200D02*
X2056300D01*
G01X1425500Y-1705700D02*
Y-1700600D01*
G01X1423800Y-1689800D02*
X1425300Y-1688400D01*
G01D02*
Y-1687000D01*
G01D02*
X1423800Y-1685600D01*
G01X1425500Y-1700600D02*
X1422400D01*
G01X1435200Y-1661000D02*
X2056300D01*
G01X1425500Y-1652100D02*
X1424700Y-1650400D01*
G01D02*
X1422800Y-1649300D01*
G01Y-1659200D02*
X1424700Y-1658200D01*
G01D02*
X1425500Y-1656400D01*
G01D02*
Y-1651400D01*
G01X1422800Y-1642800D02*
X1422200Y-1641900D01*
G01Y-1643900D02*
X1422800Y-1642800D01*
G01X2056300Y-1578700D02*
X1435200D01*
G01Y-1536500D02*
X2056300D01*
G01X1435200Y-1494300D02*
X2056300D01*
G01X1454400Y-1718400D02*
Y-1727100D01*
G01D02*
X1454900Y-1728500D01*
G01D02*
X1456000Y-1729500D01*
G01D02*
X1457800Y-1730200D01*
G01Y-1715500D02*
X1456000Y-1716200D01*
G01D02*
X1454900Y-1717200D01*
G01D02*
X1454400Y-1718400D01*
G01Y-1689200D02*
X1459900Y-1674000D01*
G01X1455600Y-1685900D02*
X1464200D01*
G01X1457800Y-1633100D02*
X1456000Y-1633800D01*
G01D02*
X1454900Y-1634800D01*
G01D02*
X1454400Y-1636200D01*
G01D02*
Y-1644700D01*
G01D02*
X1454900Y-1646100D01*
G01D02*
X1456000Y-1647100D01*
G01D02*
X1457800Y-1647800D01*
G01X1454400Y-1606900D02*
X1459900D01*
G01X1454400Y-1591700D02*
Y-1606900D01*
G01X1459900Y-1591700D02*
X1454400D01*
G01X1450400Y-1511400D02*
X1461200D01*
G01X1455700D02*
Y-1526600D01*
G01X1449700Y-1428400D02*
X1457100D01*
G01X1449700Y-1418700D02*
Y-1435800D01*
G01X1457100Y-1418700D02*
X1449700D01*
G01X1457800Y-1730200D02*
X1459900Y-1730400D01*
G01D02*
X1465300D01*
G01X1469800Y-1715200D02*
Y-1730400D01*
G01D02*
X1480500D01*
G01X1465300Y-1715200D02*
X1459900D01*
G01D02*
X1457800Y-1715500D01*
G01X1459900Y-1674000D02*
X1465300Y-1689200D01*
G01X1469800Y-1674000D02*
Y-1689200D01*
G01Y-1682700D02*
X1476300D01*
G01Y-1674000D02*
X1469800D01*
G01X1465300Y-1632800D02*
X1459900D01*
G01D02*
X1457800Y-1633100D01*
G01Y-1647800D02*
X1459900Y-1648100D01*
G01D02*
X1465300D01*
G01X1469800Y-1632800D02*
Y-1648100D01*
G01Y-1640500D02*
X1480500D01*
G01X1459900Y-1606900D02*
X1462200Y-1606200D01*
G01D02*
X1464200Y-1604000D01*
G01D02*
X1465200Y-1601000D01*
G01D02*
Y-1597600D01*
G01D02*
X1464200Y-1594500D01*
G01X1469800Y-1599300D02*
X1477300D01*
G01X1469800Y-1591700D02*
Y-1606900D01*
G01D02*
X1480500D01*
G01X1464200Y-1594500D02*
X1462200Y-1592500D01*
G01D02*
X1459900Y-1591700D01*
G01X1480500D02*
X1469800D01*
G01X1467700Y-1511400D02*
X1474300D01*
G01X1471100D02*
Y-1526600D01*
G01X1467700D02*
X1474300D01*
G01X1457100Y-1428400D02*
X1459400Y-1427800D01*
G01D02*
X1461200Y-1426100D01*
G01D02*
X1461900Y-1423600D01*
G01D02*
X1461200Y-1421200D01*
G01X1466800Y-1435800D02*
X1473000Y-1418700D01*
G01X1468100Y-1432100D02*
X1477700D01*
G01X1461200Y-1421200D02*
X1459400Y-1419400D01*
G01D02*
X1457100Y-1418700D01*
G01X1473000D02*
X1479100Y-1435800D01*
G01X1485000Y-1730400D02*
X1490400Y-1715200D01*
G01X1486200Y-1727100D02*
X1494700D01*
G01X1490400Y-1715200D02*
X1495800Y-1730400D01*
G01X1485000Y-1674000D02*
Y-1689200D01*
G01X1476300Y-1682700D02*
X1478500Y-1682100D01*
G01D02*
X1480000Y-1680500D01*
G01D02*
X1480500Y-1678400D01*
G01D02*
X1480000Y-1676200D01*
G01D02*
X1478500Y-1674600D01*
G01D02*
X1476300Y-1674000D01*
G01X1485000Y-1682700D02*
X1491500D01*
G01D02*
X1493700Y-1682100D01*
G01Y-1674600D02*
X1491500Y-1674000D01*
G01D02*
X1485000D01*
G01X1480500Y-1632800D02*
Y-1648100D01*
G01X1485000Y-1640500D02*
X1492500D01*
G01X1495800Y-1632800D02*
X1485000D01*
G01D02*
Y-1648100D01*
G01D02*
X1495800D01*
G01X1485000Y-1595400D02*
X1485700Y-1597300D01*
G01D02*
X1487600Y-1598800D01*
G01D02*
X1490400Y-1599300D01*
G01X1485000Y-1606900D02*
X1490400D01*
G01D02*
X1493100Y-1606400D01*
G01Y-1599900D02*
X1490400Y-1599300D01*
G01X1495800Y-1591700D02*
X1490400D01*
G01D02*
X1487600Y-1592200D01*
G01D02*
X1485700Y-1593700D01*
G01D02*
X1485000Y-1595400D01*
G01X1480800Y-1511400D02*
X1491800D01*
G01X1486300D02*
Y-1526600D01*
G01X1483900Y-1428400D02*
X1491300D01*
G01D02*
X1493800Y-1427800D01*
G01X1483900Y-1418700D02*
Y-1435800D01*
G01X1496200D02*
X1491300Y-1428400D01*
G01X1493800Y-1419400D02*
X1491300Y-1418700D01*
G01D02*
X1483900D01*
G01X1500200Y-1719000D02*
X1500900Y-1720900D01*
G01D02*
X1502800Y-1722300D01*
G01D02*
X1505600Y-1722800D01*
G01X1500200Y-1730400D02*
X1505600D01*
G01D02*
X1508300Y-1729900D01*
G01D02*
X1510400Y-1728500D01*
G01Y-1724800D02*
X1508300Y-1723300D01*
G01D02*
X1505600Y-1722800D01*
G01X1511100Y-1715200D02*
X1505600D01*
G01D02*
X1502800Y-1715800D01*
G01D02*
X1500900Y-1717100D01*
G01D02*
X1500200Y-1719000D01*
G01Y-1674000D02*
Y-1689200D01*
G01X1511100D02*
X1506700Y-1682700D01*
G01X1493700Y-1682100D02*
X1495200Y-1680500D01*
G01D02*
X1495800Y-1678400D01*
G01D02*
X1495200Y-1676200D01*
G01D02*
X1493700Y-1674600D01*
G01X1500200Y-1682700D02*
X1506700D01*
G01D02*
X1508900Y-1682100D01*
G01D02*
X1510500Y-1680500D01*
G01Y-1676200D02*
X1508900Y-1674600D01*
G01D02*
X1506700Y-1674000D01*
G01D02*
X1500200D01*
G01X1511100Y-1632800D02*
X1505600D01*
G01D02*
X1503600Y-1633100D01*
G01D02*
X1501800Y-1633800D01*
G01D02*
X1500600Y-1634800D01*
G01D02*
X1500200Y-1636200D01*
G01D02*
Y-1644700D01*
G01D02*
X1500600Y-1646100D01*
G01D02*
X1501800Y-1647100D01*
G01D02*
X1503600Y-1647800D01*
G01D02*
X1505600Y-1648100D01*
G01D02*
X1511100D01*
G01X1493100Y-1606400D02*
X1495000Y-1605000D01*
G01D02*
X1495800Y-1603100D01*
G01D02*
X1495000Y-1601200D01*
G01D02*
X1493100Y-1599900D01*
G01X1505600Y-1591700D02*
Y-1606900D01*
G01X1502400D02*
X1508900D01*
G01X1502400Y-1591700D02*
X1508900D01*
G01X1496000Y-1511400D02*
Y-1526600D01*
G01D02*
X1507000D01*
G01X1493800Y-1427800D02*
X1495600Y-1426100D01*
G01D02*
X1496200Y-1423600D01*
G01D02*
X1495600Y-1421200D01*
G01X1507300Y-1418700D02*
Y-1435800D01*
G01X1495600Y-1421200D02*
X1493800Y-1419400D01*
G01X1501100Y-1418700D02*
X1513300D01*
G01X1510400Y-1728500D02*
X1511100Y-1726500D01*
G01D02*
X1510400Y-1724800D01*
G01X1515400Y-1719000D02*
X1516100Y-1720900D01*
G01D02*
X1518000Y-1722300D01*
G01D02*
X1520900Y-1722800D01*
G01X1515400Y-1730400D02*
X1520900D01*
G01D02*
X1523500Y-1729900D01*
G01D02*
X1525600Y-1728500D01*
G01D02*
X1526300Y-1726500D01*
G01D02*
X1525600Y-1724800D01*
G01D02*
X1523500Y-1723300D01*
G01D02*
X1520900Y-1722800D01*
G01X1526300Y-1715200D02*
X1520900D01*
G01D02*
X1518000Y-1715800D01*
G01D02*
X1516100Y-1717100D01*
G01D02*
X1515400Y-1719000D01*
G01Y-1678400D02*
Y-1685900D01*
G01Y-1684900D02*
X1516100Y-1687100D01*
G01D02*
X1518000Y-1688600D01*
G01D02*
X1520900Y-1689200D01*
G01D02*
X1523500Y-1688600D01*
G01D02*
X1525600Y-1687100D01*
G01D02*
X1526300Y-1684900D01*
G01D02*
Y-1677200D01*
G01X1510500Y-1680500D02*
X1511100Y-1678400D01*
G01D02*
X1510500Y-1676200D01*
G01X1526300Y-1678400D02*
X1525600Y-1676200D01*
G01D02*
X1523500Y-1674600D01*
G01D02*
X1520900Y-1674000D01*
G01D02*
X1518000Y-1674600D01*
G01D02*
X1516100Y-1676200D01*
G01D02*
X1515400Y-1678400D01*
G01Y-1632800D02*
Y-1648100D01*
G01Y-1641500D02*
X1526300Y-1632800D01*
G01X1519100Y-1638500D02*
X1526300Y-1648100D01*
G01X1516300Y-1594500D02*
X1515500Y-1597600D01*
G01D02*
Y-1601000D01*
G01D02*
X1516300Y-1604000D01*
G01D02*
X1517900Y-1606200D01*
G01D02*
X1519800Y-1606900D01*
G01D02*
X1526300D01*
G01D02*
Y-1599300D01*
G01D02*
X1521900D01*
G01X1526300Y-1591700D02*
X1519800D01*
G01D02*
X1517900Y-1592500D01*
G01D02*
X1516300Y-1594500D01*
G01X1511300Y-1518900D02*
X1518900D01*
G01X1522200Y-1511400D02*
X1511300D01*
G01D02*
Y-1526600D01*
G01D02*
X1522200D01*
G01X1530600Y-1674000D02*
X1536100Y-1689200D01*
G01D02*
X1541500Y-1674000D01*
G01X1530600Y-1640500D02*
X1538300D01*
G01X1541500Y-1632800D02*
X1530600D01*
G01D02*
Y-1648100D01*
G01D02*
X1541500D01*
G01X1531800Y-1606900D02*
Y-1591700D01*
G01D02*
X1540500Y-1606900D01*
G01D02*
Y-1591700D01*
G01X1536700Y-1435800D02*
Y-1418700D01*
G01D02*
X1546400Y-1435800D01*
G01X1545800Y-1674000D02*
Y-1689200D01*
G01D02*
X1556700D01*
G01X1561200D02*
X1566500D01*
G01X1561200Y-1674000D02*
Y-1689200D01*
G01X1545800Y-1681700D02*
X1553500D01*
G01X1556700Y-1674000D02*
X1545800D01*
G01X1566500D02*
X1561200D01*
G01X1545800Y-1648100D02*
X1551300D01*
G01D02*
X1553600Y-1647300D01*
G01D02*
X1555600Y-1645200D01*
G01D02*
X1556600Y-1642100D01*
G01D02*
Y-1638800D01*
G01D02*
X1555600Y-1635700D01*
G01D02*
X1553600Y-1633700D01*
G01D02*
X1551300Y-1632800D01*
G01D02*
X1545800D01*
G01D02*
Y-1648100D01*
G01Y-1599300D02*
X1553500D01*
G01X1545800Y-1591700D02*
Y-1606900D01*
G01D02*
X1556700D01*
G01X1561200Y-1600400D02*
X1567700D01*
G01X1561200Y-1591700D02*
Y-1606900D01*
G01X1556700Y-1591700D02*
X1545800D01*
G01X1567700D02*
X1561200D01*
G01X1546400Y-1435800D02*
Y-1418700D01*
G01X1553500Y-1421200D02*
X1552600Y-1423600D01*
G01D02*
Y-1432100D01*
G01Y-1430900D02*
X1553500Y-1433400D01*
G01D02*
X1555700Y-1435200D01*
G01D02*
X1558700Y-1435800D01*
G01D02*
X1561800Y-1435200D01*
G01Y-1419400D02*
X1558700Y-1418700D01*
G01D02*
X1555700Y-1419400D01*
G01D02*
X1553500Y-1421200D01*
G01X1545800Y1379100D02*
Y1589100D01*
G01X1556100Y1444700D02*
X1562200D01*
G01X1556100Y1461800D02*
Y1444700D01*
G01X1562200Y1461800D02*
X1556100D01*
G01X1545800Y1478000D02*
X2056300D01*
G01X1566500Y-1689200D02*
X1568800Y-1688400D01*
G01D02*
X1570800Y-1686400D01*
G01D02*
X1571800Y-1683300D01*
G01D02*
Y-1679900D01*
G01D02*
X1570800Y-1676900D01*
G01D02*
X1568800Y-1674700D01*
G01D02*
X1566500Y-1674000D01*
G01X1567700Y-1600400D02*
X1569700Y-1599900D01*
G01D02*
X1571400Y-1598200D01*
G01D02*
X1571900Y-1596000D01*
G01Y-1606900D02*
X1567700Y-1600400D01*
G01X1571900Y-1596000D02*
X1571400Y-1593800D01*
G01D02*
X1569700Y-1592300D01*
G01D02*
X1567700Y-1591700D01*
G01X1564900Y-1423600D02*
X1564000Y-1421200D01*
G01X1561800Y-1435200D02*
X1564000Y-1433400D01*
G01D02*
X1564900Y-1430900D01*
G01D02*
Y-1422400D01*
G01X1577700Y-1434000D02*
X1577000Y-1432600D01*
G01D02*
X1575500Y-1432300D01*
G01D02*
X1574200Y-1433200D01*
G01D02*
Y-1434800D01*
G01D02*
X1575500Y-1435800D01*
G01D02*
X1577000Y-1435500D01*
G01D02*
X1577700Y-1434000D01*
G01X1564000Y-1421200D02*
X1561800Y-1419400D01*
G01X1562200Y1444700D02*
X1564900Y1445600D01*
G01D02*
X1567100Y1447900D01*
G01D02*
X1568300Y1451300D01*
G01D02*
Y1455200D01*
G01X1573300Y1453200D02*
X1581800D01*
G01X1573300Y1461800D02*
Y1444700D01*
G01D02*
X1585500D01*
G01X1568300Y1455200D02*
X1567100Y1458600D01*
G01D02*
X1564900Y1461100D01*
G01D02*
X1562200Y1461800D01*
G01X1585500D02*
X1573300D01*
G01X1565300Y1568400D02*
X1572500D01*
G01D02*
X1575000Y1569000D01*
G01D02*
X1576800Y1570800D01*
G01D02*
X1577400Y1573300D01*
G01D02*
X1576800Y1575800D01*
G01X1565300Y1578200D02*
Y1561000D01*
G01X1576800Y1575800D02*
X1575000Y1577600D01*
G01D02*
X1572500Y1578200D01*
G01D02*
X1565300D01*
G01X1590400Y1461800D02*
X1596600Y1444700D01*
G01X1582400Y1561000D02*
X1588500Y1578200D01*
G01D02*
X1594700Y1561000D01*
G01X1583800Y1564700D02*
X1593400D01*
G01X1607500Y-1755800D02*
Y-1788700D01*
G01X1606100Y-1578700D02*
Y-1749600D01*
G01X1596600Y1444700D02*
X1602700Y1461800D01*
G01X1607500Y1453200D02*
X1616100D01*
G01X1607500Y1461800D02*
Y1444700D01*
G01D02*
X1619800D01*
G01Y1461800D02*
X1607500D01*
G01X1599600Y1568400D02*
X1606900D01*
G01D02*
X1609300Y1569000D01*
G01D02*
X1611100Y1570800D01*
G01D02*
X1611800Y1573300D01*
G01D02*
X1611100Y1575800D01*
G01X1599600Y1578200D02*
Y1561000D01*
G01X1611800D02*
X1606900Y1568400D01*
G01X1611100Y1575800D02*
X1609300Y1577600D01*
G01D02*
X1606900Y1578200D01*
G01D02*
X1599600D01*
G01X1607500Y1628200D02*
Y1595300D01*
G01X1624700Y1461800D02*
Y1444700D01*
G01D02*
X1636900D01*
G01X1622900Y1578200D02*
Y1561000D01*
G01X1616700Y1578200D02*
X1628900D01*
G01X1641900Y1456900D02*
Y1448400D01*
G01Y1449500D02*
X1642700Y1447200D01*
G01D02*
X1644900Y1445400D01*
G01D02*
X1648000Y1444700D01*
G01D02*
X1651100Y1445400D01*
G01Y1461200D02*
X1648000Y1461800D01*
G01D02*
X1644900Y1461200D01*
G01D02*
X1642700Y1459400D01*
G01D02*
X1641900Y1456900D01*
G01X1651100Y1445400D02*
X1653300Y1447200D01*
G01D02*
X1654200Y1449500D01*
G01D02*
Y1458100D01*
G01X1659100Y1452100D02*
X1666400D01*
G01X1659100Y1461800D02*
Y1444700D01*
G01X1654200Y1456900D02*
X1653300Y1459400D01*
G01D02*
X1651100Y1461200D01*
G01X1666400Y1461800D02*
X1659100D01*
G01X1652300Y1561000D02*
Y1578200D01*
G01D02*
X1662000Y1561000D01*
G01D02*
Y1578200D01*
G01X1666400Y1452100D02*
X1668800Y1452600D01*
G01D02*
X1670600Y1454600D01*
G01X1676200Y1444700D02*
Y1461800D01*
G01D02*
X1682200Y1448400D01*
G01D02*
X1688400Y1461800D01*
G01X1670600Y1454600D02*
X1671300Y1456900D01*
G01D02*
X1670600Y1459400D01*
G01D02*
X1668800Y1461200D01*
G01D02*
X1666400Y1461800D01*
G01X1680500Y1573300D02*
X1679600Y1575800D01*
G01X1669000D02*
X1668200Y1573300D01*
G01D02*
Y1564700D01*
G01Y1565900D02*
X1669000Y1563500D01*
G01D02*
X1671200Y1561600D01*
G01D02*
X1674300Y1561000D01*
G01D02*
X1677400Y1561600D01*
G01D02*
X1679600Y1563500D01*
G01D02*
X1680500Y1565900D01*
G01D02*
Y1574500D01*
G01X1679600Y1575800D02*
X1677400Y1577600D01*
G01D02*
X1674300Y1578200D01*
G01D02*
X1671200Y1577600D01*
G01D02*
X1669000Y1575800D01*
G01X1688400Y1461800D02*
Y1444700D01*
G01X1693300Y1453200D02*
X1701900D01*
G01X1693300Y1461800D02*
Y1444700D01*
G01D02*
X1705600D01*
G01Y1461800D02*
X1693300D01*
G01Y1562800D02*
X1692600Y1564300D01*
G01D02*
X1691000Y1564700D01*
G01D02*
X1689800Y1563700D01*
G01D02*
Y1562100D01*
G01D02*
X1691000Y1561000D01*
G01D02*
X1692600Y1561500D01*
G01D02*
X1693300Y1562800D01*
G01X1711800Y1444700D02*
Y1461800D01*
G01D02*
X1721500Y1444700D01*
G01D02*
Y1461800D01*
G01X1733800D02*
Y1444700D01*
G01X1727600Y1461800D02*
X1739800D01*
G01X1754400Y-1407900D02*
Y-1494300D01*
G01X1767200Y-1427400D02*
X1773700D01*
G01X1767200Y-1418700D02*
Y-1433900D01*
G01X1773700Y-1418700D02*
X1767200D01*
G01X1763200Y1444700D02*
Y1461800D01*
G01D02*
X1772900Y1444700D01*
G01X1783200Y-1426400D02*
X1790900D01*
G01X1783200Y-1418700D02*
Y-1433900D01*
G01D02*
X1794100D01*
G01X1773700Y-1427400D02*
X1775900Y-1426800D01*
G01D02*
X1777500Y-1425200D01*
G01D02*
X1778100Y-1423100D01*
G01D02*
X1777500Y-1420900D01*
G01X1778100Y-1433900D02*
X1773700Y-1427400D01*
G01X1794100Y-1418700D02*
X1783200D01*
G01X1777500Y-1420900D02*
X1775900Y-1419300D01*
G01D02*
X1773700Y-1418700D01*
G01X1772900Y1444700D02*
Y1461800D01*
G01X1779100Y1456900D02*
Y1448400D01*
G01Y1449500D02*
X1780000Y1447200D01*
G01D02*
X1782200Y1445400D01*
G01D02*
X1785200Y1444700D01*
G01D02*
X1788300Y1445400D01*
G01Y1461200D02*
X1785200Y1461800D01*
G01D02*
X1782200Y1461200D01*
G01D02*
X1780000Y1459400D01*
G01D02*
X1779100Y1456900D01*
G01X1799100Y-1418700D02*
X1804600Y-1433900D01*
G01D02*
X1810000Y-1418700D01*
G01X1788300Y1445400D02*
X1790500Y1447200D01*
G01D02*
X1791400Y1449500D01*
G01D02*
Y1458100D01*
G01X1804200Y1446600D02*
X1803500Y1447900D01*
G01D02*
X1802000Y1448400D01*
G01D02*
X1800700Y1447300D01*
G01D02*
Y1445700D01*
G01D02*
X1802000Y1444700D01*
G01D02*
X1803500Y1445100D01*
G01D02*
X1804200Y1446600D01*
G01X1791400Y1456900D02*
X1790500Y1459400D01*
G01D02*
X1788300Y1461200D01*
G01X1823100Y1605500D02*
X1822700Y1603600D01*
G01D02*
Y1600000D01*
G01D02*
X1841100D01*
G01X1823500Y1621400D02*
X1822700Y1618300D01*
G01X1837700Y-1774400D02*
X1841000Y-1772500D01*
G01X1837700Y-1774400D02*
X1827700Y-1778100D01*
G01D02*
X1826200Y-1779100D01*
G01D02*
X1825200Y-1780600D01*
G01D02*
X1824700Y-1782400D01*
G01D02*
Y-1786000D01*
G01D02*
X1843200D01*
G01X1841700Y-1763800D02*
X1838900Y-1761500D01*
G01D02*
X1835200Y-1760500D01*
G01D02*
X1831400Y-1760600D01*
G01D02*
X1828000Y-1762100D01*
G01D02*
X1825600Y-1764600D01*
G01D02*
X1824700Y-1767700D01*
G01X1823400Y-1578700D02*
Y-1749600D01*
G01Y-1576800D02*
Y-1583600D01*
G01Y-1407900D02*
Y-1494300D01*
G01X1835800Y1611700D02*
X1825600Y1608000D01*
G01D02*
X1824100Y1606900D01*
G01D02*
X1823100Y1605500D01*
G01X1835700Y1611700D02*
X1838900Y1613600D01*
G01D02*
X1840700Y1616200D01*
G01X1841000Y1619400D02*
X1839600Y1622300D01*
G01D02*
X1836800Y1624500D01*
G01D02*
X1833100Y1625600D01*
G01D02*
X1829300Y1625400D01*
G01D02*
X1825900Y1623900D01*
G01D02*
X1823500Y1621400D01*
G01X1841000Y-1772500D02*
X1842700Y-1769800D01*
G01D02*
X1843000Y-1766700D01*
G01D02*
X1841700Y-1763800D01*
G01X1840700Y1616200D02*
X1841000Y1619400D01*
G01X1949200Y1478000D02*
Y1379100D01*
G01X1959500Y1456900D02*
Y1449500D01*
G01D02*
X1960400Y1447200D01*
G01D02*
X1962600Y1445400D01*
G01Y1461200D02*
X1960400Y1459400D01*
G01D02*
X1959500Y1456900D01*
G01X1949200Y1589100D02*
Y1478000D01*
G01X1959500Y1578200D02*
Y1563000D01*
G01Y1569500D02*
X1966000D01*
G01Y1578200D02*
X1959500D01*
G01X1962600Y1445400D02*
X1965700Y1444700D01*
G01D02*
X1968700Y1445400D01*
G01D02*
X1971100Y1447200D01*
G01D02*
X1971800Y1449500D01*
G01D02*
Y1456900D01*
G01X1965700Y1450900D02*
X1973000Y1443500D01*
G01X1976700Y1444700D02*
X1988900Y1461800D01*
G01X1971800Y1456900D02*
X1971100Y1459400D01*
G01D02*
X1968700Y1461200D01*
G01D02*
X1965700Y1461800D01*
G01D02*
X1962600Y1461200D01*
G01X1970400Y1563000D02*
X1966000Y1569500D01*
G01X1970400Y1573800D02*
X1969800Y1576000D01*
G01Y1571700D02*
X1970400Y1573800D01*
G01X1968200Y1570100D02*
X1969800Y1571700D01*
G01X1966000Y1569500D02*
X1968200Y1570100D01*
G01X1975500Y1570500D02*
X1983200D01*
G01X1975500Y1578200D02*
Y1563000D01*
G01D02*
X1986400D01*
G01X1968200Y1577600D02*
X1966000Y1578200D01*
G01X1969800Y1576000D02*
X1968200Y1577600D01*
G01X1986400Y1578200D02*
X1975500D01*
G01X1993800Y1444700D02*
Y1461800D01*
G01D02*
X2000000Y1448400D01*
G01X1996900Y1563000D02*
X2002300Y1578200D01*
G01X1991400D02*
X1996900Y1563000D01*
G01X2000000Y1448400D02*
X2006000Y1461800D01*
G01D02*
Y1444700D01*
G01X2056300Y1589100D02*
Y-1749600D01*
G01X2062500Y-1412000D02*
X2095400D01*
G01X2062500Y-1078500D02*
X2095400D01*
G01X2062500Y-745100D02*
X2095400D01*
G01X2062500Y-411500D02*
X2095400D01*
G01X2062500Y-82400D02*
X2105700D01*
G01X2062500Y251200D02*
X2095400D01*
G01X2062500Y584600D02*
X2095400D01*
G01X2062500Y918100D02*
X2095400D01*
G01X2062500Y1251500D02*
X2095400D01*
G01X2071000Y-1735700D02*
X2070400Y-1737200D01*
G01D02*
X2071000Y-1738800D01*
G01D02*
X2072600Y-1739800D01*
G01D02*
X2074700Y-1740300D01*
G01X2070400Y-1746500D02*
X2074700D01*
G01D02*
X2076900Y-1746000D01*
G01D02*
X2078500Y-1745000D01*
G01D02*
X2079100Y-1743400D01*
G01D02*
X2078500Y-1741900D01*
G01D02*
X2076900Y-1740700D01*
G01D02*
X2074700Y-1740300D01*
G01X2070400Y-1728000D02*
X2074700D01*
G01D02*
X2076900Y-1727100D01*
G01D02*
X2078500Y-1724900D01*
G01D02*
X2079100Y-1721800D01*
G01D02*
X2078500Y-1718700D01*
G01X2070400Y-1715600D02*
Y-1728000D01*
G01X2079100Y-1734100D02*
X2074700D01*
G01D02*
X2072600Y-1734500D01*
G01D02*
X2071000Y-1735700D01*
G01X2070400Y-1704100D02*
X2075600D01*
G01D02*
X2077700Y-1703500D01*
G01D02*
X2079000Y-1701700D01*
G01X2070400Y-1697000D02*
Y-1709400D01*
G01X2078500Y-1718700D02*
X2076900Y-1716400D01*
G01D02*
X2074700Y-1715600D01*
G01D02*
X2070400D01*
G01X2079000Y-1701700D02*
Y-1699500D01*
G01D02*
X2077700Y-1697700D01*
G01D02*
X2075600Y-1697000D01*
G01D02*
X2070400D01*
G01X2068700Y-1593700D02*
X2077800Y-1568000D01*
G01D02*
X2087100Y-1593700D01*
G01X2070600Y-1588200D02*
X2085000D01*
G01X2068700Y-1232300D02*
Y-1258000D01*
G01D02*
X2077800D01*
G01D02*
X2081400Y-1257600D01*
G01D02*
X2084300Y-1256000D01*
G01D02*
X2086400Y-1253600D01*
G01Y-1248000D02*
X2084300Y-1245500D01*
G01D02*
X2081400Y-1244000D01*
G01D02*
X2077800Y-1243400D01*
G01D02*
X2068700D01*
G01X2077800D02*
X2081100Y-1242800D01*
G01D02*
X2083600Y-1241300D01*
G01D02*
X2085000Y-1239100D01*
G01Y-1236600D02*
X2083600Y-1234400D01*
G01D02*
X2081100Y-1232900D01*
G01D02*
X2077800Y-1232300D01*
G01D02*
X2068700D01*
G01Y-904400D02*
Y-919200D01*
G01D02*
X2069400Y-921200D01*
G01D02*
X2071300Y-923000D01*
G01D02*
X2074400Y-924200D01*
G01D02*
X2077800Y-924600D01*
G01D02*
X2087100D01*
G01X2074400Y-899400D02*
X2071300Y-900600D01*
G01D02*
X2069400Y-902300D01*
G01D02*
X2068700Y-904400D01*
G01X2087100Y-898900D02*
X2077800D01*
G01D02*
X2074400Y-899400D01*
G01X2068700Y-591200D02*
X2077800D01*
G01D02*
X2081400Y-590200D01*
G01D02*
X2084300Y-587400D01*
G01D02*
X2086400Y-583300D01*
G01X2068700Y-565400D02*
Y-591200D01*
G01X2086400Y-573400D02*
X2084300Y-569200D01*
G01D02*
X2081400Y-566400D01*
G01D02*
X2077800Y-565400D01*
G01D02*
X2068700D01*
G01Y-232000D02*
Y-257700D01*
G01D02*
X2087100D01*
G01X2068700Y-244800D02*
X2081500D01*
G01X2087100Y-232000D02*
X2068700D01*
G01Y71500D02*
Y97300D01*
G01Y84300D02*
X2081500D01*
G01X2068700Y97300D02*
X2087100D01*
G01X2071300Y408000D02*
X2073500Y405800D01*
G01D02*
X2076000Y405000D01*
G01D02*
X2087100D01*
G01X2071300Y427800D02*
X2069700Y424200D01*
G01D02*
X2068800Y420100D01*
G01D02*
Y415700D01*
G01D02*
X2069700Y411400D01*
G01D02*
X2071300Y408000D01*
G01X2087100Y417900D02*
X2079700D01*
G01X2087100Y430700D02*
X2076000D01*
G01D02*
X2073500Y430000D01*
G01D02*
X2071300Y427800D01*
G01X2068700Y764100D02*
Y738400D01*
G01Y751300D02*
X2087100D01*
G01X2068700Y1079200D02*
X2069400Y1076400D01*
G01D02*
X2071300Y1074100D01*
G01D02*
X2074400Y1072400D01*
G01D02*
X2077800Y1072000D01*
G01D02*
X2081400Y1072400D01*
G01D02*
X2084300Y1074100D01*
G01D02*
X2086400Y1076400D01*
G01X2068700Y1433200D02*
Y1407500D01*
G01Y1418500D02*
X2087100Y1433200D01*
G01X2075000Y1423600D02*
X2087100Y1407500D01*
G01X2086400Y-1253600D02*
X2087100Y-1250800D01*
G01D02*
X2086400Y-1248000D01*
G01X2085000Y-1239100D02*
Y-1236600D01*
G01X2086400Y-583300D02*
X2087100Y-578400D01*
G01D02*
X2086400Y-573400D01*
G01X2087100Y405000D02*
Y417900D01*
G01Y764100D02*
Y738400D01*
G01X2086400Y1076400D02*
X2087100Y1079200D01*
G01D02*
Y1097700D01*
G54D13*
G01X-2400850Y-1730000D02*
Y-1705000D01*
X-2392975D01*
X-2390455Y-1706250D01*
X-2388880Y-1707917D01*
X-2388250Y-1711250D01*
X-2388880Y-1714584D01*
X-2390770Y-1716666D01*
X-2392975Y-1717917D01*
X-2400850D01*
G01X-2392975D02*
X-2388250Y-1730000D01*
G01X-2365570D02*
Y-1705000D01*
X-2377225Y-1722917D01*
X-2361475D01*
G01X-2344150Y-1705000D02*
X-2346670Y-1705833D01*
X-2348560Y-1707917D01*
X-2349820Y-1710416D01*
X-2350765Y-1713750D01*
X-2351080Y-1717500D01*
X-2350765Y-1721250D01*
X-2349820Y-1724584D01*
X-2348560Y-1727084D01*
X-2346670Y-1729167D01*
X-2344150Y-1730000D01*
X-2341630Y-1729167D01*
X-2339740Y-1727084D01*
X-2338480Y-1724584D01*
X-2337535Y-1721250D01*
X-2337220Y-1717500D01*
X-2337535Y-1713750D01*
X-2338480Y-1710416D01*
X-2339740Y-1707917D01*
X-2341630Y-1705833D01*
X-2344150Y-1705000D01*
G01X-2318950D02*
X-2321470Y-1705833D01*
X-2323360Y-1707917D01*
X-2324620Y-1710416D01*
X-2325565Y-1713750D01*
X-2325880Y-1717500D01*
X-2325565Y-1721250D01*
X-2324620Y-1724584D01*
X-2323360Y-1727084D01*
X-2321470Y-1729167D01*
X-2318950Y-1730000D01*
X-2316430Y-1729167D01*
X-2314540Y-1727084D01*
X-2313280Y-1724584D01*
X-2312335Y-1721250D01*
X-2312020Y-1717500D01*
X-2312335Y-1713750D01*
X-2313280Y-1710416D01*
X-2314540Y-1707917D01*
X-2316430Y-1705833D01*
X-2318950Y-1705000D01*
G01X-2299735Y-1719584D02*
X-2297530Y-1716666D01*
X-2295640Y-1715000D01*
X-2293120Y-1714167D01*
X-2290915Y-1715000D01*
X-2289340Y-1716666D01*
X-2288080Y-1719167D01*
X-2287765Y-1722083D01*
X-2288080Y-1724584D01*
X-2289340Y-1727084D01*
X-2291230Y-1729167D01*
X-2293435Y-1730000D01*
X-2295955Y-1729167D01*
X-2298160Y-1726667D01*
X-2299420Y-1722917D01*
X-2299735Y-1718750D01*
X-2299105Y-1713334D01*
X-2298160Y-1710416D01*
X-2296585Y-1707500D01*
X-2294380Y-1705417D01*
X-2292175Y-1705000D01*
X-2289970Y-1705833D01*
X-2288395Y-1707917D01*
G01X-2272645Y-1721667D02*
X-2264455D01*
G01X-2240830Y-1716666D02*
X-2239570Y-1715417D01*
X-2238625Y-1713334D01*
X-2237995Y-1710416D01*
X-2238625Y-1707917D01*
X-2239885Y-1706250D01*
X-2242090Y-1705000D01*
X-2250595D01*
Y-1730000D01*
X-2240200D01*
X-2237995Y-1728334D01*
X-2236735Y-1725833D01*
X-2236105Y-1722917D01*
X-2236735Y-1720001D01*
X-2238625Y-1717500D01*
X-2240830Y-1716666D01*
X-2250595D01*
G01X-2218150Y-1705000D02*
X-2220670Y-1705833D01*
X-2222560Y-1707917D01*
X-2223820Y-1710416D01*
X-2224765Y-1713750D01*
X-2225080Y-1717500D01*
X-2224765Y-1721250D01*
X-2223820Y-1724584D01*
X-2222560Y-1727084D01*
X-2220670Y-1729167D01*
X-2218150Y-1730000D01*
X-2215630Y-1729167D01*
X-2213740Y-1727084D01*
X-2212480Y-1724584D01*
X-2211535Y-1721250D01*
X-2211220Y-1717500D01*
X-2211535Y-1713750D01*
X-2212480Y-1710416D01*
X-2213740Y-1707917D01*
X-2215630Y-1705833D01*
X-2218150Y-1705000D01*
G01X-2192950D02*
X-2195470Y-1705833D01*
X-2197360Y-1707917D01*
X-2198620Y-1710416D01*
X-2199565Y-1713750D01*
X-2199880Y-1717500D01*
X-2199565Y-1721250D01*
X-2198620Y-1724584D01*
X-2197360Y-1727084D01*
X-2195470Y-1729167D01*
X-2192950Y-1730000D01*
X-2190430Y-1729167D01*
X-2188540Y-1727084D01*
X-2187280Y-1724584D01*
X-2186335Y-1721250D01*
X-2186020Y-1717500D01*
X-2186335Y-1713750D01*
X-2187280Y-1710416D01*
X-2188540Y-1707917D01*
X-2190430Y-1705833D01*
X-2192950Y-1705000D01*
G01X-2167750D02*
X-2170270Y-1705833D01*
X-2172160Y-1707917D01*
X-2173420Y-1710416D01*
X-2174365Y-1713750D01*
X-2174680Y-1717500D01*
X-2174365Y-1721250D01*
X-2173420Y-1724584D01*
X-2172160Y-1727084D01*
X-2170270Y-1729167D01*
X-2167750Y-1730000D01*
X-2165230Y-1729167D01*
X-2163340Y-1727084D01*
X-2162080Y-1724584D01*
X-2161135Y-1721250D01*
X-2160820Y-1717500D01*
X-2161135Y-1713750D01*
X-2162080Y-1710416D01*
X-2163340Y-1707917D01*
X-2165230Y-1705833D01*
X-2167750Y-1705000D01*
G01X-2142550Y-1730000D02*
Y-1705000D01*
X-2146330Y-1710000D01*
G01Y-1730000D02*
X-2138771D01*
G01X-2121445Y-1721667D02*
X-2113255D01*
G01X-2092150Y-1705000D02*
X-2094670Y-1705833D01*
X-2096560Y-1707917D01*
X-2097820Y-1710416D01*
X-2098765Y-1713750D01*
X-2099080Y-1717500D01*
X-2098765Y-1721250D01*
X-2097820Y-1724584D01*
X-2096560Y-1727084D01*
X-2094670Y-1729167D01*
X-2092150Y-1730000D01*
X-2089630Y-1729167D01*
X-2087740Y-1727084D01*
X-2086480Y-1724584D01*
X-2085535Y-1721250D01*
X-2085220Y-1717500D01*
X-2085535Y-1713750D01*
X-2086480Y-1710416D01*
X-2087740Y-1707917D01*
X-2089630Y-1705833D01*
X-2092150Y-1705000D01*
G01X-2072935Y-1709167D02*
X-2071045Y-1706667D01*
X-2068840Y-1705417D01*
X-2066320Y-1705000D01*
X-2063170Y-1705833D01*
X-2060965Y-1707917D01*
X-2060335Y-1710416D01*
X-2060650Y-1712917D01*
X-2061910Y-1715000D01*
X-2068210Y-1719167D01*
X-2071045Y-1722083D01*
X-2072935Y-1726251D01*
X-2073565Y-1730000D01*
X-2060335D01*
G01X-1950280Y-236788D02*
X-2086500D01*
G01D02*
Y-180096D01*
G01D02*
X-1950280D01*
G01Y-122616D02*
X-2086500D01*
G01D02*
Y-65924D01*
G01D02*
X-1950280D01*
G01Y-8442D02*
X-2086500D01*
G01D02*
Y48250D01*
G01D02*
X-1950280D01*
G01Y105732D02*
X-2086500D01*
G01D02*
Y162424D01*
G01D02*
X-1950280D01*
G01X-2012266Y-150030D02*
X-2010462Y-147630D01*
Y-149430D01*
X-2008662D01*
Y-150630D01*
X-2010462D01*
Y-152430D01*
X-2012266Y-150030D01*
G01Y-35856D02*
X-2010462Y-33456D01*
Y-35256D01*
X-2008662D01*
Y-36456D01*
X-2010462D01*
Y-38256D01*
X-2012266Y-35856D01*
G01Y78318D02*
X-2010462Y80718D01*
Y78918D01*
X-2008662D01*
Y77718D01*
X-2010462D01*
Y75918D01*
X-2012266Y78318D01*
G01Y192490D02*
X-2010462Y194890D01*
Y193090D01*
X-2008662D01*
Y191890D01*
X-2010462D01*
Y190090D01*
X-2012266Y192490D01*
G01X-1909516Y316678D02*
X-2025656D01*
G01D02*
Y347858D01*
G01X-2012266Y306664D02*
X-2010462Y309064D01*
Y307264D01*
X-2008662D01*
Y306064D01*
X-2010462D01*
Y304264D01*
X-2012266Y306664D01*
G01X-2025656Y347858D02*
X-1909516D01*
G01X-2010704Y516360D02*
Y-307654D01*
G01D02*
G03X-2002830Y-315528I7874J0D01*
G01D02*
X-1900468D01*
G01X-2003420Y-148404D02*
Y-166120D01*
G01D02*
X-1999484D01*
G01D02*
Y-167696D01*
G01D02*
X-1994366D01*
G01X-2012100Y-163042D02*
X-2010296Y-160642D01*
Y-162442D01*
X-2008496D01*
Y-163642D01*
X-2010296D01*
Y-165442D01*
X-2012100Y-163042D01*
G01X-2011378Y-164002D02*
X-2010296D01*
G01X-2010782Y-152002D02*
X-2010462D01*
G01X-1994366Y-146828D02*
X-1999484D01*
G01D02*
Y-148404D01*
G01D02*
X-2003420D01*
G01X-2010742Y-148002D02*
X-2010462D01*
G01X-2003420Y-34230D02*
Y-51946D01*
G01D02*
X-1999484D01*
G01D02*
Y-53522D01*
G01D02*
X-1994366D01*
G01X-2012100Y-48868D02*
X-2010296Y-46468D01*
Y-48268D01*
X-2008496D01*
Y-49468D01*
X-2010296D01*
Y-51268D01*
X-2012100Y-48868D01*
G01X-2011450Y-48002D02*
X-2010296D01*
G01X-1994366Y-32654D02*
X-1999484D01*
G01D02*
Y-34230D01*
G01D02*
X-2003420D01*
G01X-2012156Y-36002D02*
X-2008662D01*
G01X-2003420Y79944D02*
Y62228D01*
G01D02*
X-1999484D01*
G01D02*
Y60652D01*
G01D02*
X-1994366D01*
G01X-2010522Y75998D02*
X-2010462D01*
G01X-2012100Y65306D02*
X-2010296Y67706D01*
Y65906D01*
X-2008496D01*
Y64706D01*
X-2010296D01*
Y62906D01*
X-2012100Y65306D01*
G01X-2011116Y63998D02*
X-2010296D01*
G01X-1994366Y81520D02*
X-1999484D01*
G01D02*
Y79944D01*
G01D02*
X-2003420D01*
G01X-2011004Y79998D02*
X-2010462D01*
G01X-2003420Y194116D02*
Y176400D01*
G01D02*
X-1999484D01*
G01D02*
Y174824D01*
G01D02*
X-1994366D01*
G01X-2012100Y179478D02*
X-2010296Y181878D01*
Y180078D01*
X-2008496D01*
Y178878D01*
X-2010296D01*
Y177078D01*
X-2012100Y179478D01*
G01X-2011710Y179998D02*
X-2008496D01*
G01X-1994366Y195692D02*
X-1999484D01*
G01D02*
Y194116D01*
G01D02*
X-2003420D01*
G01X-2011896Y191998D02*
X-2008662D01*
G01X-2003420Y308290D02*
Y290574D01*
G01D02*
X-1999484D01*
G01D02*
Y288998D01*
G01D02*
X-1994366D01*
G01X-2012100Y293652D02*
X-2010296Y296052D01*
Y294252D01*
X-2008496D01*
Y293052D01*
X-2010296D01*
Y291252D01*
X-2012100Y293652D01*
G01X-2010856Y291998D02*
X-2010296D01*
G01X-2010338Y295998D02*
X-2010296D01*
G01X-1994366Y309866D02*
X-1999484D01*
G01D02*
Y308290D01*
G01D02*
X-2003420D01*
G01X-2011264Y307998D02*
X-2010462D01*
G01X-698500Y524234D02*
X-2002830D01*
G01D02*
G03X-2010704Y516360I0J-7874D01*
G01X-1982050Y-1703000D02*
X-1984570Y-1703833D01*
X-1986460Y-1705917D01*
X-1987720Y-1708416D01*
X-1988665Y-1711750D01*
X-1988980Y-1715500D01*
X-1988665Y-1719250D01*
X-1987720Y-1722584D01*
X-1986460Y-1725084D01*
X-1984570Y-1727167D01*
X-1982050Y-1728000D01*
X-1979530Y-1727167D01*
X-1977640Y-1725084D01*
X-1976380Y-1722584D01*
X-1975435Y-1719250D01*
X-1975120Y-1715500D01*
X-1975435Y-1711750D01*
X-1976380Y-1708416D01*
X-1977640Y-1705917D01*
X-1979530Y-1703833D01*
X-1982050Y-1703000D01*
G01X-1956850Y-1728000D02*
Y-1703000D01*
X-1960630Y-1708000D01*
G01Y-1728000D02*
X-1953071D01*
G01X-1994366Y-167696D02*
Y-146828D01*
G01Y-53522D02*
Y-32654D01*
G01Y60652D02*
Y81520D01*
G01Y174824D02*
Y195692D01*
G01Y288998D02*
Y309866D01*
G01X-1928048Y-277340D02*
G03I-23600J0D01*
G01X-1966204Y-156062D02*
Y-159962D01*
G01X-1973004Y-156062D02*
X-1966204D01*
G01X-1973004Y-159962D02*
Y-156062D01*
G01X-1966204Y-159962D02*
X-1973004D01*
G01X-1974954Y-156062D02*
Y-145862D01*
G01X-1952454Y-156062D02*
X-1974954D01*
G01X-1968104Y-153962D02*
G03I-1500J0D01*
G01X-1969404Y-141962D02*
Y-145862D01*
G01X-1973004Y-141962D02*
X-1969404D01*
G01X-1973004Y-145862D02*
Y-141962D01*
G01X-1969404Y-145862D02*
X-1973004D01*
G01X-1974954D02*
X-1952454D01*
G01X-1970104Y-45366D02*
Y-37366D01*
G01D02*
X-1974904D01*
G01D02*
Y-45366D01*
G01D02*
X-1970104D01*
G01X-1961104D02*
Y-37366D01*
G01D02*
X-1965904D01*
G01D02*
Y-45366D01*
G01D02*
X-1961104D01*
G01X-1952454Y71938D02*
X-1974954D01*
G01D02*
Y82138D01*
G01X-1966204Y68038D02*
X-1973004D01*
G01D02*
Y71938D01*
G01D02*
X-1966204D01*
G01D02*
Y68038D01*
G01X-1968104Y74038D02*
G03I-1500J0D01*
G01X-1974954Y82138D02*
X-1952454D01*
G01X-1969404D02*
X-1973004D01*
G01D02*
Y86038D01*
G01D02*
X-1969404D01*
G01D02*
Y82138D01*
G01X-1968904Y182054D02*
Y190054D01*
G01X-1973704D02*
Y182054D01*
G01D02*
X-1968904D01*
G01X-1964704Y190054D02*
Y182054D01*
G01D02*
X-1959904D01*
G01X-1968904Y190054D02*
X-1973704D01*
G01X-1959904D02*
X-1964704D01*
G01X-1962304Y287038D02*
Y295038D01*
G01X-1967104D02*
Y287038D01*
G01D02*
X-1962304D01*
G01X-1972304D02*
Y295038D01*
G01X-1977104D02*
Y287038D01*
G01D02*
X-1972304D01*
G01X-1962304Y295038D02*
X-1967104D01*
G01X-1972304D02*
X-1977104D01*
G01X-1928048Y395100D02*
G03I-23600J0D01*
G01X-1950280Y-180096D02*
Y-236788D01*
G01X-1958004Y-156062D02*
X-1954404D01*
G01X-1958004Y-159962D02*
Y-156062D01*
G01X-1954404Y-159962D02*
X-1958004D01*
G01X-1954404Y-156062D02*
Y-159962D01*
G01X-1952454Y-145862D02*
Y-156062D01*
G01X-1958004Y-141962D02*
X-1954404D01*
G01X-1958004Y-145862D02*
Y-141962D01*
G01X-1954404Y-145862D02*
X-1958004D01*
G01X-1954404Y-141962D02*
Y-145862D01*
G01X-1950280Y-65924D02*
Y-122616D01*
G01X-1952104Y-37366D02*
X-1956904D01*
G01D02*
Y-45366D01*
G01D02*
X-1952104D01*
G01D02*
Y-37366D01*
G01X-1943104Y-45366D02*
Y-37366D01*
G01D02*
X-1947904D01*
G01D02*
Y-45366D01*
G01D02*
X-1943104D01*
G01X-1950280Y48250D02*
Y-8442D01*
G01X-1954404Y68038D02*
X-1958004D01*
G01D02*
Y71938D01*
G01D02*
X-1954404D01*
G01X-1952454Y82138D02*
Y71938D01*
G01X-1954404D02*
Y68038D01*
G01Y82138D02*
X-1958004D01*
G01D02*
Y86038D01*
G01D02*
X-1954404D01*
G01D02*
Y82138D01*
G01X-1950280Y162424D02*
Y105732D01*
G01X-1955704Y190054D02*
Y182054D01*
G01D02*
X-1950904D01*
G01X-1959904D02*
Y190054D01*
G01X-1950904D02*
X-1955704D01*
G01X-1950904Y182054D02*
Y190054D01*
G01X-1946704D02*
Y182054D01*
G01D02*
X-1941904D01*
G01Y190054D02*
X-1946704D01*
G01X-1957104Y295038D02*
Y287038D01*
G01D02*
X-1952304D01*
G01Y295038D02*
X-1957104D01*
G01X-1947104D02*
Y287038D01*
G01D02*
X-1942304D01*
G01X-1952304D02*
Y295038D01*
G01X-1942304D02*
X-1947104D01*
G01X-1925104Y-45366D02*
Y-37366D01*
G01D02*
X-1929904D01*
G01D02*
Y-45366D01*
G01D02*
X-1925104D01*
G01X-1934104D02*
Y-37366D01*
G01D02*
X-1938904D01*
G01D02*
Y-45366D01*
G01D02*
X-1934104D01*
G01X-1941904Y182054D02*
Y190054D01*
G01X-1928704D02*
Y182054D01*
G01D02*
X-1923904D01*
G01X-1932904D02*
Y190054D01*
G01X-1937704D02*
Y182054D01*
G01D02*
X-1932904D01*
G01X-1923904Y190054D02*
X-1928704D01*
G01X-1932904D02*
X-1937704D01*
G01X-1942304Y287038D02*
Y295038D01*
G01X-1932304Y287038D02*
Y295038D01*
G01X-1937104D02*
Y287038D01*
G01D02*
X-1932304D01*
G01X-1927104Y295038D02*
Y287038D01*
G01D02*
X-1922304D01*
G01X-1932304Y295038D02*
X-1937104D01*
G01X-1922304D02*
X-1927104D01*
G01X-1924504Y-213362D02*
Y-221362D01*
G01D02*
X-1919704D01*
G01D02*
Y-213362D01*
G01D02*
X-1924504D01*
G01X-1909524Y-198994D02*
Y-217890D01*
G01D02*
X-1892988D01*
G01Y-198994D02*
X-1909524D01*
G01X-1911304Y-173962D02*
Y-165962D01*
G01X-1916104D02*
Y-173962D01*
G01D02*
X-1911304D01*
G01Y-165962D02*
X-1916104D01*
G01X-1910384Y-149662D02*
Y-152262D01*
G01D02*
X-1905424D01*
G01X-1922104Y-125982D02*
Y-133982D01*
G01D02*
X-1917304D01*
G01D02*
Y-125982D01*
G01X-1912104D02*
Y-133982D01*
G01D02*
X-1907304D01*
G01X-1905424Y-149662D02*
X-1910384D01*
G01X-1917304Y-125982D02*
X-1922104D01*
G01X-1907304D02*
X-1912104D01*
G01X-1922104Y-107162D02*
Y-115162D01*
G01D02*
X-1917304D01*
G01Y-107162D02*
X-1922104D01*
G01X-1909524Y-84822D02*
Y-103718D01*
G01D02*
X-1892988D01*
G01X-1917304Y-115162D02*
Y-107162D01*
G01X-1892988Y-84822D02*
X-1909524D01*
G01X-1912304Y-61962D02*
Y-53962D01*
G01X-1917104D02*
Y-61962D01*
G01D02*
X-1912304D01*
G01Y-53962D02*
X-1917104D01*
G01X-1908224Y-38262D02*
Y-35662D01*
G01D02*
X-1913184D01*
G01D02*
Y-38262D01*
G01D02*
X-1908224D01*
G01X-1917304Y-13962D02*
X-1922104D01*
G01D02*
Y-21962D01*
G01D02*
X-1917304D01*
G01X-1907704Y-23362D02*
X-1899704D01*
G01X-1907704Y-18562D02*
Y-23362D01*
G01X-1917304Y-21962D02*
Y-13962D01*
G01X-1899704Y-18562D02*
X-1907704D01*
G01X-1917304Y5038D02*
X-1922104D01*
G01D02*
Y-2962D01*
G01D02*
X-1917304D01*
G01D02*
Y5038D01*
G01X-1909524Y29352D02*
Y10456D01*
G01D02*
X-1892988D01*
G01Y29352D02*
X-1909524D01*
G01X-1912304Y59038D02*
Y67038D01*
G01D02*
X-1917104D01*
G01D02*
Y59038D01*
G01D02*
X-1912304D01*
G01X-1911984Y83538D02*
Y80938D01*
G01D02*
X-1907024D01*
G01Y83538D02*
X-1911984D01*
G01X-1920200Y103838D02*
Y95838D01*
G01D02*
X-1915400D01*
G01D02*
Y103838D01*
G01D02*
X-1920200D01*
G01X-1905400D02*
X-1910200D01*
G01D02*
Y95838D01*
G01D02*
X-1905400D01*
G01X-1922704Y122438D02*
Y114438D01*
G01D02*
X-1917904D01*
G01Y122438D02*
X-1922704D01*
G01X-1917904Y114438D02*
Y122438D01*
G01X-1909524Y143526D02*
Y124630D01*
G01D02*
X-1892988D01*
G01Y143526D02*
X-1909524D01*
G01X-1912704Y163038D02*
Y171038D01*
G01X-1917504D02*
Y163038D01*
G01D02*
X-1912704D01*
G01Y171038D02*
X-1917504D01*
G01X-1923904Y182054D02*
Y190054D01*
G01X-1911784Y186338D02*
Y183738D01*
G01D02*
X-1906824D01*
G01Y186338D02*
X-1911784D01*
G01X-1922304Y287038D02*
Y295038D01*
G01X-1909516Y347858D02*
Y316678D01*
G01X-1900468Y-315528D02*
G03X-1892594Y-307654I0J7874D01*
G01D02*
Y-258442D01*
G01X-1884720Y-250568D02*
G03X-1892594Y-258442I0J-7874D01*
G01X-1892988Y-217890D02*
Y-198994D01*
G01X-1890718Y-193132D02*
G03I-3000J0D01*
G01X-1894592Y-196002D02*
X-1892844D01*
G01X-1896498Y-192002D02*
X-1890938D01*
G01X-1906104Y-165962D02*
Y-173962D01*
G01D02*
X-1901304D01*
G01D02*
Y-165962D01*
G01X-1897104D02*
Y-173962D01*
G01D02*
X-1892304D01*
G01D02*
Y-165962D01*
G01X-1901304D02*
X-1906104D01*
G01X-1892304D02*
X-1897104D01*
G01X-1905424Y-152262D02*
Y-149662D01*
G01X-1907304Y-133982D02*
Y-125982D01*
G01X-1892988Y-103718D02*
Y-84822D01*
G01X-1891718Y-78960D02*
G03I-3000J0D01*
G01X-1897532Y-80002D02*
X-1891904D01*
G01X-1895218Y-76002D02*
X-1894218D01*
G01X-1907104Y-53962D02*
Y-61962D01*
G01D02*
X-1902304D01*
G01D02*
Y-53962D01*
G01X-1897104D02*
Y-61962D01*
G01D02*
X-1892304D01*
G01D02*
Y-53962D01*
G01X-1902304D02*
X-1907104D01*
G01X-1892304D02*
X-1897104D01*
G01X-1899704Y-23362D02*
Y-18562D01*
G01X-1891904Y-13272D02*
Y-21272D01*
G01D02*
X-1887104D01*
G01Y-13272D02*
X-1891904D01*
G01X-1892988Y10456D02*
Y29352D01*
G01X-1887704Y35038D02*
G03I-3000J0D01*
G01X-1893546Y35998D02*
X-1887862D01*
G01X-1907104Y67038D02*
Y59038D01*
G01D02*
X-1902304D01*
G01D02*
Y67038D01*
G01D02*
X-1907104D01*
G01X-1898104D02*
Y59038D01*
G01D02*
X-1893304D01*
G01D02*
Y67038D01*
G01D02*
X-1898104D01*
G01X-1907024Y80938D02*
Y83538D01*
G01X-1905400Y95838D02*
Y103838D01*
G01X-1892988Y124630D02*
Y143526D01*
G01X-1887704Y150038D02*
G03I-3000J0D01*
G01X-1892904Y147998D02*
X-1888504D01*
G01X-1892976Y151998D02*
X-1888432D01*
G01X-1897504Y171038D02*
Y163038D01*
G01D02*
X-1892704D01*
G01D02*
Y171038D01*
G01X-1907104Y174038D02*
Y166038D01*
G01D02*
X-1902304D01*
G01D02*
Y174038D01*
G01D02*
X-1907104D01*
G01X-1892704Y171038D02*
X-1897504D01*
G01X-1906824Y183738D02*
Y186338D01*
G01X-1892704Y304638D02*
X-1884704D01*
G01Y309438D02*
X-1892704D01*
G01D02*
Y304638D01*
G01X-1894104Y368038D02*
Y360038D01*
G01D02*
X-1889304D01*
G01Y368038D02*
X-1894104D01*
G01X-1900104Y417038D02*
Y429838D01*
G01X-1892904D02*
Y417038D01*
G01D02*
X-1900104D01*
G01Y429838D02*
X-1892904D01*
G01X-1884720Y-250568D02*
X-1755980D01*
G01X-1888104Y-125962D02*
Y-133962D01*
G01D02*
X-1883304D01*
G01D02*
Y-125962D01*
G01D02*
X-1888104D01*
G01X-1878090Y-26750D02*
Y-65174D01*
G01D02*
X-1841318D01*
G01X-1887104Y-21272D02*
Y-13272D01*
G01X-1841318Y-26750D02*
X-1878090D01*
G01X-1885104Y103038D02*
Y95038D01*
G01D02*
X-1880304D01*
G01D02*
Y103038D01*
G01D02*
X-1885104D01*
G01X-1874008Y174238D02*
X-1882008D01*
G01D02*
Y169438D01*
G01D02*
X-1874008D01*
G01D02*
Y174238D01*
G01X-1882008Y179438D02*
X-1874008D01*
G01D02*
Y184238D01*
G01X-1882008D02*
Y179438D01*
G01X-1874008Y184238D02*
X-1882008D01*
G01X-1874008Y193238D02*
X-1882008D01*
G01D02*
Y188438D01*
G01D02*
X-1874008D01*
G01D02*
Y193238D01*
G01X-1878704Y209438D02*
X-1886704D01*
G01D02*
Y204638D01*
G01D02*
X-1878704D01*
G01D02*
Y209438D01*
G01X-1884704Y304638D02*
Y309438D01*
G01X-1876546Y334314D02*
Y343762D01*
G01X-1856862Y334314D02*
X-1876546D01*
G01X-1876152Y333526D02*
X-1872216D01*
G01X-1876152Y327226D02*
Y333526D01*
G01X-1872216Y327226D02*
X-1876152D01*
G01X-1876546Y334314D02*
X-1878122Y332738D01*
G01X-1876152D02*
X-1878122D01*
G01D02*
Y345338D01*
G01X-1873002Y336282D02*
G03I-1182J0D01*
G01X-1875332Y335998D02*
X-1873036D01*
G01X-1876546Y343762D02*
X-1856862D01*
G01X-1876152Y350850D02*
X-1872216D01*
G01X-1876152Y344550D02*
Y350850D01*
G01X-1872216Y344550D02*
X-1876152D01*
G01X-1876546Y343762D02*
X-1878122Y345338D01*
G01D02*
X-1876152D01*
G01X-1889304Y360038D02*
Y368038D01*
G01X-1875604Y395738D02*
Y389738D01*
G01D02*
X-1868604D01*
G01X-1875604Y412738D02*
Y404738D01*
G01D02*
X-1876604D01*
G01D02*
Y395738D01*
G01D02*
X-1875604D01*
G01X-1827604Y412738D02*
X-1880604D01*
G01D02*
Y461738D01*
G01X-1875604Y465738D02*
Y434738D01*
G01D02*
X-1832604D01*
G01X-1880604Y461738D02*
X-1827604D01*
G01X-1869604Y471738D02*
X-1875604Y465738D01*
G01X-1843504Y-203062D02*
X-1867904D01*
G01D02*
Y-167662D01*
G01D02*
X-1843504D01*
G01X-1853410Y1438D02*
X-1861410D01*
G01D02*
Y-3362D01*
G01D02*
X-1853410D01*
G01X-1861410Y10438D02*
Y5638D01*
G01D02*
X-1853410D01*
G01Y10438D02*
X-1861410D01*
G01X-1853410Y19438D02*
X-1861410D01*
G01D02*
Y14638D01*
G01D02*
X-1853410D01*
G01X-1861410Y28438D02*
Y23638D01*
G01D02*
X-1853410D01*
G01Y28438D02*
X-1861410D01*
G01X-1853410Y37438D02*
X-1861410D01*
G01D02*
Y32638D01*
G01D02*
X-1853410D01*
G01Y46438D02*
X-1861410D01*
G01D02*
Y41638D01*
G01D02*
X-1853410D01*
G01X-1838684Y56018D02*
X-1861124D01*
G01D02*
Y78458D01*
G01D02*
X-1852856D01*
G01X-1858504Y104438D02*
Y128438D01*
G01X-1834504Y104438D02*
X-1858504D01*
G01X-1870304Y107638D02*
Y99638D01*
G01D02*
X-1865504D01*
G01D02*
Y107638D01*
G01D02*
X-1870304D01*
G01X-1850904Y108638D02*
G03I-3000J0D01*
G01X-1856834Y107998D02*
X-1850974D01*
G01X-1858504Y128438D02*
X-1834504D01*
G01X-1865304Y129638D02*
Y137638D01*
G01D02*
X-1870104D01*
G01D02*
Y129638D01*
G01D02*
X-1865304D01*
G01X-1859208Y162238D02*
Y154238D01*
G01D02*
X-1854408D01*
G01Y162238D02*
X-1859208D01*
G01X-1844540Y172970D02*
X-1861076D01*
G01D02*
Y189506D01*
G01D02*
X-1844540D01*
G01X-1859704Y209438D02*
X-1867704D01*
G01D02*
Y204638D01*
G01D02*
X-1859704D01*
G01D02*
Y209438D01*
G01X-1869704Y291438D02*
Y286638D01*
G01D02*
X-1861704D01*
G01D02*
Y291438D01*
G01D02*
X-1869704D01*
G01X-1861704Y300438D02*
X-1869704D01*
G01D02*
Y295638D01*
G01D02*
X-1861704D01*
G01D02*
Y300438D01*
G01X-1856862Y343762D02*
Y334314D01*
G01X-1857256Y333526D02*
Y327226D01*
G01X-1861192Y333526D02*
X-1857256D01*
G01X-1861192Y327226D02*
Y333526D01*
G01X-1857256Y327226D02*
X-1861192D01*
G01X-1872216Y333526D02*
Y327226D01*
G01X-1864736Y333526D02*
Y327226D01*
G01X-1868672Y333526D02*
X-1864736D01*
G01X-1868672Y327226D02*
Y333526D01*
G01X-1864736Y327226D02*
X-1868672D01*
G01X-1855286Y332738D02*
X-1856862Y334314D01*
G01X-1857256Y332738D02*
X-1855286D01*
G01X-1864736D02*
X-1861192D01*
G01X-1872216D02*
X-1868672D01*
G01X-1864736Y350850D02*
Y344550D01*
G01X-1868672Y350850D02*
X-1864736D01*
G01X-1868672Y344550D02*
Y350850D01*
G01X-1864736Y344550D02*
X-1868672D01*
G01X-1872216Y350850D02*
Y344550D01*
G01X-1857256Y350850D02*
Y344550D01*
G01X-1861192Y350850D02*
X-1857256D01*
G01X-1861192Y344550D02*
Y350850D01*
G01X-1857256Y344550D02*
X-1861192D01*
G01X-1855286Y345338D02*
X-1856862Y343762D01*
G01X-1855286Y345338D02*
X-1857256D01*
G01X-1872216D02*
X-1868672D01*
G01D02*
Y344550D01*
G01D02*
X-1864736D01*
G01D02*
Y345338D01*
G01D02*
X-1861192D01*
G01X-1868604Y389738D02*
Y395738D01*
G01D02*
X-1867604D01*
G01D02*
Y404738D01*
G01D02*
X-1868604D01*
G01D02*
Y412738D01*
G01X-1857604D02*
Y404738D01*
G01D02*
X-1850604D01*
G01X-1838604Y471738D02*
X-1869604D01*
G01X-1851376Y-705500D02*
X-1835751Y-755500D01*
X-1820124Y-705500D01*
G01X-1793250D02*
X-1778251D01*
G01X-1785751D02*
Y-755500D01*
G01X-1793250D02*
X-1778251D01*
G01X-1723250D02*
X-1748250D01*
Y-705500D01*
X-1723250D01*
G01X-1733250Y-729666D02*
X-1748250D01*
G01X-1704500Y-705500D02*
X-1695751Y-755500D01*
X-1685751Y-705500D01*
X-1675750Y-755500D01*
X-1667000Y-705500D01*
G01X-1623250Y-755500D02*
X-1648250D01*
Y-705500D01*
X-1623250D01*
G01X-1633250Y-729666D02*
X-1648250D01*
G01X-1599500Y-755500D02*
Y-705500D01*
X-1587000D01*
X-1582000Y-708001D01*
X-1578250Y-711334D01*
X-1575124Y-716333D01*
X-1572625Y-722168D01*
X-1572000Y-730501D01*
X-1572625Y-738834D01*
X-1575124Y-744667D01*
X-1578250Y-749668D01*
X-1582000Y-753001D01*
X-1587000Y-755500D01*
X-1599500D01*
G01X-1497625D02*
Y-705500D01*
X-1473875D01*
G01X-1482625Y-729666D02*
X-1497625D01*
G01X-1448250Y-755500D02*
Y-705500D01*
X-1432625D01*
X-1427625Y-708001D01*
X-1424500Y-711334D01*
X-1423250Y-718000D01*
X-1424500Y-724667D01*
X-1428250Y-728833D01*
X-1432625Y-731334D01*
X-1448250D01*
G01X-1432625D02*
X-1423250Y-755500D01*
G01X-1385751D02*
X-1390751Y-754667D01*
X-1395125Y-751334D01*
X-1398875Y-746334D01*
X-1401376Y-740500D01*
X-1402625Y-733833D01*
Y-727167D01*
X-1401376Y-720500D01*
X-1398875Y-714666D01*
X-1395125Y-709667D01*
X-1390751Y-706333D01*
X-1385751Y-705500D01*
X-1380750Y-706333D01*
X-1376375Y-709667D01*
X-1372625Y-714666D01*
X-1370124Y-720500D01*
X-1368875Y-727167D01*
Y-733833D01*
X-1370124Y-740500D01*
X-1372625Y-746334D01*
X-1376375Y-751334D01*
X-1380750Y-754667D01*
X-1385751Y-755500D01*
G01X-1352001D02*
Y-705500D01*
X-1335751Y-747167D01*
X-1319499Y-705500D01*
Y-755500D01*
G01X-1235751Y-705500D02*
Y-755500D01*
G01X-1250125Y-705500D02*
X-1221375D01*
G01X-1185751Y-755500D02*
X-1190751Y-754667D01*
X-1195125Y-751334D01*
X-1198875Y-746334D01*
X-1201376Y-740500D01*
X-1202625Y-733833D01*
Y-727167D01*
X-1201376Y-720500D01*
X-1198875Y-714666D01*
X-1195125Y-709667D01*
X-1190751Y-706333D01*
X-1185751Y-705500D01*
X-1180750Y-706333D01*
X-1176375Y-709667D01*
X-1172625Y-714666D01*
X-1170124Y-720500D01*
X-1168875Y-727167D01*
Y-733833D01*
X-1170124Y-740500D01*
X-1172625Y-746334D01*
X-1176375Y-751334D01*
X-1180750Y-754667D01*
X-1185751Y-755500D01*
G01X-1148250D02*
Y-705500D01*
X-1133250D01*
X-1128250Y-708001D01*
X-1124500Y-713833D01*
X-1123250Y-720500D01*
X-1124500Y-727167D01*
X-1127625Y-732167D01*
X-1133250Y-734668D01*
X-1148250D01*
G01X-1048875Y-748835D02*
X-1043875Y-753001D01*
X-1038250Y-755500D01*
X-1033250D01*
X-1028250Y-753001D01*
X-1024500Y-748835D01*
X-1022625Y-743000D01*
X-1023875Y-737168D01*
X-1027000Y-732167D01*
X-1032625Y-728833D01*
X-1040125Y-727167D01*
X-1044500Y-723834D01*
X-1046376Y-718000D01*
X-1045125Y-712167D01*
X-1042000Y-708001D01*
X-1037625Y-705500D01*
X-1033250D01*
X-1028875Y-707166D01*
X-1025124Y-711334D01*
G01X-993250Y-705500D02*
X-978251D01*
G01X-985751D02*
Y-755500D01*
G01X-993250D02*
X-978251D01*
G01X-949500D02*
Y-705500D01*
X-937000D01*
X-932000Y-708001D01*
X-928250Y-711334D01*
X-925124Y-716333D01*
X-922625Y-722168D01*
X-922000Y-730501D01*
X-922625Y-738834D01*
X-925124Y-744667D01*
X-928250Y-749668D01*
X-932000Y-753001D01*
X-937000Y-755500D01*
X-949500D01*
G01X-873250D02*
X-898250D01*
Y-705500D01*
X-873250D01*
G01X-883250Y-729666D02*
X-898250D01*
G01X-1843504Y-167662D02*
Y-203062D01*
G01X-1844704Y-171362D02*
G03I-3000J0D01*
G01X-1850634Y-172002D02*
X-1844774D01*
G01X-1846704Y-138562D02*
X-1854704D01*
G01D02*
Y-143362D01*
G01D02*
X-1846704D01*
G01X-1854704Y-128562D02*
Y-133362D01*
G01D02*
X-1846704D01*
G01Y-143362D02*
Y-138562D01*
G01Y-133362D02*
Y-128562D01*
G01D02*
X-1854704D01*
G01X-1846704Y-118562D02*
X-1854704D01*
G01D02*
Y-123362D01*
G01D02*
X-1846704D01*
G01D02*
Y-118562D01*
G01Y-98562D02*
X-1854704D01*
G01D02*
Y-103362D01*
G01D02*
X-1846704D01*
G01Y-108562D02*
X-1854704D01*
G01D02*
Y-113362D01*
G01D02*
X-1846704D01*
G01Y-103362D02*
Y-98562D01*
G01Y-113362D02*
Y-108562D01*
G01X-1854704Y-88562D02*
Y-93362D01*
G01D02*
X-1846704D01*
G01Y-88562D02*
X-1854704D01*
G01X-1846704Y-93362D02*
Y-88562D01*
G01X-1841318Y-65174D02*
Y-26750D01*
G01X-1853410Y-3362D02*
Y1438D01*
G01Y5638D02*
Y10438D01*
G01Y14638D02*
Y19438D01*
G01Y23638D02*
Y28438D01*
G01Y32638D02*
Y37438D01*
G01Y41638D02*
Y46438D01*
G01X-1838684Y78458D02*
Y56018D01*
G01X-1852856Y78458D02*
Y80426D01*
G01D02*
X-1846952D01*
G01D02*
Y78458D01*
G01D02*
X-1838684D01*
G01X-1854408Y154238D02*
Y162238D01*
G01X-1846104Y162038D02*
Y154038D01*
G01D02*
X-1841304D01*
G01D02*
Y162038D01*
G01D02*
X-1846104D01*
G01X-1844540Y189506D02*
Y172970D01*
G01X-1843354Y198040D02*
G03I-3998J0D01*
G01X-1850790Y195998D02*
X-1843914D01*
G01X-1847008Y215038D02*
X-1851808D01*
G01D02*
Y207038D01*
G01D02*
X-1847008D01*
G01X-1850838Y199998D02*
X-1843866D01*
G01X-1847008Y207038D02*
Y215038D01*
G01X-1855286Y332738D02*
Y345338D01*
G01X-1839604Y395738D02*
Y389738D01*
G01D02*
X-1832604D01*
G01X-1839604Y412738D02*
Y404738D01*
G01D02*
X-1840604D01*
G01D02*
Y395738D01*
G01D02*
X-1839604D01*
G01X-1850604Y404738D02*
Y412738D01*
G01X-1832604Y465738D02*
X-1838604Y471738D01*
G01X-1834504Y128438D02*
Y104438D01*
G01X-1829104Y167534D02*
Y162734D01*
G01D02*
X-1821104D01*
G01D02*
Y167534D01*
G01X-1819208Y171838D02*
X-1832008D01*
G01D02*
Y179038D01*
G01D02*
X-1819208D01*
G01X-1821104Y167534D02*
X-1829104D01*
G01X-1828808Y183238D02*
X-1820808D01*
G01D02*
Y188038D01*
G01X-1828808D02*
Y183238D01*
G01X-1820808Y188038D02*
X-1828808D01*
G01X-1828704Y192238D02*
X-1820704D01*
G01D02*
Y197038D01*
G01D02*
X-1828704D01*
G01D02*
Y192238D01*
G01X-1825504Y358238D02*
Y279438D01*
G01D02*
X-1746704D01*
G01Y358238D02*
X-1825504D01*
G01X-1832604Y389738D02*
Y395738D01*
G01D02*
X-1831604D01*
G01D02*
Y404738D01*
G01D02*
X-1832604D01*
G01D02*
Y412738D01*
G01X-1827604Y461738D02*
Y412738D01*
G01X-1832604Y434738D02*
Y465738D01*
G01X-1813416Y-222210D02*
X-1819716D01*
G01D02*
Y-218274D01*
G01X-1813416D02*
Y-222210D01*
G01X-1803180Y-222604D02*
X-1812628D01*
G01X-1803180Y-202920D02*
Y-222604D01*
G01X-1812628D02*
Y-202920D01*
G01X-1801604Y-224180D02*
X-1803180Y-222604D01*
G01X-1814204Y-224180D02*
X-1812628Y-222604D01*
G01X-1814204Y-222210D02*
Y-224180D01*
G01D02*
X-1801604D01*
G01X-1819716Y-218274D02*
X-1813416D01*
G01Y-207250D02*
X-1819716D01*
G01Y-203314D02*
X-1813416D01*
G01X-1819716Y-207250D02*
Y-203314D01*
G01X-1813416Y-214730D02*
X-1819716D01*
G01Y-210794D02*
X-1813416D01*
G01X-1819716Y-214730D02*
Y-210794D01*
G01X-1813416Y-203314D02*
Y-207250D01*
G01Y-210794D02*
Y-214730D01*
G01X-1812628Y-202920D02*
X-1803180D01*
G01X-1812628D02*
X-1814204Y-201344D01*
G01X-1803180Y-202920D02*
X-1801604Y-201344D01*
G01X-1814204Y-214730D02*
Y-218274D01*
G01Y-207250D02*
Y-210794D01*
G01Y-203314D02*
Y-201344D01*
G01X-1809480Y-205282D02*
G03I-1180J0D01*
G01X-1814204Y-201344D02*
X-1801604D01*
G01X-1819208Y179038D02*
Y171838D01*
G01X-1803304Y237038D02*
Y245038D01*
G01D02*
X-1808104D01*
G01D02*
Y237038D01*
G01D02*
X-1803304D01*
G01X-1796092Y-222210D02*
X-1802392D01*
G01X-1796092Y-218274D02*
Y-222210D01*
G01X-1802392D02*
Y-218274D01*
G01X-1801604Y-224180D02*
Y-222210D01*
G01X-1796092Y-207250D02*
X-1802392D01*
G01X-1796092Y-203314D02*
Y-207250D01*
G01X-1802392Y-203314D02*
X-1796092D01*
G01X-1802392Y-207250D02*
Y-203314D01*
G01Y-218274D02*
X-1796092D01*
G01X-1801604Y-207250D02*
Y-218274D01*
G01Y-201344D02*
Y-203314D01*
G01X-1788104Y245038D02*
Y237038D01*
G01D02*
X-1783304D01*
G01Y245038D02*
X-1788104D01*
G01X-1798104D02*
Y237038D01*
G01D02*
X-1793304D01*
G01D02*
Y245038D01*
G01D02*
X-1798104D01*
G01X-1802104Y395038D02*
Y387038D01*
G01D02*
X-1797304D01*
G01D02*
Y395038D01*
G01X-1792104D02*
Y387038D01*
G01D02*
X-1787304D01*
G01D02*
Y395038D01*
G01X-1797304D02*
X-1802104D01*
G01X-1787304D02*
X-1792104D01*
G01X-1775764Y-216842D02*
Y-221642D01*
G01D02*
X-1767764D01*
G01X-1775764Y-230642D02*
X-1767764D01*
G01Y-225842D02*
X-1775764D01*
G01D02*
Y-230642D01*
G01X-1767764Y-206842D02*
X-1775764D01*
G01D02*
Y-211642D01*
G01D02*
X-1767764D01*
G01X-1775764Y-197842D02*
Y-202642D01*
G01D02*
X-1767764D01*
G01Y-216842D02*
X-1775764D01*
G01X-1767764Y-197842D02*
X-1775764D01*
G01X-1783304Y237038D02*
Y245038D01*
G01X-1778104D02*
Y237038D01*
G01D02*
X-1773304D01*
G01D02*
Y245038D01*
G01D02*
X-1778104D01*
G01X-1782104Y395038D02*
Y387038D01*
G01D02*
X-1777304D01*
G01D02*
Y395038D01*
G01D02*
X-1782104D01*
G01X-1746712Y415802D02*
X-1772696D01*
G01D02*
Y436274D01*
G01D02*
X-1746712D01*
G01X-1748106Y-258442D02*
G03X-1755980Y-250568I-7874J0D01*
G01X-1767764Y-221642D02*
Y-216842D01*
G01Y-230642D02*
Y-225842D01*
G01Y-211642D02*
Y-206842D01*
G01Y-202642D02*
Y-197842D01*
G01X-1749370Y-142876D02*
G03I-9200J0D01*
G01Y17124D02*
G03I-9200J0D01*
G01Y177124D02*
G03I-9200J0D01*
G01X-1750064Y379178D02*
G03I-4000J0D01*
G01X-1756490Y375998D02*
X-1751638D01*
G01X-1757980Y379998D02*
X-1750148D01*
G01X-1756704Y401438D02*
X-1764704D01*
G01D02*
Y396638D01*
G01D02*
X-1756704D01*
G01D02*
Y401438D01*
G01X-1752224Y405738D02*
Y408338D01*
G01X-1757184D02*
Y405738D01*
G01D02*
X-1752224D01*
G01X-1768184Y408338D02*
Y405738D01*
G01D02*
X-1763224D01*
G01D02*
Y408338D01*
G01X-1752224D02*
X-1757184D01*
G01X-1763224D02*
X-1768184D01*
G01X-1745536Y442038D02*
G03I-3000J0D01*
G01X-1750808Y443998D02*
X-1746264D01*
G01X-1748106Y-258442D02*
Y-307654D01*
G01D02*
G03X-1740232Y-315528I7874J0D01*
G01D02*
X-1692988D01*
G01X-1740804Y-225962D02*
X-1748804D01*
G01D02*
Y-230762D01*
G01D02*
X-1740804D01*
G01X-1748804Y-216962D02*
Y-221762D01*
G01D02*
X-1740804D01*
G01Y-230762D02*
Y-225962D01*
G01Y-221762D02*
Y-216962D01*
G01X-1748764Y-197962D02*
Y-202762D01*
G01D02*
X-1740764D01*
G01Y-206962D02*
X-1748764D01*
G01D02*
Y-211762D01*
G01D02*
X-1740764D01*
G01X-1740804Y-216962D02*
X-1748804D01*
G01X-1740764Y-202762D02*
Y-197962D01*
G01Y-211762D02*
Y-206962D01*
G01Y-197962D02*
X-1748764D01*
G01X-1699570Y-138876D02*
G03I-24000J0D01*
G01X-1694570Y185124D02*
G03I-24000J0D01*
G01X-1746704Y279438D02*
Y358238D01*
G01X-1746712Y436274D02*
Y415802D01*
G01X-1750736Y439998D02*
X-1746336D01*
G01X-1736104Y474038D02*
Y466038D01*
G01D02*
X-1731304D01*
G01Y474038D02*
X-1736104D01*
G01X-1723704Y265038D02*
Y249038D01*
G01D02*
X-1713704D01*
G01Y265038D02*
X-1723704D01*
G01X-1716104Y288438D02*
Y275638D01*
G01D02*
X-1723304D01*
G01D02*
Y288438D01*
G01D02*
X-1716104D01*
G01X-1724104Y398038D02*
Y390038D01*
G01D02*
X-1719304D01*
G01D02*
Y398038D01*
G01D02*
X-1724104D01*
G01X-1717504Y421638D02*
X-1725504D01*
G01D02*
Y416838D01*
G01D02*
X-1717504D01*
G01D02*
Y421638D01*
G01X-1720984Y430538D02*
Y427938D01*
G01D02*
X-1716024D01*
G01D02*
Y430538D01*
G01D02*
X-1720984D01*
G01X-1715504Y440638D02*
X-1723504D01*
G01D02*
Y435838D01*
G01D02*
X-1715504D01*
G01X-1716024Y453938D02*
Y456538D01*
G01D02*
X-1720984D01*
G01D02*
Y453938D01*
G01D02*
X-1716024D01*
G01X-1715504Y449638D02*
X-1723504D01*
G01D02*
Y444838D01*
G01D02*
X-1715504D01*
G01X-1721984Y467538D02*
Y464938D01*
G01D02*
X-1717024D01*
G01D02*
Y467538D01*
G01X-1723504Y475038D02*
X-1715504D01*
G01X-1723504Y479838D02*
Y475038D01*
G01X-1731304Y466038D02*
Y474038D01*
G01X-1717024Y467538D02*
X-1721984D01*
G01X-1715504Y479838D02*
X-1723504D01*
G01X-1698704Y-226522D02*
Y-218522D01*
G01X-1703504D02*
Y-226522D01*
G01D02*
X-1698704D01*
G01Y-218522D02*
X-1703504D01*
G01X-1705704Y241438D02*
X-1713704D01*
G01D02*
Y236638D01*
G01D02*
X-1705704D01*
G01X-1713704Y249038D02*
Y265038D01*
G01X-1707104Y258038D02*
Y250038D01*
G01D02*
X-1702304D01*
G01D02*
Y258038D01*
G01X-1705704Y236638D02*
Y241438D01*
G01X-1702304Y258038D02*
X-1707104D01*
G01X-1694810Y260094D02*
G03I-3000J0D01*
G01X-1700808Y259998D02*
X-1694812D01*
G01X-1706304Y282038D02*
Y290038D01*
G01X-1711104D02*
Y282038D01*
G01D02*
X-1706304D01*
G01Y290038D02*
X-1711104D01*
G01X-1692104Y400638D02*
X-1704904D01*
G01D02*
Y407838D01*
G01D02*
X-1692104D01*
G01X-1715504Y435838D02*
Y440638D01*
G01Y444838D02*
Y449638D01*
G01Y475038D02*
Y479838D01*
G01X-1701904Y473238D02*
X-1697104D01*
G01X-1701904Y481238D02*
Y473238D01*
G01X-1697104Y481238D02*
X-1701904D01*
G01X-1692988Y-315528D02*
G03X-1685114Y-307654I0J7874D01*
G01D02*
Y-264938D01*
G01X-1656374D02*
G03X-1685114I-14370J0D01*
G01X-1662696Y240030D02*
X-1686712D01*
G01D02*
Y264046D01*
G01D02*
X-1662696D01*
G01X-1675618Y277724D02*
X-1689790D01*
G01D02*
Y288352D01*
G01D02*
X-1675618D01*
G01Y297724D02*
X-1689790D01*
G01D02*
Y308352D01*
G01D02*
X-1675618D01*
G01X-1692104Y407838D02*
Y400638D01*
G01X-1685324Y417954D02*
G03I-4000J0D01*
G01X-1695678Y428064D02*
Y456412D01*
G01X-1667330Y428064D02*
X-1695678D01*
G01Y456412D02*
X-1667330D01*
G01X-1682504Y484238D02*
Y474238D01*
G01D02*
X-1666504D01*
G01X-1697104Y473238D02*
Y481238D01*
G01X-1666504Y484238D02*
X-1682504D01*
G01X-1671564Y-234562D02*
X-1679764D01*
G01D02*
Y-231362D01*
G01X-1671564Y-224562D02*
X-1679764D01*
G01D02*
Y-221362D01*
G01D02*
X-1671564D01*
G01X-1679764Y-231362D02*
X-1671564D01*
G01X-1640764Y-237262D02*
X-1671564D01*
G01D02*
Y-198662D01*
G01Y-204562D02*
X-1679764D01*
G01D02*
Y-201362D01*
G01X-1671564Y-214562D02*
X-1679764D01*
G01D02*
Y-211362D01*
G01D02*
X-1671564D01*
G01X-1679764Y-201362D02*
X-1671564D01*
G01Y-198662D02*
X-1640764D01*
G01X-1663224Y230338D02*
X-1668184D01*
G01D02*
Y227738D01*
G01D02*
X-1663224D01*
G01X-1675618Y277724D02*
Y288352D01*
X-1679618D01*
Y277724D01*
X-1675618D01*
G01X-1679618Y279998D02*
X-1675618D01*
G01X-1679618Y283998D02*
X-1675618D01*
G01Y288352D02*
Y277724D01*
G01X-1679618Y287998D02*
X-1675618D01*
G01Y297724D02*
Y308352D01*
X-1679618D01*
Y297724D01*
X-1675618D01*
G01X-1679618Y299998D02*
X-1675618D01*
G01Y308352D02*
Y297724D01*
G01X-1679618Y303998D02*
X-1675618D01*
G01X-1679618Y307998D02*
X-1675618D01*
G01X-1676504Y409238D02*
Y399238D01*
G01D02*
X-1660504D01*
G01Y409238D02*
X-1676504D01*
G01Y414838D02*
X-1668504D01*
G01D02*
Y419638D01*
G01D02*
X-1676504D01*
G01D02*
Y414838D01*
G01X-1667330Y456412D02*
Y428064D01*
G01X-1680504Y464838D02*
X-1672504D01*
G01X-1680504Y469638D02*
Y464838D01*
G01X-1672504Y469638D02*
X-1680504D01*
G01X-1672504Y464838D02*
Y469638D01*
G01X-1666504Y474238D02*
Y484238D01*
G01X-1656374Y-264938D02*
Y-347024D01*
X-1652436Y-350962D01*
X-1572122D01*
X-1568184Y-347024D01*
Y-292300D01*
G01X-1572204Y-351000D02*
X-1652304D01*
G01D02*
X-1656304Y-347000D01*
G01D02*
Y-278400D01*
G01X-1646050Y-232916D02*
G03I-3000J0D01*
G01X-1651908Y-232002D02*
X-1646192D01*
G01X-1663224Y227738D02*
Y230338D01*
G01X-1662696Y264046D02*
Y240030D01*
G01X-1647704Y275038D02*
Y265038D01*
G01D02*
X-1631704D01*
G01X-1655104Y287438D02*
Y274638D01*
G01D02*
X-1662304D01*
G01D02*
Y287438D01*
G01X-1631704Y275038D02*
X-1647704D01*
G01X-1646704Y284638D02*
X-1638704D01*
G01X-1646704Y289438D02*
Y284638D01*
G01X-1662304Y287438D02*
X-1655104D01*
G01X-1638704Y289438D02*
X-1646704D01*
G01X-1655704Y306038D02*
Y296038D01*
G01D02*
X-1639704D01*
G01Y306038D02*
X-1655704D01*
G01X-1660504Y399238D02*
Y409238D01*
G01X-1588582Y416286D02*
X-1648426D01*
G01D02*
Y472190D01*
G01D02*
X-1588582D01*
G01X-1640764Y-234562D02*
X-1632564D01*
G01D02*
Y-231362D01*
G01X-1640764Y-198662D02*
Y-237262D01*
G01X-1632564Y-231362D02*
X-1640764D01*
G01Y-224562D02*
X-1632564D01*
G01D02*
Y-221362D01*
G01D02*
X-1640764D01*
G01Y-214562D02*
X-1632564D01*
G01D02*
Y-211362D01*
G01D02*
X-1640764D01*
G01Y-204562D02*
X-1632564D01*
G01D02*
Y-201362D01*
G01D02*
X-1640764D01*
G01X-1646104Y245038D02*
Y237038D01*
G01D02*
X-1641304D01*
G01Y245038D02*
X-1646104D01*
G01X-1641304Y237038D02*
Y245038D01*
G01X-1631304Y237038D02*
Y245038D01*
G01D02*
X-1636104D01*
G01D02*
Y237038D01*
G01D02*
X-1631304D01*
G01X-1645704Y254638D02*
X-1637704D01*
G01X-1645704Y259438D02*
Y254638D01*
G01X-1637704Y259438D02*
X-1645704D01*
G01X-1637704Y254638D02*
Y259438D01*
G01X-1631704Y265038D02*
Y275038D01*
G01X-1638704Y284638D02*
Y289438D01*
G01X-1639704Y296038D02*
Y306038D01*
G01X-1613564Y-224762D02*
Y-232762D01*
G01D02*
X-1608764D01*
G01Y-224762D02*
X-1613564D01*
G01X-1621304Y306638D02*
Y298638D01*
G01D02*
X-1616504D01*
G01D02*
Y306638D01*
G01D02*
X-1621304D01*
G01X-1608764Y-232762D02*
Y-224762D01*
G01X-1603564D02*
Y-232762D01*
G01D02*
X-1598764D01*
G01D02*
Y-224762D01*
G01D02*
X-1603564D01*
G01X-1591704Y243438D02*
X-1596504D01*
G01D02*
Y235438D01*
G01D02*
X-1591704D01*
G01X-1571704Y272038D02*
X-1595704D01*
G01D02*
Y296038D01*
G01D02*
X-1571704D01*
G01X-1578304Y-231962D02*
Y-223962D01*
G01D02*
X-1583104D01*
G01D02*
Y-231962D01*
G01D02*
X-1578304D01*
G01X-1587304D02*
Y-223962D01*
G01D02*
X-1592104D01*
G01D02*
Y-231962D01*
G01D02*
X-1587304D01*
G01X-1591704Y235438D02*
Y243438D01*
G01X-1582704Y235438D02*
Y243438D01*
G01D02*
X-1587504D01*
G01D02*
Y235438D01*
G01D02*
X-1582704D01*
G01X-1573704Y243438D02*
X-1578504D01*
G01D02*
Y235438D01*
G01D02*
X-1573704D01*
G01X-1573304Y291838D02*
G03I-3000J0D01*
G01X-1579300Y291998D02*
X-1573308D01*
G01X-1588582Y472190D02*
Y416286D01*
G01X-1577904Y426238D02*
Y418238D01*
G01D02*
X-1573104D01*
G01Y426238D02*
X-1577904D01*
G01X-1578504Y455238D02*
X-1568504D01*
G01X-1578504Y471238D02*
Y455238D01*
G01X-1568504Y471238D02*
X-1578504D01*
G01X-1568204Y-347000D02*
X-1572204Y-351000D01*
G01X-1568204Y-292300D02*
Y-347000D01*
G01X-1553224Y-292300D02*
G03X-1568184I-7480J0D01*
G01X-1560704Y-284800D02*
G03X-1568204Y-292300I0J-7500D01*
G01X-1553204D02*
G03X-1560704Y-284800I-7500J0D01*
G01X-1573704Y235438D02*
Y243438D01*
G01X-1564704Y235438D02*
Y243438D01*
G01D02*
X-1569504D01*
G01D02*
Y235438D01*
G01D02*
X-1564704D01*
G01X-1571704Y296038D02*
Y272038D01*
G01X-1560544Y306238D02*
Y298238D01*
G01D02*
X-1555744D01*
G01Y306238D02*
X-1560544D01*
G01X-1573104Y418238D02*
Y426238D01*
G01X-1568504Y429238D02*
Y413238D01*
G01D02*
X-1558504D01*
G01Y429238D02*
X-1568504D01*
G01Y455238D02*
Y471238D01*
G01X-1563504Y455238D02*
X-1553504D01*
G01X-1563504Y471238D02*
Y455238D01*
G01X-1553504Y471238D02*
X-1563504D01*
G01X-1553224Y-292300D02*
Y-347024D01*
X-1549286Y-350962D01*
X-1390232D01*
X-1386294Y-347024D01*
Y-258442D01*
G01X-1390304Y-351000D02*
X-1549204D01*
G01D02*
X-1553204Y-347000D01*
G01D02*
Y-292300D01*
G01X-1555744Y298238D02*
Y306238D01*
G01X-1558504Y413238D02*
Y429238D01*
G01X-1553504Y455238D02*
Y471238D01*
G01X-1510860Y-225962D02*
Y-233962D01*
G01D02*
X-1506060D01*
G01Y-225962D02*
X-1510860D01*
G01X-1493570Y-164076D02*
G03I-9200J0D01*
G01X-1476492Y268330D02*
G03I-22400J0D01*
G01Y473054D02*
G03I-22400J0D01*
G01X-1506060Y-233962D02*
Y-225962D01*
G01X-1491504Y-232362D02*
X-1483504D01*
G01X-1491504Y-227562D02*
Y-232362D01*
G01Y-217562D02*
Y-222362D01*
G01D02*
X-1483504D01*
G01Y-227562D02*
X-1491504D01*
G01X-1483504Y-217562D02*
X-1491504D01*
G01X-1449570Y-126676D02*
G03I-24000J0D01*
G01Y160924D02*
G03I-24000J0D01*
G01X-1483504Y-232362D02*
Y-227562D01*
G01Y-222362D02*
Y-217562D01*
G01X-1469570Y-164076D02*
G03I-9200J0D01*
G01X-1456006Y-236064D02*
Y-238422D01*
G01D02*
X-1445002D01*
G01X-1465800Y-224022D02*
G03I-3000J0D01*
G01X-1471800Y-224002D02*
X-1465800D01*
G01X-1456006Y-230946D02*
Y-234096D01*
G01X-1459942Y-236064D02*
X-1456004D01*
Y-234096D01*
X-1459942D01*
Y-236064D01*
G01X-1456006Y-223860D02*
Y-221502D01*
G01D02*
X-1445002D01*
G01X-1456006Y-225828D02*
Y-228978D01*
G01X-1459942Y-230946D02*
X-1456004D01*
Y-228978D01*
X-1459942D01*
Y-230946D01*
G01Y-225828D02*
X-1456004D01*
Y-223860D01*
X-1459942D01*
Y-225828D01*
G01X-1445770Y-164076D02*
G03I-9200J0D01*
G01X-1463032Y-18312D02*
Y48732D01*
G01X-1418936Y-18312D02*
X-1463032D01*
G01Y48732D02*
X-1459210Y52556D01*
G01D02*
X-1418936D01*
G01X-1446960Y-221502D02*
Y-238422D01*
G01X-1454048D02*
Y-221502D01*
G01X-1445002Y-238422D02*
Y-236064D01*
G01Y-225828D02*
Y-234096D01*
G01X-1445004Y-236064D02*
X-1441066D01*
Y-234096D01*
X-1445004D01*
Y-236064D01*
G01X-1445002Y-221502D02*
Y-223860D01*
G01X-1445004Y-225828D02*
X-1441066D01*
Y-223860D01*
X-1445004D01*
Y-225828D01*
G01X-1429370Y-142876D02*
G03I-9200J0D01*
G01Y177124D02*
G03I-9200J0D01*
G01X-1419704Y-238480D02*
X-1411704D01*
G01X-1419704Y-233680D02*
Y-238480D01*
G01X-1411704Y-233680D02*
X-1419704D01*
G01X-1431504Y292638D02*
Y287838D01*
G01D02*
X-1423504D01*
G01D02*
Y292638D01*
G01X-1431504Y298438D02*
X-1423504D01*
G01D02*
Y303238D01*
G01X-1431504D02*
Y298438D01*
G01X-1423504Y292638D02*
X-1431504D01*
G01X-1431304Y313038D02*
X-1423304D01*
G01D02*
Y317838D01*
G01D02*
X-1431304D01*
G01D02*
Y313038D01*
G01X-1423504Y303238D02*
X-1431504D01*
G01X-1372752Y392116D02*
X-1428656D01*
G01D02*
Y451960D01*
G01D02*
X-1372752D01*
G01X-1411704Y-238480D02*
Y-233680D01*
G01X-1419504Y-229162D02*
X-1411504D01*
G01D02*
Y-224362D01*
G01D02*
X-1419504D01*
G01D02*
Y-229162D01*
G01X-1419464Y-219802D02*
X-1411464D01*
G01D02*
Y-215002D01*
G01D02*
X-1419464D01*
G01D02*
Y-219802D01*
G01X-1418936Y52556D02*
Y-18312D01*
G01X-1386304Y-278400D02*
Y-347000D01*
G01D02*
X-1390304Y-351000D01*
G01X-1378420Y-250568D02*
G03X-1386294Y-258442I0J-7874D01*
G01X-1385704Y-19562D02*
Y-24362D01*
G01D02*
X-1377704D01*
G01X-1385704Y-14362D02*
X-1377704D01*
G01X-1385704Y-9562D02*
Y-14362D01*
G01X-1377704Y-19562D02*
X-1385704D01*
G01X-1377904Y1438D02*
X-1385904D01*
G01D02*
Y-3362D01*
G01D02*
X-1377904D01*
G01X-1377704Y-9562D02*
X-1385704D01*
G01X-1377904Y11438D02*
X-1385904D01*
G01D02*
Y6638D01*
G01D02*
X-1377904D01*
G01X-1386704Y16638D02*
X-1378704D01*
G01Y21438D02*
X-1386704D01*
G01D02*
Y16638D01*
G01Y25638D02*
X-1378704D01*
G01Y30438D02*
X-1386704D01*
G01D02*
Y25638D01*
G01X-1361004Y292338D02*
X-1395604D01*
G01D02*
Y331738D01*
G01D02*
X-1361004D01*
G01X-1378420Y-250568D02*
X-698500D01*
G01X-1377704Y-24362D02*
Y-19562D01*
G01Y-14362D02*
Y-9562D01*
G01X-1377904Y-3362D02*
Y1438D01*
G01Y6638D02*
Y11438D01*
G01X-1378704Y16638D02*
Y21438D01*
G01Y25638D02*
Y30438D01*
G01X-1376904Y44438D02*
Y39638D01*
G01D02*
X-1368904D01*
G01D02*
Y44438D01*
G01D02*
X-1376904D01*
G01Y63438D02*
Y58638D01*
G01D02*
X-1368904D01*
G01D02*
Y63438D01*
G01Y54438D02*
X-1376904D01*
G01D02*
Y49638D01*
G01D02*
X-1368904D01*
G01D02*
Y54438D01*
G01Y73438D02*
X-1376904D01*
G01D02*
Y68638D01*
G01D02*
X-1368904D01*
G01D02*
Y73438D01*
G01Y63438D02*
X-1376904D01*
G01X-1378704Y84238D02*
Y79438D01*
G01D02*
X-1370704D01*
G01D02*
Y84238D01*
G01Y93238D02*
X-1378704D01*
G01D02*
Y88438D01*
G01D02*
X-1370704D01*
G01D02*
Y93238D01*
G01Y84238D02*
X-1378704D01*
G01Y97438D02*
X-1370704D01*
G01D02*
Y102238D01*
G01D02*
X-1378704D01*
G01D02*
Y97438D01*
G01Y111238D02*
Y106438D01*
G01D02*
X-1370704D01*
G01D02*
Y111238D01*
G01D02*
X-1378704D01*
G01Y120238D02*
Y115438D01*
G01D02*
X-1370704D01*
G01D02*
Y120238D01*
G01X-1378704Y124438D02*
X-1370704D01*
G01D02*
Y129238D01*
G01X-1378704D02*
Y124438D01*
G01X-1370704Y120238D02*
X-1378704D01*
G01Y133438D02*
X-1370704D01*
G01D02*
Y138238D01*
G01D02*
X-1378704D01*
G01D02*
Y133438D01*
G01X-1370704Y129238D02*
X-1378704D01*
G01Y147238D02*
Y142438D01*
G01D02*
X-1370704D01*
G01D02*
Y147238D01*
G01D02*
X-1378704D01*
G01Y165238D02*
Y160438D01*
G01D02*
X-1370704D01*
G01D02*
Y165238D01*
G01Y156238D02*
X-1378704D01*
G01D02*
Y151438D01*
G01D02*
X-1370704D01*
G01D02*
Y156238D01*
G01Y165238D02*
X-1378704D01*
G01X-1363228Y296746D02*
G03I-3152J0D01*
G01X-1369442Y295998D02*
X-1363318D01*
G01X-1372752Y451960D02*
Y392116D01*
G01X-1361304Y51038D02*
Y43038D01*
G01D02*
X-1356504D01*
G01D02*
Y51038D01*
G01D02*
X-1361304D01*
G01Y70038D02*
Y62038D01*
G01D02*
X-1356504D01*
G01D02*
Y70038D01*
G01D02*
X-1361304D01*
G01X-1359704Y79638D02*
X-1351704D01*
G01D02*
Y84438D01*
G01X-1359704D02*
Y79638D01*
G01X-1351704Y84438D02*
X-1359704D01*
G01X-1351304Y151438D02*
Y159438D01*
G01D02*
X-1356104D01*
G01D02*
Y151438D01*
G01D02*
X-1351304D01*
G01X-1361916Y230424D02*
Y193652D01*
G01D02*
X-1323492D01*
G01Y230424D02*
X-1361916D01*
G01X-1361004Y331738D02*
Y292338D01*
G01X-1351704Y378038D02*
X-1341704D01*
G01X-1351704Y394038D02*
Y378038D01*
G01X-1357304Y382038D02*
Y390038D01*
G01D02*
X-1362104D01*
G01D02*
Y382038D01*
G01D02*
X-1357304D01*
G01X-1341704Y394038D02*
X-1351704D01*
G01X-1339104Y419438D02*
X-1355104D01*
G01D02*
Y409438D01*
G01D02*
X-1339104D01*
G01X-1325930Y437264D02*
X-1354278D01*
G01D02*
Y465612D01*
G01D02*
X-1325930D01*
G01X-1353104Y478838D02*
Y474038D01*
G01D02*
X-1345104D01*
G01Y494438D02*
X-1361104D01*
G01D02*
Y484438D01*
G01D02*
X-1345104D01*
G01Y478838D02*
X-1353104D01*
G01X-1317744Y91366D02*
X-1347664D01*
G01D02*
Y132310D01*
G01D02*
X-1317744D01*
G01X-1346104Y159438D02*
Y151438D01*
G01D02*
X-1341304D01*
G01D02*
Y159438D01*
G01D02*
X-1346104D01*
G01X-1331336D02*
X-1336136D01*
G01D02*
Y151438D01*
G01D02*
X-1331336D01*
G01X-1341704Y378038D02*
Y394038D01*
G01X-1335704Y378038D02*
X-1325704D01*
G01X-1335704Y394038D02*
Y378038D01*
G01X-1325704Y394038D02*
X-1335704D01*
G01X-1339104Y409438D02*
Y419438D01*
G01X-1349104Y428838D02*
Y424038D01*
G01D02*
X-1341104D01*
G01D02*
Y428838D01*
G01D02*
X-1349104D01*
G01X-1327062Y470876D02*
G03I-4000J0D01*
G01X-1345104Y474038D02*
Y478838D01*
G01Y484438D02*
Y494438D01*
G01X-1317744Y132310D02*
Y91366D01*
G01X-1331336Y151438D02*
Y159438D01*
G01X-1316104Y149838D02*
Y162638D01*
G01X-1308904Y149838D02*
X-1316104D01*
G01Y162638D02*
X-1308904D01*
G01X-1321304Y151438D02*
Y159438D01*
G01D02*
X-1326104D01*
G01D02*
Y151438D01*
G01D02*
X-1321304D01*
G01X-1323492Y193652D02*
Y230424D01*
G01X-1319704Y378038D02*
X-1309704D01*
G01X-1319704Y394038D02*
Y378038D01*
G01X-1325704D02*
Y394038D01*
G01X-1309704D02*
X-1319704D01*
G01X-1324504Y420438D02*
Y412438D01*
G01D02*
X-1319704D01*
G01D02*
Y420438D01*
G01D02*
X-1324504D01*
G01X-1325930Y465612D02*
Y437264D01*
G01X-1316704Y485838D02*
X-1329504D01*
G01D02*
Y493038D01*
G01D02*
X-1316704D01*
G01D02*
Y485838D01*
G01X-1312704Y-35962D02*
X-1302704D01*
G01D02*
Y-19962D01*
G01X-1312704D02*
Y-35962D01*
G01X-1298104Y-26962D02*
Y-34962D01*
G01D02*
X-1293304D01*
G01Y-26962D02*
X-1298104D01*
G01X-1302704Y-19962D02*
X-1312704D01*
G01X-1297504Y6336D02*
X-1302304D01*
G01D02*
Y-1664D01*
G01D02*
X-1297504D01*
G01X-1305356Y18488D02*
G03I-3000J0D01*
G01X-1310030Y15998D02*
X-1306682D01*
G01X-1310948Y19998D02*
X-1305764D01*
G01X-1294422Y39616D02*
X-1309382D01*
G01D02*
Y24656D01*
G01D02*
X-1294422D01*
G01X-1301822Y112570D02*
Y129106D01*
G01X-1291586Y112570D02*
X-1301822D01*
G01Y129106D02*
X-1291586D01*
G01X-1302486Y133444D02*
G03I-4000J0D01*
G01X-1310216Y131998D02*
X-1302756D01*
G01X-1309564Y135998D02*
X-1303408D01*
G01X-1308904Y162638D02*
Y149838D01*
G01X-1303904Y159838D02*
Y151838D01*
G01D02*
X-1299104D01*
G01D02*
Y159838D01*
G01D02*
X-1303904D01*
G01X-1307318Y332652D02*
Y289424D01*
G01D02*
X-1264090D01*
G01Y332652D02*
X-1307318D01*
G01X-1309704Y378038D02*
Y394038D01*
G01X-1303704Y407438D02*
X-1311704D01*
G01D02*
Y402638D01*
G01D02*
X-1303704D01*
G01D02*
Y407438D01*
G01X-1298104Y418038D02*
X-1306104D01*
G01D02*
Y413238D01*
G01D02*
X-1298104D01*
G01D02*
Y418038D01*
G01X-1300624Y426138D02*
Y428738D01*
G01D02*
X-1305584D01*
G01D02*
Y426138D01*
G01D02*
X-1300624D01*
G01X-1305584Y439738D02*
Y437138D01*
G01D02*
X-1300624D01*
G01D02*
Y439738D01*
G01D02*
X-1305584D01*
G01X-1306104Y444038D02*
X-1298104D01*
G01D02*
Y448838D01*
G01D02*
X-1306104D01*
G01D02*
Y444038D01*
G01Y453038D02*
X-1298104D01*
G01D02*
Y457838D01*
G01D02*
X-1306104D01*
G01D02*
Y453038D01*
G01Y462038D02*
X-1298104D01*
G01D02*
Y466838D01*
G01X-1306104D02*
Y462038D01*
G01X-1298104Y466838D02*
X-1306104D01*
G01X-1300824Y471938D02*
Y474538D01*
G01D02*
X-1305784D01*
G01D02*
Y471938D01*
G01D02*
X-1300824D01*
G01X-1300104Y486038D02*
X-1292104D01*
G01Y490838D02*
X-1300104D01*
G01D02*
Y486038D01*
G01X-1275304Y-60562D02*
X-1288104D01*
G01D02*
Y-53362D01*
G01D02*
X-1275304D01*
G01X-1293304Y-34962D02*
Y-26962D01*
G01X-1297504Y-1664D02*
Y6336D01*
G01X-1292304D02*
Y-1664D01*
G01D02*
X-1287504D01*
G01D02*
Y6336D01*
G01D02*
X-1292304D01*
G01X-1294422Y24656D02*
Y39616D01*
G01X-1273304Y86438D02*
X-1286104D01*
G01D02*
Y93638D01*
G01D02*
X-1273304D01*
G01X-1291586Y129106D02*
Y112570D01*
G01X-1284658Y118718D02*
Y113758D01*
G01D02*
X-1282058D01*
G01D02*
Y118718D01*
G01X-1284658Y126958D02*
X-1282058D01*
G01D02*
Y131918D01*
G01X-1284658D02*
Y126958D01*
G01X-1282058Y118718D02*
X-1284658D01*
G01X-1282058Y131918D02*
X-1284658D01*
G01X-1277216Y151226D02*
X-1281152D01*
G01D02*
Y157526D01*
G01X-1283122Y169338D02*
Y156738D01*
G01D02*
X-1281152D01*
G01X-1283122D02*
X-1281546Y158314D01*
G01X-1281152Y157526D02*
X-1277216D01*
G01X-1261862Y158314D02*
X-1281546D01*
G01D02*
Y167762D01*
G01X-1281152Y169338D02*
X-1283122D01*
G01D02*
X-1281546Y167762D01*
G01X-1281152Y174850D02*
X-1277216D01*
G01Y168550D02*
X-1281152D01*
G01D02*
Y174850D01*
G01X-1281546Y167762D02*
X-1261862D01*
G01X-1296704Y209438D02*
Y201438D01*
G01D02*
X-1291904D01*
G01Y209438D02*
X-1296704D01*
G01X-1291904Y201438D02*
Y209438D01*
G01X-1296704Y228438D02*
Y220438D01*
G01D02*
X-1291904D01*
G01Y228438D02*
X-1296704D01*
G01X-1291904Y220438D02*
Y228438D01*
G01X-1280704Y252438D02*
Y244438D01*
G01D02*
X-1275904D01*
G01Y252438D02*
X-1280704D01*
G01X-1268104Y265238D02*
X-1280904D01*
G01D02*
Y272438D01*
G01D02*
X-1268104D01*
G01X-1283704Y416438D02*
Y424438D01*
G01D02*
X-1288504D01*
G01D02*
Y416438D01*
G01D02*
X-1283704D01*
G01X-1292104Y486038D02*
Y490838D01*
G01X-1265704Y-133962D02*
Y-143962D01*
G01D02*
X-1249704D01*
G01Y-133962D02*
X-1265704D01*
G01X-1275304Y-53362D02*
Y-60562D01*
G01X-1274704Y-35962D02*
X-1264704D01*
G01D02*
Y-19962D01*
G01X-1274704D02*
Y-35962D01*
G01X-1264704Y-19962D02*
X-1274704D01*
G01X-1273304Y93638D02*
Y86438D01*
G01X-1272104Y134038D02*
Y126038D01*
G01D02*
X-1267304D01*
G01D02*
Y134038D01*
G01D02*
X-1272104D01*
G01X-1277216Y157526D02*
Y151226D01*
G01X-1262256D02*
X-1266192D01*
G01D02*
Y157526D01*
G01X-1269736D02*
Y151226D01*
G01D02*
X-1273672D01*
G01D02*
Y157526D01*
G01X-1266192Y156738D02*
X-1269736D01*
G01D02*
Y157526D01*
G01D02*
X-1273672D01*
G01D02*
Y156738D01*
G01D02*
X-1277216D01*
G01X-1266192Y157526D02*
X-1262256D01*
G01X-1273672D02*
X-1269736D01*
G01X-1266192Y169338D02*
X-1269736D01*
G01X-1273672D02*
X-1277216D01*
G01X-1273672Y174850D02*
X-1269736D01*
G01D02*
Y168550D01*
G01D02*
X-1273672D01*
G01D02*
Y174850D01*
G01X-1266192D02*
X-1262256D01*
G01Y168550D02*
X-1266192D01*
G01D02*
Y174850D01*
G01X-1277216D02*
Y168550D01*
G01X-1263042Y165794D02*
G03I-1182J0D01*
G01X-1272704Y188638D02*
X-1264704D01*
G01D02*
Y193438D01*
G01D02*
X-1272704D01*
G01D02*
Y188638D01*
G01X-1269904Y208438D02*
X-1259904D01*
G01X-1269904Y224438D02*
Y208438D01*
G01X-1259904Y224438D02*
X-1269904D01*
G01X-1269304Y254038D02*
Y238038D01*
G01D02*
X-1259304D01*
G01X-1275904Y244438D02*
Y252438D01*
G01X-1259304Y254038D02*
X-1269304D01*
G01X-1268104Y272438D02*
Y265238D01*
G01X-1264090Y289424D02*
Y332652D01*
G01X-1259104Y-167962D02*
Y-175962D01*
G01D02*
X-1254304D01*
G01Y-167962D02*
X-1259104D01*
G01X-1254304Y-175962D02*
Y-167962D01*
G01X-1248704Y-154562D02*
X-1256704D01*
G01D02*
Y-159362D01*
G01D02*
X-1248704D01*
G01D02*
Y-154562D01*
G01X-1249704Y-143962D02*
Y-133962D01*
G01X-1245824Y-97942D02*
G03I-5000J0D01*
G01X-1255380Y-100002D02*
X-1246268D01*
G01X-1255432Y-96002D02*
X-1246216D01*
G01X-1261104Y134038D02*
Y126038D01*
G01D02*
X-1256304D01*
G01D02*
Y134038D01*
G01D02*
X-1261104D01*
G01X-1262256Y157526D02*
Y151226D01*
G01X-1260286Y169338D02*
Y156738D01*
G01D02*
X-1262256D01*
G01X-1261862Y158314D02*
X-1260286Y156738D01*
G01X-1261862Y167762D02*
Y158314D01*
G01X-1252904Y159238D02*
Y151238D01*
G01D02*
X-1248104D01*
G01D02*
Y159238D01*
G01D02*
X-1252904D01*
G01X-1262256Y169338D02*
X-1260286D01*
G01X-1261862Y167762D02*
X-1260286Y169338D01*
G01X-1262256Y174850D02*
Y168550D01*
G01X-1247304Y182638D02*
X-1239304D01*
G01X-1247304Y187438D02*
Y182638D01*
G01Y191638D02*
X-1239304D01*
G01Y196438D02*
X-1247304D01*
G01D02*
Y191638D01*
G01X-1239304Y187438D02*
X-1247304D01*
G01X-1259904Y208438D02*
Y224438D01*
G01X-1247304Y201638D02*
X-1239304D01*
G01Y206438D02*
X-1247304D01*
G01D02*
Y201638D01*
G01X-1248904Y219038D02*
Y227038D01*
G01X-1253704D02*
Y219038D01*
G01D02*
X-1248904D01*
G01Y227038D02*
X-1253704D01*
G01X-1259304Y238038D02*
Y254038D01*
G01X-1253704Y251038D02*
Y243038D01*
G01D02*
X-1248904D01*
G01D02*
Y251038D01*
G01D02*
X-1253704D01*
G01X-1251904Y265038D02*
X-1243904D01*
G01X-1251904Y269838D02*
Y265038D01*
G01X-1243904Y269838D02*
X-1251904D01*
G01X-1250158Y292218D02*
G03I-3000J0D01*
G01X-1242656Y-206040D02*
Y-165884D01*
G01X-1186752Y-206040D02*
X-1242656D01*
G01Y-165884D02*
X-1186752D01*
G01X-1236704Y-159362D02*
X-1228704D01*
G01D02*
Y-154562D01*
G01D02*
X-1236704D01*
G01D02*
Y-159362D01*
G01X-1240256Y88590D02*
Y-92514D01*
G01D02*
X-1059152D01*
G01Y88590D02*
X-1240256D01*
G01X-1241104Y159238D02*
Y151238D01*
G01D02*
X-1236304D01*
G01D02*
Y159238D01*
G01X-1229304D02*
Y151238D01*
G01D02*
X-1224504D01*
G01X-1236304Y159238D02*
X-1241104D01*
G01X-1224504D02*
X-1229304D01*
G01X-1239304Y182638D02*
Y187438D01*
G01Y191638D02*
Y196438D01*
G01Y201638D02*
Y206438D01*
G01X-1233360Y214932D02*
G03I-3000J0D01*
G01X-1236986Y211998D02*
X-1235734D01*
G01X-1239164Y215998D02*
X-1233556D01*
G01X-1240312Y226030D02*
Y250046D01*
G01X-1216296Y226030D02*
X-1240312D01*
G01Y250046D02*
X-1216296D01*
G01X-1243904Y265038D02*
Y269838D01*
G01X-1232304Y265038D02*
X-1224304D01*
G01X-1232304Y269838D02*
Y265038D01*
G01X-1224304Y269838D02*
X-1232304D01*
G01X-1234304Y334038D02*
Y342038D01*
G01X-1239104D02*
Y334038D01*
G01D02*
X-1234304D01*
G01Y342038D02*
X-1239104D01*
G01X-1234704Y403038D02*
X-1242704D01*
G01D02*
Y398238D01*
G01D02*
X-1234704D01*
G01D02*
Y403038D01*
G01Y413438D02*
X-1242704D01*
G01D02*
Y408638D01*
G01D02*
X-1234704D01*
G01D02*
Y413438D01*
G01X-1209704Y-154562D02*
X-1217704D01*
G01D02*
Y-159362D01*
G01D02*
X-1209704D01*
G01X-1206304Y-136962D02*
X-1211104D01*
G01D02*
Y-144962D01*
G01D02*
X-1206304D01*
G01X-1224504Y151238D02*
Y159238D01*
G01X-1217504D02*
Y151238D01*
G01D02*
X-1212704D01*
G01D02*
Y159238D01*
G01D02*
X-1217504D01*
G01X-1225304Y187438D02*
Y182638D01*
G01D02*
X-1217304D01*
G01X-1225304Y191638D02*
X-1217304D01*
G01Y196438D02*
X-1225304D01*
G01D02*
Y191638D01*
G01X-1217304Y187438D02*
X-1225304D01*
G01X-1217304Y182638D02*
Y187438D01*
G01Y191638D02*
Y196438D01*
G01X-1222784Y205138D02*
Y202538D01*
G01D02*
X-1217824D01*
G01D02*
Y205138D01*
G01D02*
X-1222784D01*
G01X-1216296Y250046D02*
Y226030D01*
G01X-1224304Y265038D02*
Y269838D01*
G01X-1215604Y264558D02*
X-1213004D01*
G01D02*
Y269518D01*
G01X-1215604D02*
Y264558D01*
G01X-1213004Y269518D02*
X-1215604D01*
G01X-1215904Y294438D02*
X-1207904D01*
G01Y299238D02*
X-1215904D01*
G01D02*
Y294438D01*
G01Y304838D02*
X-1207904D01*
G01Y309638D02*
X-1215904D01*
G01D02*
Y304838D01*
G01X-1206042Y332324D02*
X-1223366D01*
G01D02*
Y342952D01*
G01D02*
X-1206042D01*
G01X-1209704Y-159362D02*
Y-154562D01*
G01X-1198704Y-159362D02*
X-1190704D01*
G01Y-154562D02*
X-1198704D01*
G01D02*
Y-159362D01*
G01X-1197304Y-144962D02*
Y-136962D01*
G01D02*
X-1202104D01*
G01D02*
Y-144962D01*
G01D02*
X-1197304D01*
G01X-1206304D02*
Y-136962D01*
G01X-1194504Y159238D02*
Y151238D01*
G01D02*
X-1189704D01*
G01X-1205704Y159238D02*
Y151238D01*
G01D02*
X-1200904D01*
G01D02*
Y159238D01*
G01X-1189704D02*
X-1194504D01*
G01X-1200904D02*
X-1205704D01*
G01X-1207904Y294438D02*
Y299238D01*
G01Y304838D02*
Y309638D01*
G01X-1206042Y342952D02*
Y332324D01*
G01X-1197104Y343038D02*
Y335038D01*
G01D02*
X-1192304D01*
G01Y343038D02*
X-1197104D01*
G01X-1203904Y354638D02*
G03I-3000J0D01*
G01X-1208328Y351998D02*
X-1205480D01*
G01X-1209578Y355998D02*
X-1204230D01*
G01X-1162404Y364338D02*
X-1197004D01*
G01D02*
Y403738D01*
G01D02*
X-1162404D01*
G01X-1188478Y399330D02*
G03I-3150J0D01*
G01X-1194706Y399998D02*
X-1188550D01*
G01X-1201590Y467124D02*
Y427752D01*
G01D02*
X-1162218D01*
G01Y467124D02*
X-1201590D01*
G01X-1186752Y-165884D02*
Y-206040D01*
G01X-1190704Y-159362D02*
Y-154562D01*
G01X-1189704Y151238D02*
Y159238D01*
G01X-1183104D02*
Y151238D01*
G01D02*
X-1178304D01*
G01D02*
Y159238D01*
G01D02*
X-1183104D01*
G01X-1185304Y225038D02*
Y215038D01*
G01D02*
X-1169304D01*
G01X-1173504Y209838D02*
X-1181504D01*
G01D02*
Y205038D01*
G01D02*
X-1173504D01*
G01X-1185304Y241238D02*
Y231238D01*
G01D02*
X-1169304D01*
G01Y225038D02*
X-1185304D01*
G01X-1169304Y241238D02*
X-1185304D01*
G01X-1192304Y335038D02*
Y343038D01*
G01X-1167042Y332724D02*
X-1184366D01*
G01D02*
Y343352D01*
G01D02*
X-1167042D01*
G01X-1172104Y-166962D02*
Y-174962D01*
G01D02*
X-1167304D01*
G01D02*
Y-166962D01*
G01D02*
X-1172104D01*
G01X-1171304Y159238D02*
Y151238D01*
G01D02*
X-1166504D01*
G01D02*
Y159238D01*
G01D02*
X-1171304D01*
G01X-1169304Y215038D02*
Y225038D01*
G01X-1173504Y205038D02*
Y209838D01*
G01X-1169304Y231238D02*
Y241238D01*
G01X-1135604Y260538D02*
X-1170204D01*
G01D02*
Y299938D01*
G01D02*
X-1135604D01*
G01X-1161678Y295530D02*
G03I-3150J0D01*
G01X-1167944Y295998D02*
X-1161712D01*
G01X-1167042Y343352D02*
Y332724D01*
G01X-1164904Y355038D02*
G03I-3000J0D01*
G01X-1170746Y355998D02*
X-1165062D01*
G01X-1162404Y403738D02*
Y364338D01*
G01X-1162218Y427752D02*
Y467124D01*
G01X-1157982Y-190954D02*
Y-164970D01*
G01X-1117826Y-190954D02*
X-1157982D01*
G01Y-164970D02*
X-1117826D01*
G01X-1138104Y-153962D02*
X-1146104D01*
G01D02*
Y-158762D01*
G01D02*
X-1138104D01*
G01X-1145604Y-123962D02*
Y-128762D01*
G01D02*
X-1137604D01*
G01Y-123962D02*
X-1145604D01*
G01X-1151316Y236050D02*
Y212426D01*
G01D02*
X-1127692D01*
G01Y236050D02*
X-1151316D01*
G01X-1145104Y348038D02*
Y340038D01*
G01D02*
X-1140304D01*
G01Y348038D02*
X-1145104D01*
G01X-1148702Y435038D02*
G03I-4000J0D01*
G01X-1155304Y431998D02*
X-1150100D01*
G01X-1156586Y435998D02*
X-1148818D01*
G01X-1126904Y-158762D02*
X-1118904D01*
G01Y-153962D02*
X-1126904D01*
G01D02*
Y-158762D01*
G01X-1138104D02*
Y-153962D01*
G01X-1125504Y-144562D02*
Y-136562D01*
G01D02*
X-1130304D01*
G01D02*
Y-144562D01*
G01D02*
X-1125504D01*
G01X-1134504D02*
Y-136562D01*
G01D02*
X-1139304D01*
G01D02*
Y-144562D01*
G01D02*
X-1134504D01*
G01X-1127204Y-128762D02*
X-1119204D01*
G01X-1127204Y-123962D02*
Y-128762D01*
G01X-1137604D02*
Y-123962D01*
G01X-1119204D02*
X-1127204D01*
G01X-1120304Y141038D02*
X-1125104D01*
G01D02*
Y133038D01*
G01D02*
X-1120304D01*
G01X-1134104Y141038D02*
Y133038D01*
G01D02*
X-1129304D01*
G01D02*
Y141038D01*
G01D02*
X-1134104D01*
G01X-1124704Y198038D02*
Y182038D01*
G01D02*
X-1114704D01*
G01Y198038D02*
X-1124704D01*
G01X-1135104Y197038D02*
Y189038D01*
G01D02*
X-1130304D01*
G01D02*
Y197038D01*
G01D02*
X-1135104D01*
G01X-1127692Y212426D02*
Y236050D01*
G01X-1135604Y299938D02*
Y260538D01*
G01X-1132904Y355038D02*
Y358838D01*
G01X-1129304D02*
Y355038D01*
G01D02*
X-1132904D01*
G01X-1140304Y340038D02*
Y348038D01*
G01X-1129632Y343296D02*
G03I-3000J0D01*
G01X-1135548Y343998D02*
X-1129716D01*
G01X-1132904Y356838D02*
X-1129304D01*
G01X-1135104Y358838D02*
X-1134504Y359438D01*
G01X-1132904Y358838D02*
X-1129304D01*
G01X-1134504Y359438D02*
Y368638D01*
G01X-1112904Y359438D02*
X-1134504D01*
G01X-1135104Y358838D02*
Y369238D01*
G01X-1112304Y358838D02*
X-1135104D01*
G01X-1125504Y371238D02*
X-1121904D01*
G01X-1135104Y369238D02*
X-1134504Y368638D01*
G01X-1125504Y369238D02*
Y373038D01*
G01X-1121904Y369238D02*
X-1125504D01*
G01X-1134504Y368638D02*
X-1112904D01*
G01X-1135104Y369238D02*
X-1112304D01*
G01X-1125504Y373038D02*
X-1121904D01*
G01X-1133704Y386638D02*
X-1125704D01*
G01D02*
Y391438D01*
G01X-1133704D02*
Y386638D01*
G01X-1125704Y391438D02*
X-1133704D01*
G01Y395638D02*
X-1125704D01*
G01D02*
Y400438D01*
G01D02*
X-1133704D01*
G01D02*
Y395638D01*
G01Y404638D02*
X-1125704D01*
G01D02*
Y409438D01*
G01X-1133704D02*
Y404638D01*
G01X-1131704Y424438D02*
X-1139704D01*
G01D02*
Y419638D01*
G01D02*
X-1131704D01*
G01D02*
Y424438D01*
G01X-1125704Y409438D02*
X-1133704D01*
G01X-1139704Y434438D02*
Y429638D01*
G01D02*
X-1131704D01*
G01D02*
Y434438D01*
G01D02*
X-1139704D01*
G01Y439638D02*
X-1131704D01*
G01D02*
Y444438D01*
G01X-1139704D02*
Y439638D01*
G01Y464438D02*
Y459638D01*
G01D02*
X-1131704D01*
G01D02*
Y464438D01*
G01X-1139704Y449638D02*
X-1131704D01*
G01D02*
Y454438D01*
G01D02*
X-1139704D01*
G01D02*
Y449638D01*
G01X-1131704Y444438D02*
X-1139704D01*
G01X-1131704Y464438D02*
X-1139704D01*
G01X-1131704Y474438D02*
X-1139704D01*
G01D02*
Y469638D01*
G01D02*
X-1131704D01*
G01D02*
Y474438D01*
G01X-1117826Y-164970D02*
Y-190954D01*
G01X-1118904Y-158762D02*
Y-153962D01*
G01X-1119204Y-128762D02*
Y-123962D01*
G01X-1107104Y-114962D02*
Y-122962D01*
G01D02*
X-1102304D01*
G01Y-114962D02*
X-1107104D01*
G01X-1106104Y122038D02*
Y114038D01*
G01D02*
X-1101304D01*
G01Y122038D02*
X-1106104D01*
G01X-1120304Y133038D02*
Y141038D01*
G01X-1102304D02*
X-1107104D01*
G01D02*
Y133038D01*
G01D02*
X-1102304D01*
G01X-1111304D02*
Y141038D01*
G01D02*
X-1116104D01*
G01D02*
Y133038D01*
G01D02*
X-1111304D01*
G01X-1114704Y182038D02*
Y198038D01*
G01X-1113704Y210040D02*
G03I-3998J0D01*
G01X-1121140Y207998D02*
X-1114264D01*
G01X-1121188Y211998D02*
X-1114216D01*
G01X-1108104Y295438D02*
Y290638D01*
G01D02*
X-1100104D01*
G01Y295438D02*
X-1108104D01*
G01X-1108704Y300638D02*
X-1100704D01*
G01X-1108704Y305438D02*
Y300638D01*
G01X-1100704Y305438D02*
X-1108704D01*
G01X-1118104Y355038D02*
Y358838D01*
G01X-1114504D02*
Y355038D01*
G01D02*
X-1118104D01*
G01X-1121904Y373038D02*
Y369238D01*
G01X-1118104Y356838D02*
X-1114504D01*
G01X-1112904Y359438D02*
X-1112304Y358838D01*
G01X-1118104D02*
X-1114504D01*
G01X-1112904Y368638D02*
Y359438D01*
G01X-1112304Y369238D02*
Y358838D01*
G01X-1112904Y368638D02*
X-1112304Y369238D01*
G01X-1107104Y427038D02*
Y419038D01*
G01D02*
X-1102304D01*
G01Y427038D02*
X-1107104D01*
G01X-1102304Y-122962D02*
Y-114962D01*
G01X-1096104D02*
Y-122962D01*
G01D02*
X-1091304D01*
G01D02*
Y-114962D01*
G01D02*
X-1096104D01*
G01X-1101304Y114038D02*
Y122038D01*
G01X-1084304Y141038D02*
X-1089104D01*
G01D02*
Y133038D01*
G01D02*
X-1084304D01*
G01X-1102304D02*
Y141038D01*
G01X-1093304Y133038D02*
Y141038D01*
G01D02*
X-1098104D01*
G01D02*
Y133038D01*
G01D02*
X-1093304D01*
G01X-1105704Y215638D02*
X-1097704D01*
G01D02*
Y220438D01*
G01X-1105704D02*
Y215638D01*
G01X-1097704Y220438D02*
X-1105704D01*
G01Y225638D02*
X-1097704D01*
G01D02*
Y230438D01*
G01D02*
X-1105704D01*
G01D02*
Y225638D01*
G01X-1097704Y250438D02*
X-1105704D01*
G01D02*
Y245638D01*
G01D02*
X-1097704D01*
G01D02*
Y250438D01*
G01X-1105704Y235638D02*
X-1097704D01*
G01D02*
Y240438D01*
G01D02*
X-1105704D01*
G01D02*
Y235638D01*
G01X-1100104Y290638D02*
Y295438D01*
G01X-1100704Y300638D02*
Y305438D01*
G01X-1079304Y417438D02*
X-1092104D01*
G01D02*
Y424638D01*
G01D02*
X-1079304D01*
G01X-1102304Y419038D02*
Y427038D01*
G01X-1094504Y439438D02*
Y429438D01*
G01D02*
X-1078504D01*
G01Y439438D02*
X-1094504D01*
G01X-1071704Y-196362D02*
X-1063704D01*
G01Y-191562D02*
X-1071704D01*
G01D02*
Y-196362D01*
G01Y-170362D02*
X-1063704D01*
G01X-1071704Y-165562D02*
Y-170362D01*
G01Y-180362D02*
X-1063704D01*
G01Y-175562D02*
X-1071704D01*
G01D02*
Y-180362D01*
G01X-1063704Y-165562D02*
X-1071704D01*
G01Y-160362D02*
X-1063704D01*
G01Y-155562D02*
X-1071704D01*
G01D02*
Y-160362D01*
G01X-1078304Y109038D02*
Y117038D01*
G01X-1083104D02*
Y109038D01*
G01D02*
X-1078304D01*
G01Y117038D02*
X-1083104D01*
G01X-1084304Y133038D02*
Y141038D01*
G01X-1072504Y159438D02*
Y134238D01*
G01D02*
X-1052904D01*
G01Y159438D02*
X-1072504D01*
G01X-1079304Y424638D02*
Y417438D01*
G01X-1078504Y429438D02*
Y439438D01*
G01X-1063704Y-196362D02*
Y-191562D01*
G01Y-170362D02*
Y-165562D01*
G01Y-180362D02*
Y-175562D01*
G01Y-160362D02*
Y-155562D01*
G01X-1059152Y-92514D02*
Y88590D01*
G01X-1056104Y358038D02*
Y350038D01*
G01D02*
X-1051304D01*
G01X-1066104Y358038D02*
Y350038D01*
G01D02*
X-1061304D01*
G01D02*
Y358038D01*
G01X-1051304D02*
X-1056104D01*
G01X-1061304D02*
X-1066104D01*
G01X-1056760Y373420D02*
Y440720D01*
G01X-1024240Y373420D02*
X-1056760D01*
G01Y440720D02*
X-1024240D01*
G01X-1052904Y134238D02*
Y159438D01*
G01X-1000116Y268330D02*
G03I-22400J0D01*
G01X-1051304Y350038D02*
Y358038D01*
G01X-1046104D02*
Y350038D01*
G01D02*
X-1041304D01*
G01D02*
Y358038D01*
G01X-1036104D02*
Y350038D01*
G01D02*
X-1031304D01*
G01X-1041304Y358038D02*
X-1046104D01*
G01X-1031304D02*
X-1036104D01*
G01X-1000116Y473054D02*
G03I-22400J0D01*
G01X-992404Y-204662D02*
X-1027004D01*
G01D02*
Y-165262D01*
G01X-1018478Y-169670D02*
G03I-3150J0D01*
G01X-1023746Y-172002D02*
X-1019510D01*
G01X-1024300Y-168002D02*
X-1018956D01*
G01X-1027004Y-165262D02*
X-992404D01*
G01X-1025504Y-93162D02*
Y-103162D01*
G01D02*
X-1009504D01*
G01Y-93162D02*
X-1025504D01*
G01X-1010704Y-81562D02*
X-1018704D01*
G01D02*
Y-86362D01*
G01D02*
X-1010704D01*
G01X-1018704Y-67362D02*
X-1010704D01*
G01X-1018704Y-62562D02*
Y-67362D01*
G01X-1010704Y-71562D02*
X-1018704D01*
G01D02*
Y-76362D01*
G01D02*
X-1010704D01*
G01Y-62562D02*
X-1018704D01*
G01X-1033704Y-22562D02*
Y-27362D01*
G01D02*
X-1025704D01*
G01D02*
Y-22562D01*
G01D02*
X-1033704D01*
G01X-1025704Y-13562D02*
X-1033704D01*
G01D02*
Y-18362D01*
G01D02*
X-1025704D01*
G01D02*
Y-13562D01*
G01X-1033704Y-9362D02*
X-1025704D01*
G01D02*
Y-4562D01*
G01D02*
X-1033704D01*
G01D02*
Y-9362D01*
G01X-1025704Y4438D02*
X-1033704D01*
G01D02*
Y-362D01*
G01D02*
X-1025704D01*
G01D02*
Y4438D01*
G01Y46438D02*
X-1033704D01*
G01D02*
Y41638D01*
G01D02*
X-1025704D01*
G01D02*
Y46438D01*
G01Y56438D02*
X-1033704D01*
G01D02*
Y51638D01*
G01D02*
X-1025704D01*
G01D02*
Y56438D01*
G01Y65438D02*
X-1033704D01*
G01D02*
Y60638D01*
G01D02*
X-1025704D01*
G01D02*
Y65438D01*
G01Y74438D02*
X-1033704D01*
G01D02*
Y69638D01*
G01D02*
X-1025704D01*
G01D02*
Y74438D01*
G01X-1027704Y141238D02*
Y154038D01*
G01X-1020504D02*
Y141238D01*
G01D02*
X-1027704D01*
G01Y154038D02*
X-1020504D01*
G01X-1016304Y176038D02*
X-1021104D01*
G01D02*
Y168038D01*
G01D02*
X-1016304D01*
G01X-1035304Y194438D02*
Y186438D01*
G01D02*
X-1030504D01*
G01D02*
Y194438D01*
G01D02*
X-1035304D01*
G01X-1016104D02*
X-1020904D01*
G01D02*
Y186438D01*
G01D02*
X-1016104D01*
G01X-1015624Y205738D02*
X-1020584D01*
G01D02*
Y203138D01*
G01D02*
X-1015624D01*
G01X-1021304Y350038D02*
Y358038D01*
G01X-1026104D02*
Y350038D01*
G01D02*
X-1021304D01*
G01X-1031304D02*
Y358038D01*
G01X-1021304D02*
X-1026104D01*
G01X-1024240Y440720D02*
Y373420D01*
G01X-1009504Y-103162D02*
Y-93162D01*
G01X-1010704Y-86362D02*
Y-81562D01*
G01Y-67362D02*
Y-62562D01*
G01Y-76362D02*
Y-71562D01*
G01X-1007704Y141438D02*
X-999704D01*
G01X-1007704Y146238D02*
Y141438D01*
G01X-1009304Y160838D02*
Y150838D01*
G01D02*
X-993304D01*
G01X-999704Y146238D02*
X-1007704D01*
G01X-993304Y160838D02*
X-1009304D01*
G01X-1016304Y168038D02*
Y176038D01*
G01X-1002104Y166038D02*
X-994104D01*
G01Y170838D02*
X-1002104D01*
G01D02*
Y166038D01*
G01X-1016104Y186438D02*
Y194438D01*
G01X-1015624Y203138D02*
Y205738D01*
G01X-1016104Y358038D02*
Y350038D01*
G01D02*
X-1011304D01*
G01D02*
Y358038D01*
G01D02*
X-1016104D01*
G01X-1005704Y431038D02*
Y415038D01*
G01D02*
X-995704D01*
G01Y431038D02*
X-1005704D01*
G01X-992404Y-165262D02*
Y-204662D01*
G01X-999704Y141438D02*
Y146238D01*
G01X-993304Y150838D02*
Y160838D01*
G01X-977096Y178430D02*
X-1001112D01*
G01D02*
Y202446D01*
G01X-994104Y166038D02*
Y170838D01*
G01X-1001112Y202446D02*
X-977096D01*
G01X-984704Y406438D02*
X-992704D01*
G01D02*
Y401638D01*
G01D02*
X-984704D01*
G01D02*
Y406438D01*
G01X-990304Y418638D02*
Y431438D01*
G01X-983104Y418638D02*
X-990304D01*
G01X-995704Y415038D02*
Y431038D01*
G01X-990304Y431438D02*
X-983104D01*
G01X-970704Y-97962D02*
Y-107962D01*
G01D02*
X-954704D01*
G01Y-97962D02*
X-970704D01*
G01X-974304Y-72162D02*
Y-91762D01*
G01D02*
X-949104D01*
G01Y-72162D02*
X-974304D01*
G01Y-47162D02*
Y-66762D01*
G01D02*
X-949104D01*
G01Y-47162D02*
X-974304D01*
G01Y-22162D02*
Y-41762D01*
G01D02*
X-949104D01*
G01Y-22162D02*
X-974304D01*
G01X-975104Y-2362D02*
X-962304D01*
G01Y-9562D02*
X-975104D01*
G01D02*
Y-2362D01*
G01X-979704Y158238D02*
Y148238D01*
G01D02*
X-963704D01*
G01Y158238D02*
X-979704D01*
G01X-977096Y202446D02*
Y178430D01*
G01X-970104Y169838D02*
X-978104D01*
G01D02*
Y165038D01*
G01D02*
X-970104D01*
G01D02*
Y169838D01*
G01X-962998Y182382D02*
G03I-3000J0D01*
G01X-967820Y179998D02*
X-964176D01*
G01X-968526Y183998D02*
X-963470D01*
G01X-968200Y326176D02*
X-958200D01*
G01X-983104Y431438D02*
Y418638D01*
G01X-960704Y-196562D02*
Y-201362D01*
G01D02*
X-952704D01*
G01D02*
Y-196562D01*
G01X-960704Y-184562D02*
Y-189362D01*
G01D02*
X-952704D01*
G01D02*
Y-184562D01*
G01Y-196562D02*
X-960704D01*
G01X-952704Y-174562D02*
X-960704D01*
G01D02*
Y-179362D01*
G01D02*
X-952704D01*
G01D02*
Y-174562D01*
G01Y-184562D02*
X-960704D01*
G01Y-169362D02*
X-952704D01*
G01D02*
Y-164562D01*
G01X-960704D02*
Y-169362D01*
G01X-952704Y-164562D02*
X-960704D01*
G01X-954704Y-107962D02*
Y-97962D01*
G01X-949104Y-91762D02*
Y-72162D01*
G01Y-66762D02*
Y-47162D01*
G01Y-41762D02*
Y-22162D01*
G01X-962304Y-2362D02*
Y-9562D01*
G01X-963704Y148238D02*
Y158238D01*
G01X-952704Y171438D02*
Y179438D01*
G01D02*
X-957504D01*
G01D02*
Y171438D01*
G01D02*
X-952704D01*
G01X-957184Y195338D02*
Y192738D01*
G01D02*
X-952224D01*
G01D02*
Y195338D01*
G01D02*
X-957184D01*
G01X-945304Y211038D02*
X-950104D01*
G01D02*
Y203038D01*
G01D02*
X-945304D01*
G01X-959104Y211038D02*
Y203038D01*
G01D02*
X-954304D01*
G01D02*
Y211038D01*
G01D02*
X-959104D01*
G01X-898512Y285750D02*
X-954496D01*
G01D02*
Y334726D01*
G01X-963200Y321176D02*
Y331176D01*
G01X-954496Y334726D02*
X-898512D01*
G01X-964904Y382038D02*
X-954904D01*
G01D02*
Y398038D01*
G01X-964904D02*
Y382038D01*
G01X-954904Y398038D02*
X-964904D01*
G01X-936504Y419438D02*
X-952504D01*
G01D02*
Y409438D01*
G01D02*
X-936504D01*
G01X-936104Y425838D02*
X-948904D01*
G01D02*
Y433038D01*
G01D02*
X-936104D01*
G01X-950560Y491734D02*
X-957648D01*
G01D02*
Y478346D01*
G01D02*
X-950560D01*
G01D02*
Y491734D01*
G01X-949704Y507440D02*
X-959704D01*
G01X-954704Y502440D02*
Y512440D01*
G01X-937704Y-16962D02*
Y-32962D01*
G01D02*
X-927704D01*
G01Y-16962D02*
X-937704D01*
G01X-945704Y5038D02*
X-935704D01*
G01X-945704Y21038D02*
Y5038D01*
G01X-935704D02*
Y21038D01*
G01D02*
X-945704D01*
G01X-928704Y75038D02*
X-938704D01*
G01D02*
Y59038D01*
G01D02*
X-928704D01*
G01X-946904Y104838D02*
Y96838D01*
G01D02*
X-942104D01*
G01Y104838D02*
X-946904D01*
G01X-928104Y93838D02*
X-935304D01*
G01D02*
Y106638D01*
G01D02*
X-928104D01*
G01X-942104Y96838D02*
Y104838D01*
G01X-942704Y179438D02*
X-947504D01*
G01D02*
Y171438D01*
G01D02*
X-942704D01*
G01D02*
Y179438D01*
G01X-945304Y203038D02*
Y211038D01*
G01X-948504Y382038D02*
X-938504D01*
G01X-948504Y398038D02*
Y382038D01*
G01X-938504D02*
Y398038D01*
G01D02*
X-948504D01*
G01X-936504Y409438D02*
Y419438D01*
G01X-946504Y438038D02*
X-938504D01*
G01X-946504Y442838D02*
Y438038D01*
G01X-936104Y433038D02*
Y425838D01*
G01X-938504Y438038D02*
Y442838D01*
G01D02*
X-946504D01*
G01X-930296Y485092D02*
X-940296D01*
G01X-935296Y480092D02*
Y490092D01*
G01X-932296Y508650D02*
Y518650D01*
G01X-927296Y513650D02*
X-937296D01*
G01X-918224Y-225262D02*
Y-222662D01*
G01D02*
X-923184D01*
G01D02*
Y-225262D01*
G01D02*
X-918224D01*
G01X-929704Y-215362D02*
X-921704D01*
G01D02*
Y-210562D01*
G01D02*
X-929704D01*
G01D02*
Y-215362D01*
G01X-915304Y-173362D02*
Y-183362D01*
G01D02*
X-899304D01*
G01Y-173362D02*
X-915304D01*
G01X-927704Y-32962D02*
Y-16962D01*
G01X-918470Y46558D02*
Y-13282D01*
G01D02*
X-864138D01*
G01X-926304Y8038D02*
Y16038D01*
G01X-931104D02*
Y8038D01*
G01D02*
X-926304D01*
G01Y16038D02*
X-931104D01*
G01X-864138Y46558D02*
X-918470D01*
G01X-928704Y59038D02*
Y75038D01*
G01X-923104D02*
Y67038D01*
G01D02*
X-918304D01*
G01D02*
Y75038D01*
G01D02*
X-923104D01*
G01X-912224Y88698D02*
G03I-4000J0D01*
G01X-928104Y106638D02*
Y93838D01*
G01X-920104Y122038D02*
Y114038D01*
G01D02*
X-915304D01*
G01D02*
Y122038D01*
G01D02*
X-920104D01*
G01X-918304Y175654D02*
X-908292D01*
G01Y170614D02*
X-918304D01*
G01D02*
Y175654D01*
G01Y195654D02*
X-908292D01*
G01Y190614D02*
X-918304D01*
G01D02*
Y195654D01*
G01Y215654D02*
X-908292D01*
G01Y210614D02*
X-918304D01*
G01D02*
Y215654D01*
G01X-908292Y230814D02*
X-918304D01*
G01D02*
Y235854D01*
G01D02*
X-908292D01*
G01X-918304Y255654D02*
X-908292D01*
G01Y250614D02*
X-918304D01*
G01D02*
Y255654D01*
G01X-903104Y359238D02*
X-915904D01*
G01D02*
Y366438D01*
G01D02*
X-903104D01*
G01X-915708Y416516D02*
Y376360D01*
G01D02*
X-891300D01*
G01Y416516D02*
X-915708D01*
G01X-917618Y444838D02*
Y440038D01*
G01D02*
X-909618D01*
G01Y444838D02*
X-917618D01*
G01X-927240Y477386D02*
Y463998D01*
G01D02*
X-920152D01*
G01D02*
Y477386D01*
G01X-906674Y483092D02*
X-916674D01*
G01X-920152Y477386D02*
X-927240D01*
G01Y504944D02*
Y491556D01*
G01D02*
X-920152D01*
G01D02*
Y504944D01*
G01D02*
X-927240D01*
G01X-873696Y-227170D02*
X-897712D01*
G01D02*
Y-203154D01*
G01D02*
X-873696D01*
G01X-898810Y-205106D02*
G03I-3000J0D01*
G01X-902594Y-208002D02*
X-901026D01*
G01X-904600Y-204002D02*
X-899020D01*
G01X-905104Y-194962D02*
X-897104D01*
G01D02*
Y-190162D01*
G01D02*
X-905104D01*
G01D02*
Y-194962D01*
G01X-899304Y-183362D02*
Y-173362D01*
G01X-900704Y-149962D02*
Y-165962D01*
G01D02*
X-890704D01*
G01Y-149962D02*
X-900704D01*
G01X-881530Y65864D02*
X-909878D01*
G01D02*
Y94212D01*
G01D02*
X-881530D01*
G01X-910004Y119518D02*
Y114558D01*
G01D02*
X-907404D01*
G01Y119518D02*
X-910004D01*
G01X-907404Y114558D02*
Y119518D01*
G01X-897304Y114038D02*
Y122038D01*
G01X-902104D02*
Y114038D01*
G01D02*
X-897304D01*
G01Y122038D02*
X-902104D01*
G01X-869904Y164852D02*
X-908304D01*
G01D02*
Y261624D01*
G01X-908292Y175654D02*
Y170614D01*
G01Y195654D02*
Y190614D01*
G01Y215654D02*
Y210614D01*
G01Y235854D02*
Y230814D01*
G01Y255654D02*
Y250614D01*
G01X-908304Y261624D02*
X-869904D01*
G01X-898512Y334726D02*
Y285750D01*
G01X-903104Y366438D02*
Y359238D01*
G01X-913984Y432738D02*
Y430138D01*
G01D02*
X-909024D01*
G01Y432738D02*
X-913984D01*
G01X-898704Y429638D02*
X-890704D01*
G01X-898704Y434438D02*
Y429638D01*
G01X-909024Y430138D02*
Y432738D01*
G01X-898704Y443438D02*
Y438638D01*
G01D02*
X-890704D01*
G01X-909618Y440038D02*
Y444838D01*
G01X-890704Y434438D02*
X-898704D01*
G01X-890704Y443438D02*
X-898704D01*
G01X-903618Y477386D02*
Y463998D01*
G01D02*
X-896530D01*
G01X-911674Y478092D02*
Y488092D01*
G01X-896530Y477386D02*
X-903618D01*
G01Y504944D02*
Y491556D01*
G01D02*
X-896530D01*
G01X-908674Y510650D02*
Y520650D01*
G01X-896530Y504944D02*
X-903618D01*
G01X-903674Y515650D02*
X-913674D01*
G01X-872704Y-190162D02*
X-880704D01*
G01D02*
Y-194962D01*
G01D02*
X-872704D01*
G01X-869704Y-174162D02*
X-885704D01*
G01D02*
Y-184162D01*
G01D02*
X-869704D01*
G01X-890704Y-165962D02*
Y-149962D01*
G01X-885104Y-153962D02*
Y-161962D01*
G01D02*
X-880304D01*
G01D02*
Y-153962D01*
G01D02*
X-885104D01*
G01X-880704Y-23962D02*
Y-33962D01*
G01D02*
X-864704D01*
G01Y-23962D02*
X-880704D01*
G01X-881530Y94212D02*
Y65864D01*
G01X-884004Y114558D02*
X-881404D01*
G01D02*
Y119518D01*
G01X-884004D02*
Y114558D01*
G01X-888304Y114038D02*
Y122038D01*
G01X-893104D02*
Y114038D01*
G01D02*
X-888304D01*
G01X-879704Y126638D02*
X-871704D01*
G01X-879704Y131438D02*
Y126638D01*
G01X-881404Y119518D02*
X-884004D01*
G01X-888304Y122038D02*
X-893104D01*
G01X-871704Y131438D02*
X-879704D01*
G01X-891504Y360438D02*
X-883504D01*
G01D02*
Y365238D01*
G01X-891504D02*
Y360438D01*
G01X-883504Y365238D02*
X-891504D01*
G01X-891300Y376360D02*
Y416516D01*
G01X-874298Y380690D02*
G03I-4002J0D01*
G01X-882240Y379998D02*
X-874360D01*
G01X-880552Y383998D02*
X-876048D01*
G01X-890704Y429638D02*
Y434438D01*
G01Y438638D02*
Y443438D01*
G01X-896530Y463998D02*
Y477386D01*
G01X-879996D02*
Y463998D01*
G01D02*
X-872908D01*
G01X-885052Y476092D02*
Y486092D01*
G01X-880052Y481092D02*
X-890052D01*
G01X-879996Y504944D02*
Y491556D01*
G01D02*
X-872908D01*
G01Y477386D02*
X-879996D01*
G01X-896530Y491556D02*
Y504944D01*
G01X-884052Y508650D02*
Y518650D01*
G01X-872908Y504944D02*
X-879996D01*
G01X-879052Y513650D02*
X-889052D01*
G01X-873696Y-203154D02*
Y-227170D01*
G01X-872704Y-194962D02*
Y-190162D01*
G01X-869704Y-184162D02*
Y-174162D01*
G01X-867104Y-152562D02*
Y-165362D01*
G01D02*
X-874304D01*
G01D02*
Y-152562D01*
G01D02*
X-867104D01*
G01X-864704Y-33962D02*
Y-23962D01*
G01X-864138Y-13282D02*
Y46558D01*
G01X-863704Y81038D02*
Y65038D01*
G01D02*
X-853704D01*
G01X-873104Y79038D02*
Y71038D01*
G01D02*
X-868304D01*
G01D02*
Y79038D01*
G01X-853704Y81038D02*
X-863704D01*
G01X-868304Y79038D02*
X-873104D01*
G01X-864704Y95638D02*
X-856704D01*
G01Y100438D02*
X-864704D01*
G01D02*
Y95638D01*
G01X-862304Y122038D02*
Y114038D01*
G01D02*
X-857504D01*
G01X-873004Y120518D02*
Y115558D01*
G01D02*
X-870404D01*
G01D02*
Y120518D01*
G01X-871704Y126638D02*
Y131438D01*
G01X-857504Y122038D02*
X-862304D01*
G01X-870404Y120518D02*
X-873004D01*
G01X-869904Y261624D02*
Y164852D01*
G01Y175854D02*
X-859892D01*
G01Y170814D02*
X-869904D01*
G01D02*
Y175854D01*
G01Y195654D02*
X-859892D01*
G01Y190614D02*
X-869904D01*
G01D02*
Y195654D01*
G01Y215654D02*
X-859892D01*
G01Y210614D02*
X-869904D01*
G01D02*
Y215654D01*
G01X-859892Y230614D02*
X-869904D01*
G01D02*
Y235654D01*
G01D02*
X-859892D01*
G01X-869904Y255654D02*
X-859892D01*
G01Y250614D02*
X-869904D01*
G01D02*
Y255654D01*
G01X-858504Y344838D02*
X-866504D01*
G01D02*
Y340038D01*
G01D02*
X-858504D01*
G01X-866504Y350038D02*
X-858504D01*
G01Y354838D02*
X-866504D01*
G01D02*
Y350038D01*
G01Y360038D02*
X-858504D01*
G01X-866504Y364838D02*
Y360038D01*
G01Y374838D02*
Y370038D01*
G01D02*
X-858504D01*
G01Y364838D02*
X-866504D01*
G01X-858504Y374838D02*
X-866504D01*
G01X-858504Y384838D02*
X-866504D01*
G01D02*
Y380038D01*
G01D02*
X-858504D01*
G01X-864024Y390138D02*
Y392738D01*
G01D02*
X-868984D01*
G01D02*
Y390138D01*
G01D02*
X-864024D01*
G01X-858504Y402838D02*
X-866504D01*
G01D02*
Y398038D01*
G01D02*
X-858504D01*
G01X-866504Y408038D02*
X-858504D01*
G01Y412838D02*
X-866504D01*
G01D02*
Y408038D01*
G01Y418038D02*
X-858504D01*
G01Y422838D02*
X-866504D01*
G01D02*
Y418038D01*
G01Y432838D02*
Y428038D01*
G01D02*
X-858504D01*
G01Y432838D02*
X-866504D01*
G01X-872908Y463998D02*
Y477386D01*
G01X-855430Y483092D02*
X-865430D01*
G01X-872908Y491556D02*
Y504944D01*
G01X-855430Y514650D02*
X-865430D01*
G01X-859184Y-227862D02*
Y-230462D01*
G01D02*
X-854224D01*
G01D02*
Y-227862D01*
G01D02*
X-859184D01*
G01X-858704Y-211162D02*
Y-219162D01*
G01D02*
X-853904D01*
G01D02*
Y-211162D01*
G01D02*
X-858704D01*
G01X-858104Y-191962D02*
Y-199962D01*
G01D02*
X-853304D01*
G01D02*
Y-191962D01*
G01D02*
X-858104D01*
G01X-853704Y65038D02*
Y81038D01*
G01X-856704Y95638D02*
Y100438D01*
G01X-857504Y114038D02*
Y122038D01*
G01X-859892Y175854D02*
Y170814D01*
G01Y195654D02*
Y190614D01*
G01Y215654D02*
Y210614D01*
G01Y235654D02*
Y230614D01*
G01Y255654D02*
Y250614D01*
G01X-858504Y340038D02*
Y344838D01*
G01Y350038D02*
Y354838D01*
G01Y360038D02*
Y364838D01*
G01Y370038D02*
Y374838D01*
G01Y380038D02*
Y384838D01*
G01Y398038D02*
Y402838D01*
G01Y408038D02*
Y412838D01*
G01Y418038D02*
Y422838D01*
G01Y428038D02*
Y432838D01*
G01X-856374Y477386D02*
Y463998D01*
G01D02*
X-849286D01*
G01D02*
Y477386D01*
G01X-860430Y478092D02*
Y488092D01*
G01X-856374Y504944D02*
Y491556D01*
G01D02*
X-849286D01*
G01D02*
Y504944D01*
G01Y477386D02*
X-856374D01*
G01X-860430Y509650D02*
Y519650D01*
G01X-849286Y504944D02*
X-856374D01*
G01X-827704Y-155562D02*
Y-160362D01*
G01X-819704Y-155562D02*
X-827704D01*
G01Y-160362D02*
X-819704D01*
G01X-827704Y-132562D02*
Y-137362D01*
G01D02*
X-819704D01*
G01X-827704Y-143562D02*
Y-148362D01*
G01X-819704Y-143562D02*
X-827704D01*
G01Y-148362D02*
X-819704D01*
G01X-827704Y-128362D02*
X-819704D01*
G01X-827704Y-123562D02*
Y-128362D01*
G01X-819704Y-132562D02*
X-827704D01*
G01X-819704Y-123562D02*
X-827704D01*
G01X-824500Y38968D02*
X-829300D01*
G01D02*
Y30968D01*
G01D02*
X-824500D01*
G01X-821704Y49038D02*
G03I-4000J0D01*
G01X-829566Y47998D02*
X-821842D01*
G01X-828394Y51998D02*
X-823014D01*
G01X-822598Y108242D02*
X-830598D01*
G01D02*
Y103442D01*
G01D02*
X-822598D01*
G01X-830598Y94438D02*
X-822598D01*
G01Y99238D02*
X-830598D01*
G01D02*
Y94438D01*
G01Y117438D02*
Y112638D01*
G01D02*
X-822598D01*
G01Y117438D02*
X-830598D01*
G01X-832752Y477386D02*
Y463998D01*
G01D02*
X-825664D01*
G01D02*
X-832752D01*
Y467998D01*
X-825664D01*
Y463998D01*
G01X-832752Y467998D02*
X-825664D01*
G01Y477386D02*
X-832752D01*
G01X-829808Y490092D02*
Y500092D01*
G01X-824808Y495092D02*
X-834808D01*
G01X-819704Y-160362D02*
Y-155562D01*
G01Y-137362D02*
Y-132562D01*
G01Y-148362D02*
Y-143562D01*
G01Y-128362D02*
Y-123562D01*
G01X-814500Y30968D02*
Y38968D01*
G01D02*
X-819300D01*
G01D02*
Y30968D01*
G01D02*
X-814500D01*
G01X-824500D02*
Y38968D01*
G01X-822940Y78074D02*
Y57602D01*
G01D02*
X-802468D01*
G01Y78074D02*
X-822940D01*
G01X-822598Y103442D02*
Y108242D01*
G01Y94438D02*
Y99238D01*
G01Y112638D02*
Y117438D01*
G01X-815704Y174454D02*
X-805692D01*
G01Y169414D02*
X-815704D01*
G01D02*
Y174454D01*
G01Y194454D02*
X-805692D01*
G01Y189414D02*
X-815704D01*
G01D02*
Y194454D01*
G01Y214454D02*
X-805692D01*
G01Y209414D02*
X-815704D01*
G01D02*
Y214454D01*
G01X-805692Y229614D02*
X-815704D01*
G01D02*
Y234654D01*
G01D02*
X-805692D01*
G01Y249414D02*
X-815704D01*
G01D02*
Y254454D01*
G01D02*
X-805692D01*
G01X-825664Y463998D02*
Y477386D01*
G01X-816186Y482092D02*
Y492092D01*
G01X-811186Y487092D02*
X-821186D01*
G01X-810186Y511650D02*
X-820186D01*
G01X-815186Y506650D02*
Y516650D01*
G01X-809300Y38968D02*
Y30968D01*
G01D02*
X-804500D01*
G01Y38968D02*
X-809300D01*
G01X-804500Y30968D02*
Y38968D01*
G01X-794500Y30968D02*
Y38968D01*
G01D02*
X-799300D01*
G01D02*
Y30968D01*
G01D02*
X-794500D01*
G01X-802468Y57602D02*
Y78074D01*
G01X-804704Y91638D02*
X-796704D01*
G01D02*
Y96438D01*
G01X-804704D02*
Y91638D01*
G01X-792304Y110238D02*
X-805104D01*
G01D02*
Y117438D01*
G01X-792304D02*
Y110238D01*
G01X-796704Y96438D02*
X-804704D01*
G01Y100638D02*
X-796704D01*
G01D02*
Y105438D01*
G01D02*
X-804704D01*
G01D02*
Y100638D01*
G01X-805104Y117438D02*
X-792304D01*
G01X-767304Y163652D02*
X-805704D01*
G01D02*
Y260424D01*
G01X-805692Y174454D02*
Y169414D01*
G01Y194454D02*
Y189414D01*
G01Y214454D02*
Y209414D01*
G01Y234654D02*
Y229614D01*
G01Y254454D02*
Y249414D01*
G01X-805704Y260424D02*
X-767304D01*
G01X-689130Y295180D02*
X-792908D01*
G01D02*
Y406832D01*
G01D02*
X-689130D01*
G01X-809130Y477386D02*
Y463998D01*
G01D02*
X-802042D01*
G01D02*
X-809130D01*
Y467998D01*
X-802042D01*
Y463998D01*
G01X-809130Y467998D02*
X-802042D01*
G01Y463998D02*
Y477386D01*
G01D02*
X-809130D01*
G01Y504944D02*
Y491556D01*
G01D02*
X-802042D01*
G01X-792564Y478092D02*
Y488092D01*
G01X-787564Y483092D02*
X-797564D01*
G01X-802042Y491556D02*
Y504944D01*
G01D02*
X-809130D01*
G01X-786564Y512650D02*
X-796564D01*
G01X-763704Y-153962D02*
X-787704D01*
G01D02*
Y-129962D01*
G01X-780504Y-134562D02*
G03I-3000J0D01*
G01X-786136Y-136002D02*
X-780872D01*
G01X-787704Y-129962D02*
X-763704D01*
G01X-785068Y-132002D02*
X-781940D01*
G01X-784904Y112838D02*
Y104838D01*
G01D02*
X-780104D01*
G01D02*
Y112838D01*
G01D02*
X-784904D01*
G01X-785508Y477386D02*
Y463998D01*
G01D02*
X-778420D01*
G01D02*
Y477386D01*
G01Y463998D02*
X-785508D01*
Y467998D01*
X-778420D01*
Y463998D01*
G01X-785508Y467998D02*
X-778420D01*
G01Y477386D02*
X-785508D01*
G01Y504944D02*
Y491556D01*
G01D02*
X-778420D01*
G01D02*
Y504944D01*
G01X-791564Y507650D02*
Y517650D01*
G01X-778420Y504944D02*
X-785508D01*
G01X-763704Y-129962D02*
Y-153962D01*
G01X-758142Y-109828D02*
Y16156D01*
G01X-690110Y-109828D02*
X-758142D01*
G01Y16156D02*
X-690110D01*
G01X-770704Y57786D02*
Y41786D01*
G01D02*
X-760704D01*
G01Y57786D02*
X-770704D01*
G01X-760704Y41786D02*
Y57786D01*
G01X-762238Y95194D02*
Y88894D01*
G01D02*
X-766174D01*
G01D02*
Y95194D01*
G01X-754758Y88894D02*
X-758694D01*
G01D02*
Y95194D01*
G01Y107006D02*
X-762238D01*
G01X-754758Y95194D02*
X-758694D01*
G01D02*
Y94406D01*
G01D02*
X-762238D01*
G01X-766174Y107006D02*
X-768144D01*
G01D02*
Y94406D01*
G01D02*
X-766174D01*
G01X-768144Y107006D02*
X-766568Y105430D01*
G01X-768144Y94406D02*
X-766568Y95982D01*
G01X-766174Y95194D02*
X-762238D01*
G01X-758694D02*
X-754758D01*
G01Y106218D02*
X-758694D01*
G01D02*
Y112518D01*
G01X-762238D02*
Y106218D01*
G01D02*
X-766174D01*
G01D02*
Y112518D01*
G01X-766568Y105430D02*
X-746884D01*
G01Y95982D02*
X-766568D01*
G01D02*
Y105430D01*
G01X-758694Y112518D02*
X-754758D01*
G01X-766174D02*
X-762238D01*
G01X-767304Y260424D02*
Y163652D01*
G01Y174654D02*
X-757292D01*
G01D02*
Y169614D01*
G01D02*
X-767304D01*
G01D02*
Y174654D01*
G01Y194454D02*
X-757292D01*
G01D02*
Y189414D01*
G01D02*
X-767304D01*
G01D02*
Y194454D01*
G01Y214454D02*
X-757292D01*
G01D02*
Y209414D01*
G01D02*
X-767304D01*
G01D02*
Y214454D01*
G01X-757292Y234454D02*
Y229414D01*
G01D02*
X-767304D01*
G01D02*
Y234454D01*
G01X-757292Y254454D02*
Y249414D01*
G01D02*
X-767304D01*
G01D02*
Y254454D01*
G01Y234454D02*
X-757292D01*
G01X-767304Y254454D02*
X-757292D01*
G01X-707026Y-220254D02*
G03I-23600J0D01*
G01X-755304Y51386D02*
Y43386D01*
G01D02*
X-750504D01*
G01D02*
Y51386D01*
G01D02*
X-755304D01*
G01X-747278Y95194D02*
Y88894D01*
G01D02*
X-751214D01*
G01D02*
Y95194D01*
G01X-754758D02*
Y88894D01*
G01X-747278Y107006D02*
X-745308D01*
G01D02*
Y94406D01*
G01D02*
X-747278D01*
G01X-751214Y107006D02*
X-754758D01*
G01X-751214Y94406D02*
X-754758D01*
G01D02*
Y95194D01*
G01X-746884Y95982D02*
X-745308Y94406D01*
G01X-746884Y105430D02*
X-745308Y107006D01*
G01X-751214Y95194D02*
X-747278D01*
G01X-754758Y112518D02*
Y106218D01*
G01X-747278Y112518D02*
Y106218D01*
G01D02*
X-751214D01*
G01D02*
Y112518D01*
G01X-746884Y105430D02*
Y95982D01*
G01X-748064Y103462D02*
G03I-1182J0D01*
G01X-750300Y103998D02*
X-748192D01*
G01X-751214Y112518D02*
X-747278D01*
G01X-707026Y484708D02*
G03I-23600J0D01*
G01X-726704Y-155562D02*
X-734704D01*
G01D02*
Y-160362D01*
G01D02*
X-726704D01*
G01D02*
Y-155562D01*
G01X-734704Y-132562D02*
Y-137362D01*
G01D02*
X-726704D01*
G01D02*
Y-132562D01*
G01Y-144562D02*
X-734704D01*
G01D02*
Y-149362D01*
G01D02*
X-726704D01*
G01D02*
Y-144562D01*
G01Y-132562D02*
X-734704D01*
G01X-726704Y-121562D02*
X-734704D01*
G01D02*
Y-126362D01*
G01D02*
X-726704D01*
G01D02*
Y-121562D01*
G01X-731162Y40772D02*
Y101400D01*
G01X-689430Y40772D02*
X-731162D01*
G01Y101400D02*
X-689430D01*
G01X-698500Y-250568D02*
G03X-690626Y-242694I0J7874D01*
G01D02*
Y124038D01*
G01X-690110Y16156D02*
Y-109828D01*
G01X-689430Y101400D02*
Y40772D01*
G01X-690626Y124038D02*
G03X-694562Y127976I-3938J0D01*
G01D02*
X-696282D01*
G01X-700218Y131912D02*
G03X-696282Y127976I3936J0D01*
G01X-700218Y131912D02*
Y214392D01*
G01X-696282Y218332D02*
G03X-700218Y214392I2J-3938D01*
G01X-694562Y218330D02*
G03X-690626Y222266I0J3936D01*
G01D02*
Y516360D01*
G01X-696282Y218330D02*
X-694562D01*
G01X-689130Y406832D02*
Y295180D01*
G01X-690626Y516360D02*
G03X-698500Y524234I-7874J0D01*
G01X718294Y-273068D02*
X38374D01*
G01X30500Y-265194D02*
G03X38374Y-273068I7874J0D01*
G01X30500Y-265194D02*
Y101538D01*
G01X34436Y105476D02*
G03X30500Y101538I2J-3938D01*
G01X34436Y105476D02*
X36156D01*
G01D02*
G03X40092Y109412I0J3936D01*
G01D02*
Y191892D01*
G01X30500Y199766D02*
G03X34436Y195830I3936J0D01*
G01X40092Y191892D02*
G03X36156Y195832I-3938J2D01*
G01Y195830D02*
X34436D01*
G01X30500Y199766D02*
Y493860D01*
G01X38374Y501734D02*
G03X30500Y493860I0J-7874D01*
G01X38374Y501734D02*
X1342704D01*
G01X46900Y-242754D02*
G03I23600J0D01*
G01Y462208D02*
G03I23600J0D01*
G01X66578Y-167062D02*
Y-171862D01*
G01D02*
X74578D01*
G01D02*
Y-167062D01*
G01Y-178062D02*
X66578D01*
G01D02*
Y-182862D01*
G01D02*
X74578D01*
G01D02*
Y-178062D01*
G01Y-155062D02*
X66578D01*
G01D02*
Y-159862D01*
G01D02*
X74578D01*
G01D02*
Y-155062D01*
G01Y-167062D02*
X66578D01*
G01X88178Y28286D02*
Y20286D01*
G01D02*
X92978D01*
G01D02*
Y28286D01*
G01D02*
X88178D01*
G01X103624Y-689000D02*
X119249Y-739000D01*
X134876Y-689000D01*
G01X161750D02*
X176749D01*
G01X169249D02*
Y-739000D01*
G01X161750D02*
X176749D01*
G01X231750D02*
X206750D01*
Y-689000D01*
X231750D01*
G01X221750Y-713166D02*
X206750D01*
G01X250500Y-689000D02*
X259249Y-739000D01*
X269249Y-689000D01*
X279250Y-739000D01*
X288000Y-689000D01*
G01X331750Y-739000D02*
X306750D01*
Y-689000D01*
X331750D01*
G01X321750Y-713166D02*
X306750D01*
G01X355500Y-739000D02*
Y-689000D01*
X368000D01*
X373000Y-691501D01*
X376750Y-694834D01*
X379876Y-699833D01*
X382375Y-705668D01*
X383000Y-714001D01*
X382375Y-722334D01*
X379876Y-728167D01*
X376750Y-733168D01*
X373000Y-736501D01*
X368000Y-739000D01*
X355500D01*
G01X457375D02*
Y-689000D01*
X481125D01*
G01X472375Y-713166D02*
X457375D01*
G01X506750Y-739000D02*
Y-689000D01*
X522375D01*
X527375Y-691501D01*
X530500Y-694834D01*
X531750Y-701500D01*
X530500Y-708167D01*
X526750Y-712333D01*
X522375Y-714834D01*
X506750D01*
G01X522375D02*
X531750Y-739000D01*
G01X569249D02*
X564249Y-738167D01*
X559875Y-734834D01*
X556125Y-729834D01*
X553624Y-724000D01*
X552375Y-717333D01*
Y-710667D01*
X553624Y-704000D01*
X556125Y-698166D01*
X559875Y-693167D01*
X564249Y-689833D01*
X569249Y-689000D01*
X574250Y-689833D01*
X578625Y-693167D01*
X582375Y-698166D01*
X584876Y-704000D01*
X586125Y-710667D01*
Y-717333D01*
X584876Y-724000D01*
X582375Y-729834D01*
X578625Y-734834D01*
X574250Y-738167D01*
X569249Y-739000D01*
G01X602999D02*
Y-689000D01*
X619249Y-730667D01*
X635501Y-689000D01*
Y-739000D01*
G01X724250Y-712333D02*
X726750Y-709833D01*
X728625Y-705668D01*
X729876Y-699833D01*
X728625Y-694834D01*
X726125Y-691501D01*
X721750Y-689000D01*
X704875D01*
Y-739000D01*
X725500D01*
X729876Y-735667D01*
X732375Y-730667D01*
X733625Y-724833D01*
X732375Y-719001D01*
X728625Y-714001D01*
X724250Y-712333D01*
X704875D01*
G01X769249Y-739000D02*
X764249Y-738167D01*
X759875Y-734834D01*
X756125Y-729834D01*
X753624Y-724000D01*
X752375Y-717333D01*
Y-710667D01*
X753624Y-704000D01*
X756125Y-698166D01*
X759875Y-693167D01*
X764249Y-689833D01*
X769249Y-689000D01*
X774250Y-689833D01*
X778625Y-693167D01*
X782375Y-698166D01*
X784876Y-704000D01*
X786125Y-710667D01*
Y-717333D01*
X784876Y-724000D01*
X782375Y-729834D01*
X778625Y-734834D01*
X774250Y-738167D01*
X769249Y-739000D01*
G01X819249Y-689000D02*
Y-739000D01*
G01X804875Y-689000D02*
X833625D01*
G01X869249D02*
Y-739000D01*
G01X854875Y-689000D02*
X883625D01*
G01X919249Y-739000D02*
X914249Y-738167D01*
X909875Y-734834D01*
X906125Y-729834D01*
X903624Y-724000D01*
X902375Y-717333D01*
Y-710667D01*
X903624Y-704000D01*
X906125Y-698166D01*
X909875Y-693167D01*
X914249Y-689833D01*
X919249Y-689000D01*
X924250Y-689833D01*
X928625Y-693167D01*
X932375Y-698166D01*
X934876Y-704000D01*
X936125Y-710667D01*
Y-717333D01*
X934876Y-724000D01*
X932375Y-729834D01*
X928625Y-734834D01*
X924250Y-738167D01*
X919249Y-739000D01*
G01X952999D02*
Y-689000D01*
X969249Y-730667D01*
X985501Y-689000D01*
Y-739000D01*
G01X1056125Y-732335D02*
X1061125Y-736501D01*
X1066750Y-739000D01*
X1071750D01*
X1076750Y-736501D01*
X1080500Y-732335D01*
X1082375Y-726500D01*
X1081125Y-720668D01*
X1078000Y-715667D01*
X1072375Y-712333D01*
X1064875Y-710667D01*
X1060500Y-707334D01*
X1058624Y-701500D01*
X1059875Y-695667D01*
X1063000Y-691501D01*
X1067375Y-689000D01*
X1071750D01*
X1076125Y-690666D01*
X1079876Y-694834D01*
G01X1111750Y-689000D02*
X1126749D01*
G01X1119249D02*
Y-739000D01*
G01X1111750D02*
X1126749D01*
G01X1155500D02*
Y-689000D01*
X1168000D01*
X1173000Y-691501D01*
X1176750Y-694834D01*
X1179876Y-699833D01*
X1182375Y-705668D01*
X1183000Y-714001D01*
X1182375Y-722334D01*
X1179876Y-728167D01*
X1176750Y-733168D01*
X1173000Y-736501D01*
X1168000Y-739000D01*
X1155500D01*
G01X1231750D02*
X1206750D01*
Y-689000D01*
X1231750D01*
G01X1221750Y-713166D02*
X1206750D01*
G01X114178Y-78462D02*
Y-86462D01*
G01D02*
X118978D01*
G01X114178Y-58462D02*
Y-66462D01*
G01D02*
X118978D01*
G01Y-78462D02*
X114178D01*
G01Y-38462D02*
Y-46462D01*
G01D02*
X118978D01*
G01Y-58462D02*
X114178D01*
G01X118978Y-38462D02*
X114178D01*
G01X106178Y20286D02*
X110978D01*
G01D02*
Y28286D01*
G01X101978Y20286D02*
Y28286D01*
G01X97178D02*
Y20286D01*
G01D02*
X101978D01*
G01X106178Y28286D02*
Y20286D01*
G01X110978Y28286D02*
X106178D01*
G01X101978D02*
X97178D01*
G01X118978Y-86462D02*
Y-78462D01*
G01Y-66462D02*
Y-58462D01*
G01Y-46462D02*
Y-38462D01*
G01X117178Y-11462D02*
Y-19462D01*
G01D02*
X121978D01*
G01D02*
Y-11462D01*
G01D02*
X117178D01*
G01X119178Y453538D02*
Y445538D01*
G01D02*
X123978D01*
G01D02*
Y453538D01*
G01D02*
X119178D01*
G01X120178Y478538D02*
Y470538D01*
G01D02*
X124978D01*
G01D02*
Y478538D01*
G01D02*
X120178D01*
G01X144374Y8468D02*
X149174D01*
G01D02*
Y16468D01*
G01D02*
X144374D01*
G01D02*
Y8468D01*
G01X134374Y16468D02*
Y8468D01*
G01D02*
X139174D01*
G01D02*
Y16468D01*
G01D02*
X134374D01*
G01X143578Y147138D02*
X151578D01*
G01Y151938D02*
X143578D01*
G01D02*
Y147138D01*
G01Y182138D02*
X151578D01*
G01Y186938D02*
X143578D01*
G01D02*
Y182138D01*
G01X143178Y444538D02*
X147978D01*
G01D02*
Y452538D01*
G01D02*
X143178D01*
G01D02*
Y444538D01*
G01X142778Y470538D02*
X147578D01*
G01D02*
Y478538D01*
G01X142778D02*
Y470538D01*
G01X147578Y478538D02*
X142778D01*
G01X152178Y-81462D02*
Y-89462D01*
G01D02*
X156978D01*
G01D02*
Y-81462D01*
G01D02*
X152178D01*
G01Y-57462D02*
Y-65462D01*
G01D02*
X156978D01*
G01D02*
Y-57462D01*
G01X152178Y-38462D02*
Y-46462D01*
G01D02*
X156978D01*
G01D02*
Y-38462D01*
G01Y-57462D02*
X152178D01*
G01X156978Y-38462D02*
X152178D01*
G01Y-17462D02*
Y-25462D01*
G01D02*
X156978D01*
G01D02*
Y-17462D01*
G01D02*
X152178D01*
G01X154374Y16468D02*
Y8468D01*
G01D02*
X159174D01*
G01D02*
Y16468D01*
G01D02*
X154374D01*
G01X169174D02*
X164374D01*
G01D02*
Y8468D01*
G01D02*
X169174D01*
G01X151578Y147138D02*
Y151938D01*
G01Y182138D02*
Y186938D01*
G01X166178Y452538D02*
Y444538D01*
G01D02*
X170978D01*
G01Y452538D02*
X166178D01*
G01X183178Y-214462D02*
Y-222462D01*
G01D02*
X187978D01*
G01Y-214462D02*
X183178D01*
G01X169174Y8468D02*
Y16468D01*
G01X170978Y444538D02*
Y452538D01*
G01X193778Y-233662D02*
Y-241662D01*
G01D02*
X198578D01*
G01D02*
Y-233662D01*
G01D02*
X193778D01*
G01X193178Y-214462D02*
Y-222462D01*
G01D02*
X197978D01*
G01D02*
Y-214462D01*
G01X187978Y-222462D02*
Y-214462D01*
G01X197978D02*
X193178D01*
G01X198578Y29538D02*
Y19538D01*
G01D02*
X214578D01*
G01Y29538D02*
X198578D01*
G01X197378Y99538D02*
Y91538D01*
G01D02*
X202178D01*
G01Y99538D02*
X197378D01*
G01X219228Y157638D02*
X196728D01*
G01D02*
Y167838D01*
G01X205478Y153738D02*
X198678D01*
G01D02*
Y157638D01*
G01D02*
X205478D01*
G01X200578Y159738D02*
G03I1500J0D01*
G01X196728Y167838D02*
X219228D01*
G01X202278D02*
X198678D01*
G01D02*
Y171738D01*
G01D02*
X202278D01*
G01X220228Y214638D02*
X197728D01*
G01X199678D02*
X206478D01*
G01X199678Y210738D02*
Y214638D01*
G01X206478Y210738D02*
X199678D01*
G01X197728Y214638D02*
Y224838D01*
G01D02*
X220228D01*
G01X199678Y228738D02*
X203278D01*
G01X199678Y224838D02*
Y228738D01*
G01X203278Y224838D02*
X199678D01*
G01X201578Y216738D02*
G03I1500J0D01*
G01X206378Y400338D02*
X198378D01*
G01D02*
Y395538D01*
G01D02*
X206378D01*
G01X198378Y410338D02*
Y405538D01*
G01D02*
X206378D01*
G01Y410338D02*
X198378D01*
G01X188578Y439138D02*
X196578D01*
G01D02*
Y443938D01*
G01X188578D02*
Y439138D01*
G01X196578Y443938D02*
X188578D01*
G01X196578Y452938D02*
X188578D01*
G01D02*
Y448138D01*
G01D02*
X196578D01*
G01D02*
Y452938D01*
G01X190178Y478538D02*
Y470538D01*
G01D02*
X194978D01*
G01D02*
Y478538D01*
G01D02*
X190178D01*
G01X214578Y19538D02*
Y29538D01*
G01X214178Y101938D02*
Y89138D01*
G01D02*
X206978D01*
G01D02*
Y101938D01*
G01X202178Y91538D02*
Y99538D01*
G01X206978Y101938D02*
X214178D01*
G01X217278Y153738D02*
X213678D01*
G01Y157638D02*
X217278D01*
G01D02*
Y153738D01*
G01X213678D02*
Y157638D01*
G01X205478D02*
Y153738D01*
G01X217278Y167838D02*
X213678D01*
G01Y171738D02*
X217278D01*
G01D02*
Y167838D01*
G01X213678D02*
Y171738D01*
G01X202278D02*
Y167838D01*
G01X218278Y214638D02*
Y210738D01*
G01X214678Y214638D02*
X218278D01*
G01X214678Y210738D02*
Y214638D01*
G01X218278Y210738D02*
X214678D01*
G01X206478Y214638D02*
Y210738D01*
G01X218278Y228738D02*
Y224838D01*
G01X214678Y228738D02*
X218278D01*
G01X214678Y224838D02*
Y228738D01*
G01X218278Y224838D02*
X214678D01*
G01X203278Y228738D02*
Y224838D01*
G01X204372Y217498D02*
X201784D01*
G01X206378Y395538D02*
Y400338D01*
G01Y405538D02*
Y410338D01*
G01X213178Y443538D02*
X217978D01*
G01D02*
Y451538D01*
G01D02*
X213178D01*
G01D02*
Y443538D01*
G01X214178Y470538D02*
X218978D01*
G01D02*
Y478538D01*
G01X214178D02*
Y470538D01*
G01X218978Y478538D02*
X214178D01*
G01X224578Y24938D02*
Y20138D01*
G01D02*
X232578D01*
G01D02*
Y24938D01*
G01D02*
X224578D01*
G01X220678Y59438D02*
Y61638D01*
G01D02*
X224478D01*
G01D02*
Y59438D01*
G01D02*
X220678D01*
G01X232978Y91538D02*
Y99538D01*
G01X228178D02*
Y91538D01*
G01D02*
X232978D01*
G01X220278Y98018D02*
Y93058D01*
G01D02*
X222878D01*
G01D02*
Y98018D01*
G01X232978Y99538D02*
X228178D01*
G01X222878Y98018D02*
X220278D01*
G01X219228Y167838D02*
Y157638D01*
G01X220228Y224838D02*
Y214638D01*
G01X241978Y-251662D02*
Y-243662D01*
G01D02*
X237178D01*
G01D02*
Y-251662D01*
G01D02*
X241978D01*
G01X236778Y-224262D02*
Y-232262D01*
G01D02*
X241578D01*
G01D02*
Y-224262D01*
G01D02*
X236778D01*
G01X246178Y31538D02*
X250978D01*
G01D02*
Y39538D01*
G01D02*
X246178D01*
G01D02*
Y31538D01*
G01Y52538D02*
X250978D01*
G01D02*
Y60538D01*
G01X246178D02*
Y52538D01*
G01X250978Y60538D02*
X246178D01*
G01Y91538D02*
X250978D01*
G01D02*
Y99538D01*
G01X246178D02*
Y91538D01*
G01X241978D02*
Y99538D01*
G01X237178D02*
Y91538D01*
G01D02*
X241978D01*
G01X250978Y99538D02*
X246178D01*
G01X241978D02*
X237178D01*
G01X241578Y143138D02*
X249578D01*
G01D02*
Y147938D01*
G01X241578D02*
Y143138D01*
G01X249578Y147938D02*
X241578D01*
G01Y152138D02*
X249578D01*
G01D02*
Y156938D01*
G01D02*
X241578D01*
G01D02*
Y152138D01*
G01Y178138D02*
X249578D01*
G01D02*
Y182938D01*
G01X241978Y168338D02*
X249978D01*
G01D02*
Y173138D01*
G01D02*
X241978D01*
G01X241578Y182938D02*
Y178138D01*
G01X241978Y173138D02*
Y168338D01*
G01X251578Y202938D02*
Y198138D01*
G01D02*
X259578D01*
G01X241578Y187138D02*
X249578D01*
G01D02*
Y191938D01*
G01D02*
X241578D01*
G01X249578Y182938D02*
X241578D01*
G01Y191938D02*
Y187138D01*
G01X259578Y202938D02*
X251578D01*
G01X241978Y208638D02*
X249978D01*
G01D02*
Y213438D01*
G01D02*
X241978D01*
G01D02*
Y208638D01*
G01X241578Y228138D02*
X249578D01*
G01D02*
Y232938D01*
G01D02*
X241578D01*
G01D02*
Y228138D01*
G01Y237138D02*
X249578D01*
G01D02*
Y241938D01*
G01D02*
X241578D01*
G01D02*
Y237138D01*
G01X243778Y262738D02*
X259778D01*
G01X243778Y272738D02*
Y262738D01*
G01X259778Y272738D02*
X243778D01*
G01X242978Y279138D02*
X258978D01*
G01X242978Y289138D02*
Y279138D01*
G01X258978Y289138D02*
X242978D01*
G01Y294338D02*
X258978D01*
G01X242978Y304338D02*
Y294338D01*
G01X258978Y304338D02*
X242978D01*
G01Y309738D02*
X258978D01*
G01Y319738D02*
X242978D01*
G01D02*
Y309738D01*
G01X236578Y438138D02*
X244578D01*
G01D02*
Y442938D01*
G01X236578D02*
Y438138D01*
G01X244578Y451938D02*
X236578D01*
G01D02*
Y447138D01*
G01D02*
X244578D01*
G01D02*
Y451938D01*
G01Y442938D02*
X236578D01*
G01X237178Y478538D02*
Y470538D01*
G01D02*
X241978D01*
G01D02*
Y478538D01*
G01D02*
X237178D01*
G01X261578Y-247862D02*
X269578D01*
G01D02*
Y-243062D01*
G01D02*
X261578D01*
G01D02*
Y-247862D01*
G01Y-233062D02*
Y-237862D01*
G01D02*
X269578D01*
G01D02*
Y-233062D01*
G01D02*
X261578D01*
G01X270178Y-44462D02*
Y-52462D01*
G01D02*
X274978D01*
G01Y-44462D02*
X270178D01*
G01X265578Y-17462D02*
X275578D01*
G01X265578Y-1462D02*
Y-17462D01*
G01X275578Y-1462D02*
X265578D01*
G01X255178Y99538D02*
Y91538D01*
G01D02*
X259978D01*
G01D02*
Y99538D01*
G01X272578Y83938D02*
X264578D01*
G01D02*
Y79138D01*
G01D02*
X272578D01*
G01X259978Y99538D02*
X255178D01*
G01X262478Y154238D02*
Y162238D01*
G01D02*
X257678D01*
G01D02*
Y154238D01*
G01D02*
X262478D01*
G01X259578Y198138D02*
Y202938D01*
G01X257778Y188938D02*
Y180938D01*
G01D02*
X262578D01*
G01D02*
Y188938D01*
G01D02*
X257778D01*
G01Y219238D02*
Y211238D01*
G01D02*
X262578D01*
G01D02*
Y219238D01*
G01X257778Y238538D02*
Y230538D01*
G01D02*
X262578D01*
G01D02*
Y238538D01*
G01Y219238D02*
X257778D01*
G01X262578Y238538D02*
X257778D01*
G01X259778Y262738D02*
Y272738D01*
G01X258978Y279138D02*
Y289138D01*
G01Y294338D02*
Y304338D01*
G01X268494Y312534D02*
X278494D01*
G01X258978Y309738D02*
Y319738D01*
G01X265978Y451538D02*
Y459538D01*
G01D02*
X261178D01*
G01D02*
Y451538D01*
G01D02*
X265978D01*
G01X261178Y478538D02*
Y470538D01*
G01D02*
X265978D01*
G01D02*
Y478538D01*
G01D02*
X261178D01*
G01X274978Y-52462D02*
Y-44462D01*
G01X275578Y-17462D02*
Y-1462D01*
G01X272578Y79138D02*
Y83938D01*
G01X273494Y317534D02*
Y307534D01*
G01X271826Y329828D02*
X302930D01*
G01X271826Y366048D02*
Y329828D01*
G01X302930Y366048D02*
X271826D01*
G01X283578Y458540D02*
X288378D01*
G01D02*
Y466540D01*
G01X283578D02*
Y458540D01*
G01X288378Y466540D02*
X283578D01*
G01X297378Y148938D02*
Y156938D01*
G01D02*
X292578D01*
G01D02*
Y148938D01*
G01D02*
X297378D01*
G01X302930Y329828D02*
Y366048D01*
G01X298378Y458540D02*
Y466540D01*
G01X293578D02*
Y458540D01*
G01D02*
X298378D01*
G01Y466540D02*
X293578D01*
G01X349178Y122338D02*
X333178D01*
G01D02*
Y112338D01*
G01D02*
X349178D01*
G01X331178Y405538D02*
Y397538D01*
G01D02*
X335978D01*
G01D02*
Y405538D01*
G01D02*
X331178D01*
G01X349378Y-125862D02*
X365378D01*
G01Y-115862D02*
X349378D01*
G01D02*
Y-125862D01*
G01X349178Y112338D02*
Y122338D01*
G01X360778Y171938D02*
X355978D01*
G01D02*
Y163938D01*
G01D02*
X360778D01*
G01X352578Y319938D02*
X344578D01*
G01D02*
Y315138D01*
G01D02*
X352578D01*
G01D02*
Y319938D01*
G01X355978Y327538D02*
Y335538D01*
G01D02*
X351178D01*
G01Y327538D02*
X355978D01*
G01X351178Y335538D02*
Y327538D01*
G01X341178Y405538D02*
Y397538D01*
G01D02*
X345978D01*
G01D02*
Y405538D01*
G01D02*
X341178D01*
G01X365378Y-125862D02*
Y-115862D01*
G01X365578Y-49862D02*
X373578D01*
G01D02*
Y-45062D01*
G01X365578D02*
Y-49862D01*
G01X373578Y-36062D02*
X365578D01*
G01D02*
Y-40862D01*
G01D02*
X373578D01*
G01D02*
Y-36062D01*
G01Y-45062D02*
X365578D01*
G01Y-13862D02*
X373578D01*
G01D02*
Y-9062D01*
G01X365578D02*
Y-13862D01*
G01X373578Y-18062D02*
X365578D01*
G01D02*
Y-22862D01*
G01D02*
X373578D01*
G01D02*
Y-18062D01*
G01X365578Y-4862D02*
X373578D01*
G01D02*
Y-62D01*
G01D02*
X365578D01*
G01D02*
Y-4862D01*
G01X373578Y-9062D02*
X365578D01*
G01Y19138D02*
X373578D01*
G01D02*
Y23938D01*
G01D02*
X365578D01*
G01D02*
Y19138D01*
G01X373578Y33938D02*
X365578D01*
G01D02*
Y29138D01*
G01D02*
X373578D01*
G01D02*
Y33938D01*
G01X360778Y163938D02*
Y171938D01*
G01X365978Y327538D02*
Y335538D01*
G01D02*
X361178D01*
G01D02*
Y327538D01*
G01D02*
X365978D01*
G01X375978Y335538D02*
X371178D01*
G01D02*
Y327538D01*
G01D02*
X375978D01*
G01X392178Y-1040D02*
Y-9040D01*
G01D02*
X396978D01*
G01Y-1040D02*
X392178D01*
G01X375978Y327538D02*
Y335538D01*
G01X411578Y-188062D02*
X403578D01*
G01D02*
Y-192862D01*
G01D02*
X411578D01*
G01Y-178062D02*
X403578D01*
G01D02*
Y-182862D01*
G01D02*
X411578D01*
G01X394846Y-87790D02*
X399646D01*
G01D02*
Y-95790D01*
G01D02*
X394846D01*
G01D02*
Y-87790D01*
G01X406838Y-38672D02*
Y-33872D01*
G01D02*
X414838D01*
G01Y-38672D02*
X406838D01*
G01X396978Y-9040D02*
Y-1040D01*
G01X414836Y40068D02*
X406836D01*
G01D02*
Y44868D01*
G01X406962Y29120D02*
Y24320D01*
G01D02*
X398962D01*
G01D02*
Y29120D01*
G01D02*
X406962D01*
G01X406836Y44868D02*
X414836D01*
G01X409300Y50280D02*
X404500D01*
G01D02*
Y58280D01*
G01D02*
X409300D01*
G01D02*
Y50280D01*
G01X395178Y334338D02*
X403178D01*
G01D02*
Y339138D01*
G01X395178D02*
Y334338D01*
G01X403178Y339138D02*
X395178D01*
G01X411578Y-192862D02*
Y-188062D01*
G01Y-182862D02*
Y-178062D01*
G01X430586Y-117414D02*
X422586D01*
G01D02*
Y-112614D01*
G01D02*
X430586D01*
G01X432922Y-67830D02*
X428122D01*
G01D02*
Y-59830D01*
G01D02*
X432922D01*
G01X414712Y-62294D02*
Y-57494D01*
G01D02*
X422712D01*
G01D02*
Y-62294D01*
G01D02*
X414712D01*
G01X422586Y-33872D02*
X430586D01*
G01Y-38672D02*
X422586D01*
G01X414838Y-33872D02*
Y-38672D01*
G01X422586D02*
Y-33872D01*
G01X422710Y-10250D02*
Y-15050D01*
G01D02*
X414710D01*
G01D02*
Y-10250D01*
G01X414578Y-24862D02*
X422578D01*
G01D02*
Y-20062D01*
G01D02*
X414578D01*
G01D02*
Y-24862D01*
G01X425048Y-4838D02*
X420248D01*
G01Y3162D02*
X425048D01*
G01D02*
Y-4838D01*
G01X417174D02*
X412374D01*
G01D02*
Y3162D01*
G01D02*
X417174D01*
G01D02*
Y-4838D01*
G01X414710Y-10250D02*
X422710D01*
G01X420248Y-4838D02*
Y3162D01*
G01X430584Y8572D02*
X422584D01*
G01Y13372D02*
X430584D01*
G01X422584Y21246D02*
X430584D01*
G01Y16446D02*
X422584D01*
G01Y8572D02*
Y13372D01*
G01Y16446D02*
Y21246D01*
G01X414836Y44868D02*
Y40068D01*
G01X417174Y58280D02*
Y50280D01*
G01X412374Y58280D02*
X417174D01*
G01X412374Y50280D02*
Y58280D01*
G01X417174Y50280D02*
X412374D01*
G01X424178Y118538D02*
Y110538D01*
G01D02*
X428978D01*
G01Y118538D02*
X424178D01*
G01X419578Y403138D02*
X427578D01*
G01D02*
Y407938D01*
G01X419578D02*
Y403138D01*
G01X427578Y407938D02*
X419578D01*
G01Y412138D02*
X427578D01*
G01D02*
Y416938D01*
G01D02*
X419578D01*
G01D02*
Y412138D01*
G01X431178Y-137462D02*
Y-145462D01*
G01D02*
X435978D01*
G01D02*
Y-137462D01*
G01D02*
X431178D01*
G01X442178D02*
Y-145462D01*
G01D02*
X446978D01*
G01Y-137462D02*
X442178D01*
G01X430586Y-112614D02*
Y-117414D01*
G01X443870Y-99330D02*
Y-91330D01*
G01X448670Y-99330D02*
X443870D01*
G01X438460Y-93792D02*
X430460D01*
G01X438460Y-88992D02*
Y-93792D01*
G01X430460Y-88992D02*
X438460D01*
G01X430460Y-93792D02*
Y-88992D01*
G01X443870Y-91330D02*
X448670D01*
G01X432922Y-59830D02*
Y-67830D01*
G01X430586Y-33872D02*
Y-38672D01*
G01X443870Y-44210D02*
Y-36210D01*
G01X448670Y-44210D02*
X443870D01*
G01Y-36210D02*
X448670D01*
G01X443870Y-12712D02*
Y-4712D01*
G01X448670Y-12712D02*
X443870D01*
G01X447756Y-20062D02*
X439756D01*
G01D02*
Y-24862D01*
G01D02*
X447756D01*
G01X438458Y5498D02*
Y698D01*
G01D02*
X430458D01*
G01D02*
Y5498D01*
G01D02*
X438458D01*
G01X430460Y-7176D02*
Y-2376D01*
G01D02*
X438460D01*
G01D02*
Y-7176D01*
G01D02*
X430460D01*
G01X443870Y-4712D02*
X448670D01*
G01X430584Y13372D02*
Y8572D01*
G01Y21246D02*
Y16446D01*
G01X442178Y118538D02*
Y110538D01*
G01D02*
X446978D01*
G01X437978D02*
Y118538D01*
G01X433178D02*
Y110538D01*
G01D02*
X437978D01*
G01X428978D02*
Y118538D01*
G01X446978D02*
X442178D01*
G01X437978D02*
X433178D01*
G01X437578Y183138D02*
X445578D01*
G01D02*
Y187938D01*
G01D02*
X437578D01*
G01D02*
Y183138D01*
G01X445578Y197938D02*
X437578D01*
G01D02*
Y193138D01*
G01D02*
X445578D01*
G01D02*
Y197938D01*
G01X437578Y213138D02*
X445578D01*
G01D02*
Y217938D01*
G01X437578D02*
Y213138D01*
G01X445578Y207938D02*
X437578D01*
G01D02*
Y203138D01*
G01D02*
X445578D01*
G01D02*
Y207938D01*
G01Y217938D02*
X437578D01*
G01X446978Y-145462D02*
Y-137462D01*
G01X448670Y-91330D02*
Y-99330D01*
G01X459618Y-83454D02*
X464418D01*
G01Y-91454D02*
X459618D01*
G01D02*
Y-83454D01*
G01X454206Y-81116D02*
Y-85916D01*
G01D02*
X446206D01*
G01D02*
Y-81116D01*
G01D02*
X454206D01*
G01X459618Y-51956D02*
X464418D01*
G01X459618Y-59956D02*
Y-51956D01*
G01X464418Y-59956D02*
X459618D01*
G01X462080Y-46546D02*
X454080D01*
G01X462080Y-41746D02*
Y-46546D01*
G01X454080D02*
Y-41746D01*
G01X451744Y-59958D02*
Y-51958D01*
G01X456544Y-59958D02*
X451744D01*
G01X456544Y-51958D02*
Y-59958D01*
G01X451744Y-51958D02*
X456544D01*
G01X454080Y-41746D02*
X462080D01*
G01Y-33872D02*
Y-38672D01*
G01D02*
X454080D01*
G01Y-33872D02*
X462080D01*
G01X448670Y-36210D02*
Y-44210D01*
G01X454080Y-38672D02*
Y-33872D01*
G01X464418Y-12714D02*
X459618D01*
G01D02*
Y-4714D01*
G01X465756Y-20062D02*
X457756D01*
G01Y-24862D02*
X465756D01*
G01X456544Y-12714D02*
X451744D01*
G01D02*
Y-4714D01*
G01X456544D02*
Y-12714D01*
G01X448670Y-4712D02*
Y-12712D01*
G01X457756Y-20062D02*
Y-24862D01*
G01X447756D02*
Y-20062D01*
G01X459618Y-4714D02*
X464418D01*
G01X451744D02*
X456544D01*
G01X469956Y8572D02*
X461956D01*
G01Y13372D02*
X469956D01*
G01X461956Y8572D02*
Y13372D01*
G01X456546Y10908D02*
X451746D01*
G01D02*
Y18908D01*
G01D02*
X456546D01*
G01D02*
Y10908D01*
G01X446208Y40068D02*
Y44868D01*
G01X454208D02*
Y40068D01*
G01D02*
X446208D01*
G01Y44868D02*
X454208D01*
G01X451408Y68138D02*
X459408D01*
G01D02*
Y72938D01*
G01D02*
X451408D01*
G01D02*
Y68138D01*
G01X460178Y118538D02*
Y110538D01*
G01D02*
X464978D01*
G01X446978D02*
Y118538D01*
G01X455978Y110538D02*
Y118538D01*
G01X451178D02*
Y110538D01*
G01D02*
X455978D01*
G01X464978Y118538D02*
X460178D01*
G01X455978D02*
X451178D01*
G01X474178Y-149462D02*
Y-157462D01*
G01D02*
X478978D01*
G01D02*
Y-149462D01*
G01X465178D02*
Y-157462D01*
G01D02*
X469978D01*
G01D02*
Y-149462D01*
G01X478978D02*
X474178D01*
G01X469978D02*
X465178D01*
G01X472292Y-107202D02*
X467492D01*
G01D02*
Y-99202D01*
G01D02*
X472292D01*
G01D02*
Y-107202D01*
G01X480166Y-83578D02*
X475366D01*
G01D02*
Y-75578D01*
G01X480166D02*
Y-83578D01*
G01X464418Y-83454D02*
Y-91454D01*
G01X480166Y-59832D02*
Y-67832D01*
G01D02*
X475366D01*
G01D02*
Y-59832D01*
G01Y-75578D02*
X480166D01*
G01X475366Y-59832D02*
X480166D01*
G01Y-52082D02*
X475366D01*
G01D02*
Y-44082D01*
G01X480166D02*
Y-52082D01*
G01X464418Y-51956D02*
Y-59956D01*
G01X467492Y-51958D02*
X472292D01*
G01D02*
Y-59958D01*
G01D02*
X467492D01*
G01D02*
Y-51958D01*
G01X475366Y-44082D02*
X480166D01*
G01X467492Y-44210D02*
Y-36210D01*
G01X472292Y-44210D02*
X467492D01*
G01X472292Y-36210D02*
Y-44210D01*
G01X467492Y-36210D02*
X472292D01*
G01X464418Y-4714D02*
Y-12714D01*
G01X469828Y-15050D02*
Y-10250D01*
G01X477828Y-15050D02*
X469828D01*
G01X477828Y-10250D02*
Y-15050D01*
G01X465756Y-24862D02*
Y-20062D01*
G01X477778Y-27662D02*
X485778D01*
G01Y-22862D02*
X477778D01*
G01D02*
Y-27662D01*
G01X469828Y-10250D02*
X477828D01*
G01X469956Y13372D02*
Y8572D01*
G01X472292Y58154D02*
X467492D01*
G01D02*
Y66154D01*
G01X472292D02*
Y58154D01*
G01X467492Y66154D02*
X472292D01*
G01X469178Y118538D02*
Y110538D01*
G01D02*
X473978D01*
G01D02*
Y118538D01*
G01X464978Y110538D02*
Y118538D01*
G01X478178D02*
Y110538D01*
G01D02*
X482978D01*
G01X473978Y118538D02*
X469178D01*
G01X482978D02*
X478178D01*
G01X485578Y223938D02*
X477578D01*
G01D02*
Y219138D01*
G01D02*
X485578D01*
G01X471578Y397138D02*
X479578D01*
G01D02*
Y401938D01*
G01D02*
X471578D01*
G01D02*
Y397138D01*
G01X479578Y421938D02*
X471578D01*
G01D02*
Y417138D01*
G01D02*
X479578D01*
G01D02*
Y421938D01*
G01X471578Y437138D02*
X479578D01*
G01D02*
Y441938D01*
G01D02*
X471578D01*
G01D02*
Y437138D01*
G01Y447138D02*
X479578D01*
G01D02*
Y451938D01*
G01D02*
X471578D01*
G01D02*
Y447138D01*
G01X496578Y-225062D02*
X488578D01*
G01Y-229862D02*
X496578D01*
G01D02*
Y-225062D01*
G01X488578D02*
Y-229862D01*
G01X500178Y-218862D02*
X492978D01*
G01Y-206062D02*
X500178D01*
G01X492978Y-218862D02*
Y-206062D01*
G01X493178Y-189462D02*
X497978D01*
G01X493178Y-181462D02*
Y-189462D01*
G01X488978D02*
Y-181462D01*
G01X484178D02*
Y-189462D01*
G01D02*
X488978D01*
G01X497978Y-181462D02*
X493178D01*
G01X488978D02*
X484178D01*
G01X491178Y-76462D02*
Y-84462D01*
G01X486378D02*
Y-76462D01*
G01X491178Y-84462D02*
X486378D01*
G01Y-76462D02*
X491178D01*
G01X491978Y-63462D02*
Y-55462D01*
G01X487178D02*
Y-63462D01*
G01D02*
X491978D01*
G01Y-55462D02*
X487178D01*
G01Y-35462D02*
Y-43462D01*
G01D02*
X491978D01*
G01D02*
Y-35462D01*
G01D02*
X487178D01*
G01X486978Y-6262D02*
Y-14262D01*
G01D02*
X491778D01*
G01D02*
Y-6262D01*
G01X485778Y-27662D02*
Y-22862D01*
G01X490966Y14036D02*
Y6036D01*
G01X486166D02*
Y14036D01*
G01X490966Y6036D02*
X486166D01*
G01X491778Y-6262D02*
X486978D01*
G01X486166Y14036D02*
X490966D01*
G01X492978Y24138D02*
Y32138D01*
G01X488178D02*
Y24138D01*
G01D02*
X492978D01*
G01Y32138D02*
X488178D01*
G01X482978Y110538D02*
Y118538D01*
G01X485578Y219138D02*
Y223938D01*
G01X505578Y441938D02*
X497578D01*
G01D02*
Y437138D01*
G01D02*
X505578D01*
G01Y451938D02*
X497578D01*
G01D02*
Y447138D01*
G01D02*
X505578D01*
G01X500178Y-206062D02*
Y-218862D01*
G01X497978Y-189462D02*
Y-181462D01*
G01X511662Y-83454D02*
Y-91454D01*
G01X506862Y-83454D02*
X511662D01*
G01X506862Y-91454D02*
Y-83454D01*
G01X511662Y-91454D02*
X506862D01*
G01Y-75706D02*
Y-67706D01*
G01X511662Y-75706D02*
X506862D01*
G01X511662Y-67706D02*
Y-75706D01*
G01X506862Y-67706D02*
X511662D01*
G01X514736Y-59958D02*
Y-51958D01*
G01X519536Y-59958D02*
X514736D01*
G01Y-51958D02*
X519536D01*
G01X501324Y-57494D02*
X509324D01*
G01X501324Y-62294D02*
Y-57494D01*
G01X509324Y-62294D02*
X501324D01*
G01X509324Y-57494D02*
Y-62294D01*
G01X503788Y-44082D02*
Y-52082D01*
G01X498988D02*
Y-44082D01*
G01X503788Y-52082D02*
X498988D01*
G01X506862Y-52084D02*
Y-44084D01*
G01X511662Y-52084D02*
X506862D01*
G01X511662Y-44084D02*
Y-52084D01*
G01X509326Y-38672D02*
X501326D01*
G01X509326Y-33872D02*
Y-38672D01*
G01X501326Y-33872D02*
X509326D01*
G01X501326Y-38672D02*
Y-33872D01*
G01X514736Y-36208D02*
X519536D01*
G01X514736Y-44208D02*
Y-36208D01*
G01X519536Y-44208D02*
X514736D01*
G01X498988Y-44082D02*
X503788D01*
G01X506862Y-44084D02*
X511662D01*
G01X501326Y-15050D02*
Y-10250D01*
G01X509326D02*
Y-15050D01*
G01D02*
X501326D01*
G01X502578Y-25862D02*
X510578D01*
G01D02*
Y-21062D01*
G01D02*
X502578D01*
G01D02*
Y-25862D01*
G01X511662Y-4838D02*
X506862D01*
G01D02*
Y3162D01*
G01D02*
X511662D01*
G01D02*
Y-4838D01*
G01X501326Y-10250D02*
X509326D01*
G01X514736Y18784D02*
Y26784D01*
G01X519536Y18784D02*
X514736D01*
G01Y26784D02*
X519536D01*
G01X503788Y50280D02*
X498988D01*
G01D02*
Y58280D01*
G01D02*
X503788D01*
G01D02*
Y50280D01*
G01X506378Y136738D02*
Y128738D01*
G01D02*
X511178D01*
G01D02*
Y136738D01*
G01D02*
X506378D01*
G01X509178Y202538D02*
Y192538D01*
G01D02*
X525178D01*
G01Y202538D02*
X509178D01*
G01Y218738D02*
Y208738D01*
G01D02*
X525178D01*
G01Y218738D02*
X509178D01*
G01X514178Y320538D02*
Y312538D01*
G01D02*
X518978D01*
G01Y320538D02*
X514178D01*
G01X504978Y414938D02*
Y422938D01*
G01D02*
X500178D01*
G01D02*
Y414938D01*
G01D02*
X504978D01*
G01X505578Y437138D02*
Y441938D01*
G01Y447138D02*
Y451938D01*
G01X525074Y-70168D02*
X517074D01*
G01X525074Y-65368D02*
Y-70168D01*
G01X517074Y-65368D02*
X525074D01*
G01X517074Y-70168D02*
Y-65368D01*
G01Y-78042D02*
Y-73242D01*
G01D02*
X525074D01*
G01D02*
Y-78042D01*
G01D02*
X517074D01*
G01X532946Y-62294D02*
X524946D01*
G01Y-57494D02*
X532946D01*
G01Y-54420D02*
X524946D01*
G01Y-49620D02*
X532946D01*
G01X524946Y-62294D02*
Y-57494D01*
G01Y-54420D02*
Y-49620D01*
G01X519536Y-51958D02*
Y-59958D01*
G01X522610Y-36210D02*
X527410D01*
G01D02*
Y-44210D01*
G01D02*
X522610D01*
G01D02*
Y-36210D01*
G01X519536Y-36208D02*
Y-44208D01*
G01X522778Y-25862D02*
X530778D01*
G01D02*
Y-21062D01*
G01D02*
X522778D01*
G01D02*
Y-25862D01*
G01X532948Y16446D02*
X524948D01*
G01Y21246D02*
X532948D01*
G01X524948Y16446D02*
Y21246D01*
G01X519536Y26784D02*
Y18784D01*
G01X517072Y36994D02*
X525072D01*
G01X517072Y32194D02*
Y36994D01*
G01X525072Y32194D02*
X517072D01*
G01X525072Y36994D02*
Y32194D01*
G01X530978Y101338D02*
Y81738D01*
G01D02*
X556178D01*
G01Y101338D02*
X530978D01*
G01X529578Y136738D02*
Y128738D01*
G01D02*
X534378D01*
G01Y136738D02*
X529578D01*
G01X518178D02*
Y128738D01*
G01D02*
X522978D01*
G01D02*
Y136738D01*
G01D02*
X518178D01*
G01X525178Y192538D02*
Y202538D01*
G01Y208738D02*
Y218738D01*
G01X518978Y312538D02*
Y320538D01*
G01X543158Y-99328D02*
X538358D01*
G01D02*
Y-91328D01*
G01X543158D02*
Y-99328D01*
G01X551032Y-83580D02*
X546232D01*
G01D02*
Y-75580D01*
G01X538358Y-91328D02*
X543158D01*
G01X540822Y-78042D02*
X532822D01*
G01X540822Y-73242D02*
Y-78042D01*
G01X532822Y-73242D02*
X540822D01*
G01X532822Y-78042D02*
Y-73242D01*
G01X551032Y-67830D02*
X546232D01*
G01D02*
Y-59830D01*
G01Y-75580D02*
X551032D01*
G01X546232Y-59830D02*
X551032D01*
G01X532946Y-57494D02*
Y-62294D01*
G01X543158Y-52082D02*
X538358D01*
G01D02*
Y-44082D01*
G01X543158D02*
Y-52082D01*
G01X532946Y-49620D02*
Y-54420D01*
G01X551032Y-52084D02*
X546232D01*
G01D02*
Y-44084D01*
G01X540822Y-38672D02*
X532822D01*
G01X540822Y-33872D02*
Y-38672D01*
G01X532822Y-33872D02*
X540822D01*
G01X532822Y-38672D02*
Y-33872D01*
G01X538358Y-44082D02*
X543158D01*
G01X546232Y-44084D02*
X551032D01*
G01X540696Y-15050D02*
Y-10250D01*
G01X548696D02*
Y-15050D01*
G01D02*
X540696D01*
G01Y-10250D02*
X548696D01*
G01X532948Y21246D02*
Y16446D01*
G01X556570Y8572D02*
X548570D01*
G01Y13372D02*
X556570D01*
G01X548570Y8572D02*
Y13372D01*
G01X543158Y18910D02*
Y10910D01*
G01X538358Y18910D02*
X543158D01*
G01X538358Y10910D02*
Y18910D01*
G01X543158Y10910D02*
X538358D01*
G01X537578Y67138D02*
X545578D01*
G01D02*
Y71938D01*
G01D02*
X537578D01*
G01D02*
Y67138D01*
G01X534378Y128738D02*
Y136738D01*
G01X540778D02*
Y128738D01*
G01D02*
X545578D01*
G01D02*
Y136738D01*
G01D02*
X540778D01*
G01X547778Y287138D02*
Y282338D01*
G01D02*
X555778D01*
G01Y276738D02*
X547778D01*
G01D02*
Y271938D01*
G01D02*
X555778D01*
G01Y287138D02*
X547778D01*
G01X567120Y-117140D02*
X575120D01*
G01X567120Y-112340D02*
Y-117140D01*
G01X575120Y-112340D02*
X567120D01*
G01X551032Y-75580D02*
Y-83580D01*
G01X558908Y-83578D02*
X554108D01*
G01D02*
Y-75578D01*
G01X558908D02*
Y-83578D01*
G01X564320Y-78042D02*
Y-73242D01*
G01D02*
X572320D01*
G01Y-78042D02*
X564320D01*
G01X564444Y-65368D02*
Y-70168D01*
G01D02*
X556444D01*
G01Y-65368D02*
X564444D01*
G01X551032Y-59830D02*
Y-67830D01*
G01X554108Y-75578D02*
X558908D01*
G01X556444Y-70168D02*
Y-65368D01*
G01X564444Y-41746D02*
Y-46546D01*
G01D02*
X556444D01*
G01D02*
Y-41746D01*
G01X551032Y-44084D02*
Y-52084D01*
G01X556444Y-41746D02*
X564444D01*
G01X566782Y-28460D02*
X561982D01*
G01X566782Y-20460D02*
Y-28460D01*
G01X561982D02*
Y-20460D01*
G01D02*
X566782D01*
G01X556444Y-2376D02*
X564444D01*
G01Y-7176D02*
X556444D01*
G01X564444Y-2376D02*
Y-7176D01*
G01X556444D02*
Y-2376D01*
G01X556570Y13372D02*
Y8572D01*
G01X564446Y32194D02*
X556446D01*
G01X564446Y36994D02*
Y32194D01*
G01X556446Y36994D02*
X564446D01*
G01X564444Y24320D02*
X556444D01*
G01X564444Y29120D02*
Y24320D01*
G01X556444Y29120D02*
X564444D01*
G01X556446Y32194D02*
Y36994D01*
G01X556444Y24320D02*
Y29120D01*
G01X564320Y55816D02*
Y60616D01*
G01X572320Y55816D02*
X564320D01*
G01X561982Y50404D02*
X566782D01*
G01D02*
Y42404D01*
G01D02*
X561982D01*
G01D02*
Y50404D01*
G01X564320Y60616D02*
X572320D01*
G01X556178Y81738D02*
Y101338D01*
G01X564378Y136738D02*
Y128738D01*
G01D02*
X569178D01*
G01Y136738D02*
X564378D01*
G01X552578D02*
Y128738D01*
G01D02*
X557378D01*
G01D02*
Y136738D01*
G01D02*
X552578D01*
G01X572178Y247338D02*
X564178D01*
G01D02*
Y242538D01*
G01D02*
X572178D01*
G01X555778Y282338D02*
Y287138D01*
G01Y271938D02*
Y276738D01*
G01X556978Y312538D02*
Y320538D01*
G01X552178D02*
Y312538D01*
G01D02*
X556978D01*
G01Y320538D02*
X552178D01*
G01X575120Y-117140D02*
Y-112340D01*
G01X572320Y-73242D02*
Y-78042D01*
G01X573518Y-26862D02*
X581518D01*
G01D02*
Y-22062D01*
G01D02*
X573518D01*
G01D02*
Y-26862D01*
G01X572320Y60616D02*
Y55816D01*
G01X576178Y136738D02*
Y128738D01*
G01D02*
X580978D01*
G01D02*
Y136738D01*
G01X569178Y128738D02*
Y136738D01*
G01X580978D02*
X576178D01*
G01X572178Y242538D02*
Y247338D01*
G01X591778D02*
X583778D01*
G01D02*
Y242538D01*
G01D02*
X591778D01*
G01X574578Y386138D02*
X582578D01*
G01D02*
Y390938D01*
G01X574578D02*
Y386138D01*
G01Y375738D02*
X582578D01*
G01D02*
Y380538D01*
G01D02*
X574578D01*
G01D02*
Y375738D01*
G01X582578Y390938D02*
X574578D01*
G01X594178Y-219462D02*
X598978D01*
G01D02*
Y-211462D01*
G01D02*
X594178D01*
G01D02*
Y-219462D01*
G01X600178Y-189062D02*
Y-201862D01*
G01D02*
X592978D01*
G01Y-189062D02*
X600178D01*
G01X592978Y-201862D02*
Y-189062D01*
G01X605578Y-156462D02*
X589578D01*
G01Y-166462D02*
X605578D01*
G01X589578Y-156462D02*
Y-166462D01*
G01X598578Y-98462D02*
X588578D01*
G01Y-114462D02*
X598578D01*
G01D02*
Y-98462D01*
G01X588578D02*
Y-114462D01*
G01X601578Y-27062D02*
Y-31862D01*
G01D02*
X609578D01*
G01Y-27062D02*
X601578D01*
G01X587978Y136738D02*
Y128738D01*
G01D02*
X592778D01*
G01D02*
Y136738D01*
G01D02*
X587978D01*
G01X591778Y242538D02*
Y247338D01*
G01X593578Y280138D02*
X601578D01*
G01D02*
Y284938D01*
G01D02*
X593578D01*
G01X601578Y275938D02*
X593578D01*
G01Y271138D02*
X601578D01*
G01D02*
Y275938D01*
G01X593578Y284938D02*
Y280138D01*
G01Y275938D02*
Y271138D01*
G01Y298138D02*
X601578D01*
G01D02*
Y302938D01*
G01X593578Y289138D02*
X601578D01*
G01D02*
Y293938D01*
G01D02*
X593578D01*
G01Y302938D02*
Y298138D01*
G01Y293938D02*
Y289138D01*
G01X601578Y302938D02*
X593578D01*
G01Y307138D02*
X601578D01*
G01D02*
Y311938D01*
G01D02*
X593578D01*
G01D02*
Y307138D01*
G01X605578Y-166462D02*
Y-156462D01*
G01X627978Y-98062D02*
X615178D01*
G01D02*
Y-90862D01*
G01D02*
X627978D01*
G01X609578Y-31862D02*
Y-27062D01*
G01X613578Y77538D02*
Y67538D01*
G01D02*
X629578D01*
G01Y77538D02*
X613578D01*
G01X613178Y231538D02*
Y215538D01*
G01D02*
X623178D01*
G01Y231538D02*
X613178D01*
G01X627978Y-90862D02*
Y-98062D01*
G01X643778Y6236D02*
X635778D01*
G01D02*
Y1436D01*
G01D02*
X643778D01*
G01Y15236D02*
X635778D01*
G01D02*
Y10436D01*
G01D02*
X643778D01*
G01X620578Y62938D02*
Y58138D01*
G01D02*
X628578D01*
G01D02*
Y62938D01*
G01X629578Y67538D02*
Y77538D01*
G01X628578Y62938D02*
X620578D01*
G01X623178Y215538D02*
Y231538D01*
G01X648378Y400338D02*
X635578D01*
G01D02*
Y407538D01*
G01D02*
X648378D01*
G01X634578Y450138D02*
X642578D01*
G01Y454938D02*
X634578D01*
G01D02*
Y450138D01*
G01X639978Y468338D02*
X631978D01*
G01Y463538D02*
X639978D01*
G01X631978Y468338D02*
Y463538D01*
G01X653578Y-96462D02*
Y-112462D01*
G01D02*
X663578D01*
G01X644178Y-98462D02*
Y-106462D01*
G01D02*
X648978D01*
G01D02*
Y-98462D01*
G01D02*
X644178D01*
G01X663578Y-96462D02*
X653578D01*
G01X647178Y-7462D02*
Y-15462D01*
G01D02*
X651978D01*
G01D02*
Y-7462D01*
G01X643778Y1436D02*
Y6236D01*
G01X651978Y-7462D02*
X647178D01*
G01X643778Y10436D02*
Y15236D01*
G01X654178Y101538D02*
Y93538D01*
G01D02*
X658978D01*
G01Y101538D02*
X654178D01*
G01X651178Y207538D02*
Y199538D01*
G01D02*
X655978D01*
G01Y207538D02*
X651178D01*
G01X657578Y275938D02*
X649578D01*
G01D02*
Y271138D01*
G01D02*
X657578D01*
G01Y284938D02*
X649578D01*
G01D02*
Y280138D01*
G01D02*
X657578D01*
G01Y293938D02*
X649578D01*
G01D02*
Y289138D01*
G01D02*
X657578D01*
G01X649578Y302938D02*
Y298138D01*
G01D02*
X657578D01*
G01Y302938D02*
X649578D01*
G01X657578Y311938D02*
X649578D01*
G01D02*
Y307138D01*
G01D02*
X657578D01*
G01X648378Y407538D02*
Y400338D01*
G01X637978Y426338D02*
Y421538D01*
G01D02*
X645978D01*
G01D02*
Y426338D01*
G01X637978Y412538D02*
X645978D01*
G01D02*
Y417338D01*
G01D02*
X637978D01*
G01D02*
Y412538D01*
G01X645978Y426338D02*
X637978D01*
G01Y439538D02*
X645978D01*
G01D02*
Y444338D01*
G01X637978D02*
Y439538D01*
G01X645978Y435338D02*
X637978D01*
G01D02*
Y430538D01*
G01D02*
X645978D01*
G01D02*
Y435338D01*
G01X642578Y450138D02*
Y454938D01*
G01X645978Y444338D02*
X637978D01*
G01X639978Y463538D02*
Y468338D01*
G01X663578Y-112462D02*
Y-96462D01*
G01X658578Y66138D02*
X666578D01*
G01D02*
Y70938D01*
G01D02*
X658578D01*
G01D02*
Y66138D01*
G01Y79938D02*
Y75138D01*
G01D02*
X666578D01*
G01D02*
Y79938D01*
G01D02*
X658578D01*
G01X658978Y93538D02*
Y101538D01*
G01X673978Y207538D02*
X669178D01*
G01D02*
Y199538D01*
G01D02*
X673978D01*
G01X655978D02*
Y207538D01*
G01X660178D02*
Y199538D01*
G01D02*
X664978D01*
G01D02*
Y207538D01*
G01D02*
X660178D01*
G01X657578Y271138D02*
Y275938D01*
G01Y280138D02*
Y284938D01*
G01Y289138D02*
Y293938D01*
G01Y298138D02*
Y302938D01*
G01Y307138D02*
Y311938D01*
G01X684578Y70938D02*
X676578D01*
G01D02*
Y66138D01*
G01D02*
X684578D01*
G01D02*
Y70938D01*
G01X676578Y75138D02*
X684578D01*
G01D02*
Y79938D01*
G01X676578D02*
Y75138D01*
G01X684578Y79938D02*
X676578D01*
G01X681178Y136938D02*
Y128938D01*
G01D02*
X685978D01*
G01D02*
Y136938D01*
G01D02*
X681178D01*
G01X673978Y199538D02*
Y207538D01*
G01X682978Y199538D02*
Y207538D01*
G01D02*
X678178D01*
G01D02*
Y199538D01*
G01D02*
X682978D01*
G01X678078Y414038D02*
X675878D01*
G01D02*
Y417838D01*
G01D02*
X678078D01*
G01D02*
Y414038D01*
G01X673578Y443138D02*
X681578D01*
G01D02*
Y447938D01*
G01D02*
X673578D01*
G01D02*
Y443138D01*
G01X699178Y198538D02*
X703978D01*
G01D02*
Y206538D01*
G01D02*
X699178D01*
G01D02*
Y198538D01*
G01X691178Y269938D02*
Y265138D01*
G01D02*
X699178D01*
G01D02*
Y269938D01*
G01D02*
X691178D01*
G01X699178Y278938D02*
X691178D01*
G01D02*
Y274138D01*
G01D02*
X699178D01*
G01D02*
Y278938D01*
G01X691178Y287938D02*
Y283138D01*
G01D02*
X699178D01*
G01D02*
Y287938D01*
G01X691178Y305938D02*
Y301138D01*
G01D02*
X699178D01*
G01D02*
Y305938D01*
G01Y296938D02*
X691178D01*
G01D02*
Y292138D01*
G01D02*
X699178D01*
G01D02*
Y296938D01*
G01Y287938D02*
X691178D01*
G01X699178Y314938D02*
X691178D01*
G01D02*
Y310138D01*
G01D02*
X699178D01*
G01D02*
Y314938D01*
G01Y305938D02*
X691178D01*
G01Y323938D02*
Y319138D01*
G01D02*
X699178D01*
G01D02*
Y323938D01*
G01D02*
X691178D01*
G01X693578Y438138D02*
X701578D01*
G01D02*
Y442938D01*
G01X693578D02*
Y438138D01*
G01X701578Y442938D02*
X693578D01*
G01X726168Y-280942D02*
G03X718294Y-273068I-7874J0D01*
G01X709978Y196138D02*
Y208938D01*
G01X717178D02*
Y196138D01*
G01D02*
X709978D01*
G01X723578Y194538D02*
X733578D01*
G01X723578Y210538D02*
Y194538D01*
G01X709978Y208938D02*
X717178D01*
G01X733578Y210538D02*
X723578D01*
G01X708578Y392538D02*
Y376538D01*
G01D02*
X718578D01*
G01D02*
Y392538D01*
G01D02*
X708578D01*
G01X711178Y410538D02*
Y402538D01*
G01D02*
X715978D01*
G01D02*
Y410538D01*
G01D02*
X711178D01*
G01X893098Y-314800D02*
Y-369524D01*
X889160Y-373462D01*
X730106D01*
X726168Y-369524D01*
Y-280942D01*
G01X730178Y-373500D02*
X889078D01*
G01X726178Y-300900D02*
Y-369500D01*
G01D02*
X730178Y-373500D01*
G01X751578Y20538D02*
X735578D01*
G01Y10538D02*
X751578D01*
G01X735578Y20538D02*
Y10538D01*
G01X741378Y56938D02*
Y53338D01*
G01X739578Y56938D02*
X743378D01*
G01Y53338D02*
X739578D01*
G01D02*
Y56938D01*
G01X741378Y71738D02*
Y68138D01*
G01X739578Y71738D02*
X743378D01*
G01Y68138D02*
X739578D01*
G01D02*
Y71738D01*
G01X726578Y70538D02*
G03I3000J0D01*
G01X732392Y69498D02*
X726764D01*
G01X730066Y73498D02*
X729090D01*
G01X740378Y87738D02*
Y91338D01*
G01X742378Y87738D02*
X738578D01*
G01D02*
Y91338D01*
G01D02*
X742378D01*
G01X738578Y194538D02*
X748578D01*
G01X738578Y210538D02*
Y194538D01*
G01X733578D02*
Y210538D01*
G01X748578D02*
X738578D01*
G01X737178Y266138D02*
X745178D01*
G01X737178Y270938D02*
Y266138D01*
G01X745178Y270938D02*
X737178D01*
G01X745178Y280938D02*
X737178D01*
G01Y276138D02*
X745178D01*
G01X737178Y285138D02*
X745178D01*
G01X737178Y280938D02*
Y276138D01*
G01Y289938D02*
Y285138D01*
G01Y294138D02*
X745178D01*
G01Y298938D02*
X737178D01*
G01X745178Y289938D02*
X737178D01*
G01Y298938D02*
Y294138D01*
G01X758000Y-1608501D02*
X759500Y-1610167D01*
X761250Y-1611167D01*
X763500Y-1611500D01*
X765750Y-1610833D01*
X767500Y-1609500D01*
X768750Y-1607167D01*
X769000Y-1604500D01*
X768500Y-1601834D01*
X767250Y-1600167D01*
X765500Y-1598834D01*
X763750Y-1598500D01*
X762000Y-1598834D01*
X759750Y-1600167D01*
X760500Y-1591500D01*
X767250D01*
G01X798000Y-1611500D02*
Y-1591500D01*
X803000D01*
X805000Y-1592500D01*
X806500Y-1593833D01*
X807750Y-1595833D01*
X808750Y-1598167D01*
X809000Y-1601500D01*
X808750Y-1604834D01*
X807750Y-1607167D01*
X806500Y-1609167D01*
X805000Y-1610500D01*
X803000Y-1611500D01*
X798000D01*
G01X828500D02*
X818500D01*
Y-1591500D01*
X828500D01*
G01X824500Y-1601166D02*
X818500D01*
G01X845000Y-1601500D02*
X850000D01*
Y-1607500D01*
X848500Y-1609500D01*
X846750Y-1610833D01*
X844250Y-1611500D01*
X841750Y-1610833D01*
X840000Y-1609500D01*
X838500Y-1607500D01*
X837500Y-1605167D01*
X837000Y-1602500D01*
Y-1600167D01*
X837500Y-1598167D01*
X838500Y-1595833D01*
X840000Y-1593833D01*
X841500Y-1592500D01*
X843500Y-1591500D01*
X845250D01*
X847250Y-1592167D01*
X848750Y-1593500D01*
G01X858500Y-1611500D02*
Y-1591500D01*
X864750D01*
X866750Y-1592500D01*
X868000Y-1593833D01*
X868500Y-1596500D01*
X868000Y-1599167D01*
X866500Y-1600833D01*
X864750Y-1601834D01*
X858500D01*
G01X864750D02*
X868500Y-1611500D01*
G01X888500D02*
X878500D01*
Y-1591500D01*
X888500D01*
G01X884500Y-1601166D02*
X878500D01*
G01X908500Y-1611500D02*
X898500D01*
Y-1591500D01*
X908500D01*
G01X904500Y-1601166D02*
X898500D01*
G01X748372Y-256462D02*
Y-248462D01*
G01X743572D02*
Y-256462D01*
G01D02*
X748372D01*
G01X758372D02*
Y-248462D01*
G01X753572D02*
Y-256462D01*
G01D02*
X758372D01*
G01X748372Y-248462D02*
X743572D01*
G01X758372D02*
X753572D01*
G01X751578Y10538D02*
Y20538D01*
G01X750578Y29938D02*
X742578D01*
G01D02*
Y25138D01*
G01D02*
X750578D01*
G01D02*
Y29938D01*
G01Y38938D02*
X742578D01*
G01D02*
Y34138D01*
G01D02*
X750578D01*
G01D02*
Y38938D01*
G01X753178Y51738D02*
X753778Y51138D01*
G01X743978Y51738D02*
X743378Y51138D01*
G01Y56938D02*
Y53338D01*
G01X753178Y73338D02*
Y51738D01*
G01D02*
X743978D01*
G01D02*
Y73338D01*
G01X753778Y73938D02*
Y51138D01*
G01D02*
X743378D01*
G01D02*
Y73938D01*
G01X757578Y76538D02*
G03I3000J0D01*
G01X755778Y64338D02*
Y60738D01*
G01X753778Y73938D02*
X753178Y73338D01*
G01X743378Y73938D02*
X743978Y73338D01*
G01X743378Y71738D02*
Y68138D01*
G01X753778Y64338D02*
X757578D01*
G01D02*
Y60738D01*
G01D02*
X753778D01*
G01D02*
Y64338D01*
G01X743978Y73338D02*
X753178D01*
G01X743378Y73938D02*
X753778D01*
G01X763420Y77498D02*
X757736D01*
G01X754778Y80338D02*
Y83938D01*
G01X742378Y78138D02*
X742978Y78738D01*
G01X752778Y78138D02*
X752178Y78738D01*
G01X756578Y80338D02*
X752778D01*
G01D02*
Y83938D01*
G01D02*
X756578D01*
G01D02*
Y80338D01*
G01X742378Y91338D02*
Y87738D01*
G01X752178Y78738D02*
X742978D01*
G01D02*
Y100338D01*
G01X752178D02*
Y78738D01*
G01X752778Y78138D02*
X742378D01*
G01D02*
Y100938D01*
G01X752778D02*
Y78138D01*
G01X754778Y95138D02*
Y98738D01*
G01X742978Y100338D02*
X742378Y100938D01*
G01X752178Y100338D02*
X752778Y100938D01*
G01X756578Y95138D02*
X752778D01*
G01D02*
Y98738D01*
G01D02*
X756578D01*
G01D02*
Y95138D01*
G01X742978Y100338D02*
X752178D01*
G01X742378Y100938D02*
X752778D01*
G01X748578Y194538D02*
Y210538D01*
G01X753578Y194538D02*
X763578D01*
G01X753578Y210538D02*
Y194538D01*
G01X763578Y210538D02*
X753578D01*
G01X745178Y266138D02*
Y270938D01*
G01Y276138D02*
Y280938D01*
G01Y285138D02*
Y289938D01*
G01Y294138D02*
Y298938D01*
G01X775500Y-1546000D02*
X773500Y-1546667D01*
X772000Y-1548333D01*
X771000Y-1550333D01*
X770250Y-1553000D01*
X770000Y-1556000D01*
X770250Y-1559000D01*
X771000Y-1561667D01*
X772000Y-1563667D01*
X773500Y-1565333D01*
X775500Y-1566000D01*
X777500Y-1565333D01*
X779000Y-1563667D01*
X780000Y-1561667D01*
X780750Y-1559000D01*
X781000Y-1556000D01*
X780750Y-1553000D01*
X780000Y-1550333D01*
X779000Y-1548333D01*
X777500Y-1546667D01*
X775500Y-1546000D01*
G01X795500Y-1566667D02*
X795000Y-1566333D01*
Y-1565667D01*
X795500Y-1565333D01*
X796000Y-1565667D01*
Y-1566333D01*
X795500Y-1566667D01*
G01X815500Y-1546000D02*
X813500Y-1546667D01*
X812000Y-1548333D01*
X811000Y-1550333D01*
X810250Y-1553000D01*
X810000Y-1556000D01*
X810250Y-1559000D01*
X811000Y-1561667D01*
X812000Y-1563667D01*
X813500Y-1565333D01*
X815500Y-1566000D01*
X817500Y-1565333D01*
X819000Y-1563667D01*
X820000Y-1561667D01*
X820750Y-1559000D01*
X821000Y-1556000D01*
X820750Y-1553000D01*
X820000Y-1550333D01*
X819000Y-1548333D01*
X817500Y-1546667D01*
X815500Y-1546000D01*
G01X835500D02*
X833500Y-1546667D01*
X832000Y-1548333D01*
X831000Y-1550333D01*
X830250Y-1553000D01*
X830000Y-1556000D01*
X830250Y-1559000D01*
X831000Y-1561667D01*
X832000Y-1563667D01*
X833500Y-1565333D01*
X835500Y-1566000D01*
X837500Y-1565333D01*
X839000Y-1563667D01*
X840000Y-1561667D01*
X840750Y-1559000D01*
X841000Y-1556000D01*
X840750Y-1553000D01*
X840000Y-1550333D01*
X839000Y-1548333D01*
X837500Y-1546667D01*
X835500Y-1546000D01*
G01X850000Y-1563001D02*
X851500Y-1564667D01*
X853250Y-1565667D01*
X855500Y-1566000D01*
X857750Y-1565333D01*
X859500Y-1564000D01*
X860750Y-1561667D01*
X861000Y-1559000D01*
X860500Y-1556334D01*
X859250Y-1554667D01*
X857500Y-1553334D01*
X855750Y-1553000D01*
X854000Y-1553334D01*
X851750Y-1554667D01*
X852500Y-1546000D01*
X859250D01*
G01X873250Y-1550333D02*
X874500Y-1546000D01*
G01X877750D02*
X876500Y-1550333D01*
G01X775578Y96538D02*
Y80538D01*
G01D02*
X785578D01*
G01X766178Y94538D02*
Y86538D01*
G01D02*
X770978D01*
G01D02*
Y94538D01*
G01X785578Y96538D02*
X775578D01*
G01X770978Y94538D02*
X766178D01*
G01X772978Y195538D02*
Y203538D01*
G01X768178Y195538D02*
X772978D01*
G01X763578Y194538D02*
Y210538D01*
G01X768178Y203538D02*
Y195538D01*
G01X772978Y203538D02*
X768178D01*
G01X782868Y-256462D02*
Y-248462D01*
G01X778068D02*
Y-256462D01*
G01D02*
X782868D01*
G01X792868D02*
Y-248462D01*
G01X788068D02*
Y-256462D01*
G01D02*
X792868D01*
G01X782868Y-248462D02*
X778068D01*
G01X792868D02*
X788068D01*
G01X789444Y-149176D02*
G03I24000J0D01*
G01X793978Y-5662D02*
Y2338D01*
G01D02*
X789178D01*
G01D02*
Y-5662D01*
G01D02*
X793978D01*
G01X791078Y17938D02*
X783078D01*
G01D02*
Y13138D01*
G01D02*
X791078D01*
G01D02*
Y17938D01*
G01X785178Y71938D02*
Y59138D01*
G01D02*
X777978D01*
G01D02*
Y71938D01*
G01D02*
X785178D01*
G01X794978Y67538D02*
X790178D01*
G01D02*
Y59538D01*
G01D02*
X794978D01*
G01X785578Y80538D02*
Y96538D01*
G01X790178Y93938D02*
Y85938D01*
G01D02*
X794978D01*
G01Y93938D02*
X790178D01*
G01X789444Y138424D02*
G03I24000J0D01*
G01X781978Y195538D02*
Y203538D01*
G01X777178D02*
Y195538D01*
G01D02*
X781978D01*
G01Y203538D02*
X777178D01*
G01X811364Y-256462D02*
Y-248462D01*
G01X806564Y-256462D02*
X811364D01*
G01X806564Y-248462D02*
Y-256462D01*
G01X811364Y-248462D02*
X806564D01*
G01X810610Y71026D02*
X814546D01*
G01X810610Y64726D02*
Y71026D01*
G01X814546Y64726D02*
X810610D01*
G01X822420Y71814D02*
X802736D01*
G01X807066Y70238D02*
X810610D01*
G01X807066Y71026D02*
Y64726D01*
G01X803130Y71026D02*
X807066D01*
G01X803130Y64726D02*
Y71026D01*
G01X807066Y64726D02*
X803130D01*
G01X802736Y71814D02*
Y81262D01*
G01Y71814D02*
X801160Y70238D01*
G01X803130D02*
X801160D01*
G01D02*
Y82838D01*
G01X794978Y59538D02*
Y67538D01*
G01X803918Y73782D02*
G03I1180J0D01*
G01X806244Y73498D02*
X803952D01*
G01X802736Y81262D02*
X822420D01*
G01X807066Y82838D02*
X818090D01*
G01X807066Y88350D02*
Y82050D01*
G01X803130Y88350D02*
X807066D01*
G01X803130Y82050D02*
Y88350D01*
G01X807066Y82050D02*
X803130D01*
G01X802736Y81262D02*
X801160Y82838D01*
G01D02*
X803130D01*
G01X794978Y85938D02*
Y93938D01*
G01X821364Y-256462D02*
Y-248462D01*
G01X816564D02*
Y-256462D01*
G01D02*
X821364D01*
G01Y-248462D02*
X816564D01*
G01X822026Y71026D02*
Y64726D01*
G01X818090Y71026D02*
X822026D01*
G01X818090Y64726D02*
Y71026D01*
G01X822026Y64726D02*
X818090D01*
G01X814546Y71026D02*
Y64726D01*
G01X822420Y81262D02*
Y71814D01*
G01X823996Y70238D02*
X822420Y71814D01*
G01X822026Y70238D02*
X823996D01*
G01D02*
Y82838D01*
G01X814546Y70238D02*
X818090D01*
G01X822026Y88350D02*
Y82050D01*
G01X818090Y88350D02*
X822026D01*
G01X818090Y82050D02*
Y88350D01*
G01X822026Y82050D02*
X818090D01*
G01X823996Y82838D02*
X822420Y81262D01*
G01X823996Y82838D02*
X822026D01*
G01X822578Y99138D02*
X830578D01*
G01Y103938D02*
X822578D01*
G01D02*
Y99138D01*
G01X845934Y-248462D02*
Y-256462D01*
G01D02*
X850734D01*
G01Y-248462D02*
X845934D01*
G01X840178Y61538D02*
X844978D01*
G01D02*
Y69538D01*
G01D02*
X840178D01*
G01D02*
Y61538D01*
G01X844978Y79538D02*
Y87538D01*
G01D02*
X840178D01*
G01Y79538D02*
X844978D01*
G01X840178Y87538D02*
Y79538D01*
G01X830178Y87538D02*
Y79538D01*
G01D02*
X834978D01*
G01D02*
Y87538D01*
G01D02*
X830178D01*
G01X848578Y103938D02*
X840578D01*
G01Y99138D02*
X848578D01*
G01X830578D02*
Y103938D01*
G01X840578D02*
Y99138D01*
G01X850734Y-256462D02*
Y-248462D01*
G01X860734Y-256462D02*
Y-248462D01*
G01X855934D02*
Y-256462D01*
G01D02*
X860734D01*
G01Y-248462D02*
X855934D01*
G01X853638Y54242D02*
G03I3000J0D01*
G01X859544Y53498D02*
X853732D01*
G01X858444Y69036D02*
X861594D01*
G01X863562D02*
X866712D01*
G01X856476D02*
X854118D01*
G01D02*
Y80040D01*
G01X871038Y70994D02*
X854118D01*
G01X858444Y69038D02*
Y65100D01*
X856476D01*
Y69038D01*
X858444D01*
G01X863562D02*
Y65100D01*
X861594D01*
Y69038D01*
X863562D01*
G01X858444Y80040D02*
X866712D01*
G01X854118D02*
X856476D01*
G01X854118Y78082D02*
X871038D01*
G01X858444Y83976D02*
Y80038D01*
X856476D01*
Y83976D01*
X858444D01*
G01X848578Y99138D02*
Y103938D01*
G01X858578Y95138D02*
X866578D01*
G01Y99938D02*
X858578D01*
G01D02*
Y95138D01*
G01X879558Y-248482D02*
Y-256482D01*
G01D02*
X884358D01*
G01X874356Y-256462D02*
Y-248462D01*
G01X869556D02*
Y-256462D01*
G01D02*
X874356D01*
G01X884358Y-248482D02*
X879558D01*
G01X874356Y-248462D02*
X869556D01*
G01X868680Y69036D02*
X871038D01*
G01D02*
Y80040D01*
G01X868680Y69038D02*
Y65100D01*
X866712D01*
Y69038D01*
X868680D01*
G01X871038Y80040D02*
X868680D01*
G01Y83976D02*
Y80038D01*
X866712D01*
Y83976D01*
X868680D01*
G01X866578Y95138D02*
Y99938D01*
G01X889078Y-373500D02*
X893078Y-369500D01*
G01D02*
Y-314800D01*
G01X908058D02*
G03X893098I-7480J0D01*
G01X900578Y-307300D02*
G03X893078Y-314800I0J-7500D01*
G01X884358Y-256482D02*
Y-248482D01*
G01X894978Y-249862D02*
Y-237062D01*
G01X902178Y-249862D02*
X894978D01*
G01Y-237062D02*
X902178D01*
G01X996248Y-287438D02*
Y-369524D01*
X992310Y-373462D01*
X911996D01*
X908058Y-369524D01*
Y-314800D01*
G01X912078Y-373500D02*
X992178D01*
G01X908078Y-369500D02*
X912078Y-373500D01*
G01X908078Y-314800D02*
Y-369500D01*
G01Y-314800D02*
G03X900578Y-307300I-7500J0D01*
G01X912978Y-250462D02*
Y-242462D01*
G01D02*
X908178D01*
G01Y-250462D02*
X912978D01*
G01X902178Y-237062D02*
Y-249862D01*
G01X908178Y-242462D02*
Y-250462D01*
G01X913578Y220938D02*
Y212938D01*
G01D02*
X918378D01*
G01Y220938D02*
X913578D01*
G01X921978Y-250462D02*
Y-242462D01*
G01D02*
X917178D01*
G01D02*
Y-250462D01*
G01D02*
X921978D01*
G01X931578Y220938D02*
Y212938D01*
G01D02*
X936378D01*
G01X922578Y220938D02*
Y212938D01*
G01D02*
X927378D01*
G01D02*
Y220938D01*
G01X918378Y212938D02*
Y220938D01*
G01X936378D02*
X931578D01*
G01X927378D02*
X922578D01*
G01X921578Y296138D02*
X929578D01*
G01D02*
Y300938D01*
G01D02*
X921578D01*
G01D02*
Y296138D01*
G01X927178Y316538D02*
Y308538D01*
G01D02*
X931978D01*
G01D02*
Y316538D01*
G01D02*
X927178D01*
G01X921578Y324138D02*
X929578D01*
G01D02*
Y328938D01*
G01D02*
X921578D01*
G01D02*
Y324138D01*
G01Y334138D02*
X929578D01*
G01D02*
Y338938D01*
G01X921578D02*
Y334138D01*
G01X929578Y338938D02*
X921578D01*
G01X936378Y212938D02*
Y220938D01*
G01X994178Y299838D02*
X963378D01*
G01X955178Y305738D02*
Y302538D01*
G01D02*
X963378D01*
G01Y299838D02*
Y338438D01*
G01Y315738D02*
X955178D01*
G01D02*
Y312538D01*
G01D02*
X963378D01*
G01Y305738D02*
X955178D01*
G01X963378Y335738D02*
X955178D01*
G01D02*
Y332538D01*
G01D02*
X963378D01*
G01Y325738D02*
X955178D01*
G01D02*
Y322538D01*
G01D02*
X963378D01*
G01Y338438D02*
X994178D01*
G01X980058Y-252822D02*
Y-244822D01*
G01D02*
X975258D01*
G01D02*
Y-252822D01*
G01D02*
X980058D01*
G01X975978Y214538D02*
Y222538D01*
G01X971178D02*
Y214538D01*
G01D02*
X975978D01*
G01Y222538D02*
X971178D01*
G01X968664Y334092D02*
G03I3000J0D01*
G01X974604Y333498D02*
X968724D01*
G01X990578Y457538D02*
X974578D01*
G01Y447538D02*
X990578D01*
G01X974578Y457538D02*
Y447538D01*
G01X992178Y-373500D02*
X996178Y-369500D01*
G01D02*
Y-300900D01*
G01X1024988Y-287438D02*
G03X996248I-14370J0D01*
G01X1002378Y305738D02*
Y302538D01*
G01D02*
X994178D01*
G01Y338438D02*
Y299838D01*
G01Y305738D02*
X1002378D01*
G01X994178Y315738D02*
X1002378D01*
G01D02*
Y312538D01*
G01D02*
X994178D01*
G01Y325738D02*
X1002378D01*
G01D02*
Y322538D01*
G01D02*
X994178D01*
G01Y335738D02*
X1002378D01*
G01D02*
Y332538D01*
G01D02*
X994178D01*
G01X997578Y410938D02*
Y406138D01*
G01D02*
X1005578D01*
G01Y410938D02*
X997578D01*
G01X992978Y431538D02*
Y439538D01*
G01D02*
X988178D01*
G01D02*
Y431538D01*
G01D02*
X992978D01*
G01X990578Y447538D02*
Y457538D01*
G01X1025578Y405938D02*
X1017578D01*
G01D02*
Y401138D01*
G01D02*
X1025578D01*
G01X1005578Y406138D02*
Y410938D01*
G01X1080106Y-338028D02*
X1032862D01*
G01X1024988Y-330154D02*
G03X1032862Y-338028I7874J0D01*
G01X1024988Y-330154D02*
Y-287438D01*
G01X1034444Y162624D02*
G03I24000J0D01*
G01X1022178Y335538D02*
Y327538D01*
G01D02*
X1026978D01*
G01D02*
Y335538D01*
G01D02*
X1022178D01*
G01X1034378Y379338D02*
X1042378D01*
G01Y384138D02*
X1034378D01*
G01D02*
Y379338D01*
G01X1025578Y401138D02*
Y405938D01*
G01X1023278Y434638D02*
X1025478D01*
G01D02*
Y430838D01*
G01D02*
X1023278D01*
G01D02*
Y434638D01*
G01X1039444Y-161376D02*
G03I24000J0D01*
G01X1046578Y224138D02*
X1054578D01*
G01D02*
Y228938D01*
G01D02*
X1046578D01*
G01D02*
Y224138D01*
G01X1042378Y379338D02*
Y384138D01*
G01X1055378Y409138D02*
Y404338D01*
G01D02*
X1063378D01*
G01X1055378Y422338D02*
X1063378D01*
G01X1055378Y427138D02*
Y422338D01*
G01Y413338D02*
X1063378D01*
G01Y418138D02*
X1055378D01*
G01D02*
Y413338D01*
G01X1063378Y409138D02*
X1055378D01*
G01X1067978Y440938D02*
X1055178D01*
G01D02*
Y448138D01*
G01X1063378Y427138D02*
X1055378D01*
G01X1063378Y436138D02*
X1055378D01*
G01D02*
Y431338D01*
G01D02*
X1063378D01*
G01X1055378Y452538D02*
X1063378D01*
G01Y457338D02*
X1055378D01*
G01D02*
Y452538D01*
G01X1055178Y448138D02*
X1067978D01*
G01X1073178Y346538D02*
Y338538D01*
G01D02*
X1077978D01*
G01Y346538D02*
X1073178D01*
G01X1065378Y399138D02*
X1057378D01*
G01D02*
Y394338D01*
G01D02*
X1065378D01*
G01D02*
Y399138D01*
G01X1063378Y404338D02*
Y409138D01*
G01Y422338D02*
Y427138D01*
G01Y413338D02*
Y418138D01*
G01X1067978Y448138D02*
Y440938D01*
G01X1063378Y431338D02*
Y436138D01*
G01Y452538D02*
Y457338D01*
G01X1087980Y-280942D02*
Y-330154D01*
G01X1080106Y-338028D02*
G03X1087980Y-330154I0J7874D01*
G01X1095854Y-273068D02*
G03X1087980Y-280942I0J-7874D01*
G01X1080678Y-244262D02*
X1088678D01*
G01D02*
Y-239462D01*
G01D02*
X1080678D01*
G01D02*
Y-244262D01*
G01X1080638Y-234262D02*
X1088638D01*
G01D02*
Y-229462D01*
G01D02*
X1080638D01*
G01X1088578Y-220462D02*
X1080578D01*
G01Y-225262D02*
X1088578D01*
G01D02*
Y-220462D01*
G01X1080638Y-229462D02*
Y-234262D01*
G01X1080578Y-220462D02*
Y-225262D01*
G01X1082578Y275938D02*
X1074578D01*
G01D02*
Y271138D01*
G01D02*
X1082578D01*
G01D02*
Y275938D01*
G01Y284938D02*
X1074578D01*
G01D02*
Y280138D01*
G01D02*
X1082578D01*
G01D02*
Y284938D01*
G01X1090178Y347938D02*
Y335138D01*
G01D02*
X1082978D01*
G01D02*
Y347938D01*
G01X1083578Y328938D02*
X1075578D01*
G01D02*
Y324138D01*
G01D02*
X1083578D01*
G01D02*
Y328938D01*
G01X1082978Y347938D02*
X1090178D01*
G01X1077978Y338538D02*
Y346538D01*
G01X1224594Y-273068D02*
X1095854D01*
G01X1115618Y-239322D02*
X1107618D01*
G01D02*
Y-244122D01*
G01D02*
X1115618D01*
G01X1107638Y-234142D02*
X1115638D01*
G01Y-229342D02*
X1107638D01*
G01D02*
Y-234142D01*
G01X1092178Y253538D02*
Y245538D01*
G01D02*
X1096978D01*
G01D02*
Y253538D01*
G01D02*
X1092178D01*
G01X1108978Y347538D02*
X1104178D01*
G01D02*
Y339538D01*
G01D02*
X1108978D01*
G01X1099978D02*
Y347538D01*
G01D02*
X1095178D01*
G01D02*
Y339538D01*
G01D02*
X1099978D01*
G01X1115618Y-244122D02*
Y-239322D01*
G01X1115638Y-234142D02*
Y-229342D01*
G01X1111578Y323938D02*
Y319138D01*
G01D02*
X1119578D01*
G01D02*
Y323938D01*
G01D02*
X1111578D01*
G01X1126978Y347538D02*
X1122178D01*
G01D02*
Y339538D01*
G01D02*
X1126978D01*
G01X1108978D02*
Y347538D01*
G01X1117978Y339538D02*
Y347538D01*
G01D02*
X1113178D01*
G01D02*
Y339538D01*
G01D02*
X1117978D01*
G01X1134778Y-232262D02*
X1142778D01*
G01D02*
Y-227462D01*
G01D02*
X1134778D01*
G01D02*
Y-232262D01*
G01X1141178Y253538D02*
Y245538D01*
G01D02*
X1145978D01*
G01Y253538D02*
X1141178D01*
G01X1128978Y317138D02*
Y329938D01*
G01X1136178D02*
Y317138D01*
G01D02*
X1128978D01*
G01Y329938D02*
X1136178D01*
G01X1135978Y339538D02*
Y347538D01*
G01D02*
X1131178D01*
G01D02*
Y339538D01*
G01D02*
X1135978D01*
G01X1140178Y347538D02*
Y339538D01*
G01D02*
X1144978D01*
G01Y347538D02*
X1140178D01*
G01X1126978Y339538D02*
Y347538D01*
G01X1137178Y372538D02*
Y364538D01*
G01D02*
X1141978D01*
G01D02*
Y372538D01*
G01D02*
X1137178D01*
G01X1145978Y245538D02*
Y253538D01*
G01X1162978Y347538D02*
X1158178D01*
G01D02*
Y339538D01*
G01D02*
X1162978D01*
G01X1144978D02*
Y347538D01*
G01X1149178D02*
Y339538D01*
G01D02*
X1153978D01*
G01D02*
Y347538D01*
G01D02*
X1149178D01*
G01X1180978Y-229062D02*
X1172978D01*
G01D02*
Y-233862D01*
G01D02*
X1180978D01*
G01Y-207062D02*
X1176178D01*
G01D02*
Y-215062D01*
G01D02*
X1180978D01*
G01X1172578Y-183062D02*
Y-191062D01*
G01D02*
X1177378D01*
G01D02*
Y-183062D01*
G01D02*
X1172578D01*
G01X1173778Y107138D02*
Y115138D01*
G01X1168978D02*
Y107138D01*
G01D02*
X1173778D01*
G01Y115138D02*
X1168978D01*
G01X1181378Y192538D02*
X1176578D01*
G01D02*
Y184538D01*
G01D02*
X1181378D01*
G01X1166578Y192538D02*
Y184538D01*
G01D02*
X1171378D01*
G01D02*
Y192538D01*
G01D02*
X1166578D01*
G01X1176578Y310938D02*
X1168578D01*
G01D02*
Y306138D01*
G01D02*
X1176578D01*
G01D02*
Y310938D01*
G01Y319938D02*
X1168578D01*
G01D02*
Y315138D01*
G01D02*
X1176578D01*
G01D02*
Y319938D01*
G01Y328938D02*
X1168578D01*
G01D02*
Y324138D01*
G01D02*
X1176578D01*
G01D02*
Y328938D01*
G01Y337338D02*
Y345338D01*
G01X1171778D02*
Y337338D01*
G01D02*
X1176578D01*
G01Y345338D02*
X1171778D01*
G01X1162978Y339538D02*
Y347538D01*
G01X1180578Y-242862D02*
X1188578D01*
G01D02*
Y-238062D01*
G01D02*
X1180578D01*
G01D02*
Y-242862D01*
G01X1188378Y-231062D02*
X1193178D01*
G01D02*
Y-223062D01*
G01D02*
X1188378D01*
G01D02*
Y-231062D01*
G01X1180978Y-233862D02*
Y-229062D01*
G01Y-215062D02*
Y-207062D01*
G01X1190578Y-191062D02*
X1195378D01*
G01X1181578Y-183062D02*
Y-191062D01*
G01D02*
X1186378D01*
G01D02*
Y-183062D01*
G01X1190578D02*
Y-191062D01*
G01X1195378Y-183062D02*
X1190578D01*
G01X1186378D02*
X1181578D01*
G01X1180778Y-66062D02*
X1188778D01*
G01D02*
Y-61262D01*
G01X1180778D02*
Y-66062D01*
G01X1181578Y-75862D02*
X1189578D01*
G01D02*
Y-71062D01*
G01D02*
X1181578D01*
G01D02*
Y-75862D01*
G01X1188778Y-61262D02*
X1180778D01*
G01Y-57062D02*
X1188778D01*
G01D02*
Y-52262D01*
G01D02*
X1180778D01*
G01D02*
Y-57062D01*
G01Y-48062D02*
X1188778D01*
G01D02*
Y-43262D01*
G01X1180778D02*
Y-48062D01*
G01X1188778Y-43262D02*
X1180778D01*
G01Y-39062D02*
X1188778D01*
G01D02*
Y-34262D01*
G01D02*
X1180778D01*
G01D02*
Y-39062D01*
G01X1187178Y107138D02*
X1191978D01*
G01D02*
Y115138D01*
G01X1182978Y107138D02*
Y115138D01*
G01X1178178D02*
Y107138D01*
G01D02*
X1182978D01*
G01X1187178Y115138D02*
Y107138D01*
G01X1191978Y115138D02*
X1187178D01*
G01X1182978D02*
X1178178D01*
G01X1181378Y184538D02*
Y192538D01*
G01X1203978Y-201862D02*
Y-209862D01*
G01D02*
X1208778D01*
G01D02*
Y-201862D01*
G01X1208578Y-183062D02*
Y-191062D01*
G01D02*
X1213378D01*
G01X1195378D02*
Y-183062D01*
G01X1204378Y-191062D02*
Y-183062D01*
G01X1199578D02*
Y-191062D01*
G01D02*
X1204378D01*
G01X1208778Y-201862D02*
X1203978D01*
G01X1213378Y-183062D02*
X1208578D01*
G01X1204378D02*
X1199578D01*
G01X1215578Y-72062D02*
X1207578D01*
G01D02*
Y-76862D01*
G01D02*
X1215578D01*
G01X1207378Y-62262D02*
Y-67062D01*
G01D02*
X1215378D01*
G01X1215178Y-51262D02*
X1207178D01*
G01D02*
Y-56062D01*
G01D02*
X1215178D01*
G01X1215378Y-62262D02*
X1207378D01*
G01X1209978Y107138D02*
Y115138D01*
G01X1205178D02*
Y107138D01*
G01D02*
X1209978D01*
G01X1196178Y115138D02*
Y107138D01*
G01D02*
X1200978D01*
G01D02*
Y115138D01*
G01X1209978D02*
X1205178D01*
G01X1200978D02*
X1196178D01*
G01X1202578Y207138D02*
X1210578D01*
G01D02*
Y211938D01*
G01D02*
X1202578D01*
G01D02*
Y207138D01*
G01X1201578Y255138D02*
X1209578D01*
G01D02*
Y259938D01*
G01D02*
X1201578D01*
G01D02*
Y255138D01*
G01Y268938D02*
Y264138D01*
G01D02*
X1209578D01*
G01D02*
Y268938D01*
G01D02*
X1201578D01*
G01X1209578Y277938D02*
X1201578D01*
G01D02*
Y273138D01*
G01D02*
X1209578D01*
G01D02*
Y277938D01*
G01X1208178Y311538D02*
Y303538D01*
G01D02*
X1212978D01*
G01Y311538D02*
X1208178D01*
G01X1232468Y-280942D02*
G03X1224594Y-273068I-7874J0D01*
G01X1223378Y-248062D02*
X1215378D01*
G01D02*
Y-252862D01*
G01D02*
X1223378D01*
G01D02*
Y-248062D01*
G01X1213378Y-191062D02*
Y-183062D01*
G01X1215578Y-76862D02*
Y-72062D01*
G01X1215378Y-67062D02*
Y-62262D01*
G01X1215178Y-56062D02*
Y-51262D01*
G01X1216178Y237538D02*
Y229538D01*
G01D02*
X1220978D01*
G01D02*
Y237538D01*
G01D02*
X1216178D01*
G01X1212978Y303538D02*
Y311538D01*
G01X1342704Y-338028D02*
X1240342D01*
G01X1232468Y-330154D02*
G03X1240342Y-338028I7874J0D01*
G01X1232468Y-330154D02*
Y-280942D01*
G01X1246978Y-242262D02*
Y-234262D01*
G01X1242178D02*
Y-242262D01*
G01D02*
X1246978D01*
G01X1232778Y-234262D02*
Y-242262D01*
G01D02*
X1237578D01*
G01D02*
Y-234262D01*
G01X1246978D02*
X1242178D01*
G01X1237578D02*
X1232778D01*
G01X1241178Y-188462D02*
Y-196462D01*
G01D02*
X1245978D01*
G01D02*
Y-188462D01*
G01D02*
X1241178D01*
G01X1242178Y-76462D02*
Y-84462D01*
G01D02*
X1246978D01*
G01D02*
Y-76462D01*
G01D02*
X1242178D01*
G01Y44538D02*
Y36538D01*
G01D02*
X1246978D01*
G01D02*
Y44538D01*
G01D02*
X1242178D01*
G01Y151538D02*
Y143538D01*
G01D02*
X1246978D01*
G01D02*
Y151538D01*
G01D02*
X1242178D01*
G01X1270578Y212538D02*
X1246578D01*
G01D02*
Y236538D01*
G01D02*
X1270578D01*
G01X1247778Y231938D02*
G03I3000J0D01*
G01X1252524Y229498D02*
X1249032D01*
G01X1253340Y233498D02*
X1248216D01*
G01X1279500Y-1435000D02*
Y-1415000D01*
X1276500Y-1419000D01*
G01Y-1435000D02*
X1282500D01*
G01X1299500Y-1435667D02*
X1299000Y-1435333D01*
Y-1434667D01*
X1299500Y-1434333D01*
X1300000Y-1434667D01*
Y-1435333D01*
X1299500Y-1435667D01*
G01Y-1426667D02*
X1299000Y-1426333D01*
Y-1425667D01*
X1299500Y-1425334D01*
X1300000Y-1425667D01*
Y-1426333D01*
X1299500Y-1426667D01*
G01X1314750Y-1418333D02*
X1316250Y-1416334D01*
X1318000Y-1415333D01*
X1320000Y-1415000D01*
X1322500Y-1415667D01*
X1324250Y-1417333D01*
X1324750Y-1419333D01*
X1324500Y-1421334D01*
X1323500Y-1423000D01*
X1318500Y-1426333D01*
X1316250Y-1428667D01*
X1314750Y-1432001D01*
X1314250Y-1435000D01*
X1324750D01*
G01X1267922Y-299840D02*
G03I23600J0D01*
G01X1281178Y200538D02*
Y192538D01*
G01D02*
X1285978D01*
G01X1270578Y236538D02*
Y212538D01*
G01X1285978Y200538D02*
X1281178D01*
G01X1267922Y372600D02*
G03I23600J0D01*
G01X1284610Y-1466600D02*
X1286490D01*
G01X1285550D02*
Y-1472900D01*
G01X1284610D02*
X1286490D01*
G01X1290048D02*
Y-1466600D01*
X1293652Y-1472900D01*
Y-1466600D01*
G01X1299873Y-1467125D02*
X1299403Y-1466810D01*
X1298855Y-1466600D01*
X1298228D01*
X1297523Y-1466915D01*
X1296975Y-1467440D01*
X1296583Y-1468070D01*
X1296270Y-1469120D01*
X1296192Y-1470065D01*
X1296348Y-1471010D01*
X1296583Y-1471640D01*
X1297053Y-1472270D01*
X1297602Y-1472690D01*
X1298150Y-1472900D01*
X1298698D01*
X1299247Y-1472690D01*
X1299717Y-1472375D01*
X1300108Y-1471955D01*
G01X1302805Y-1472900D02*
Y-1466600D01*
G01X1306095D02*
Y-1472900D01*
G01Y-1469750D02*
X1302805D01*
G01X1290178Y200538D02*
Y192538D01*
G01D02*
X1294978D01*
G01D02*
Y200538D01*
G01X1285978Y192538D02*
Y200538D01*
G01X1294978D02*
X1290178D01*
G01X1302578Y199138D02*
X1310578D01*
G01D02*
Y203938D01*
G01D02*
X1302578D01*
G01D02*
Y199138D01*
G01X1310578Y213938D02*
X1302578D01*
G01D02*
Y209138D01*
G01D02*
X1310578D01*
G01D02*
Y213938D01*
G01X1302578Y229138D02*
X1310578D01*
G01D02*
Y233938D01*
G01X1302578D02*
Y229138D01*
G01X1310578Y223938D02*
X1302578D01*
G01D02*
Y219138D01*
G01D02*
X1310578D01*
G01D02*
Y223938D01*
G01Y233938D02*
X1302578D01*
G01X1310578Y243938D02*
X1302578D01*
G01D02*
Y239138D01*
G01D02*
X1310578D01*
G01D02*
Y243938D01*
G01X1353050Y-1486000D02*
Y-1470400D01*
X1350710Y-1473520D01*
G01Y-1486000D02*
X1355390D01*
G01X1350578Y493860D02*
Y-330154D01*
G01X1342704Y-338028D02*
G03X1350578Y-330154I0J7874D01*
G01Y493860D02*
G03X1342704Y501734I-7874J0D01*
G01X1458450Y-1471500D02*
Y-1455900D01*
X1463325D01*
X1464885Y-1456680D01*
X1465860Y-1457720D01*
X1466250Y-1459800D01*
X1465860Y-1461880D01*
X1464690Y-1463180D01*
X1463325Y-1463960D01*
X1458450D01*
G01X1463325D02*
X1466250Y-1471500D01*
G01X1482590D02*
Y-1455900D01*
X1475375Y-1467080D01*
X1485125D01*
G01X1498150Y-1455900D02*
X1496590Y-1456420D01*
X1495420Y-1457720D01*
X1494640Y-1459280D01*
X1494055Y-1461360D01*
X1493860Y-1463700D01*
X1494055Y-1466040D01*
X1494640Y-1468120D01*
X1495420Y-1469680D01*
X1496590Y-1470980D01*
X1498150Y-1471500D01*
X1499710Y-1470980D01*
X1500880Y-1469680D01*
X1501660Y-1468120D01*
X1502245Y-1466040D01*
X1502440Y-1463700D01*
X1502245Y-1461360D01*
X1501660Y-1459280D01*
X1500880Y-1457720D01*
X1499710Y-1456420D01*
X1498150Y-1455900D01*
G01X1516050D02*
X1514490Y-1456420D01*
X1513320Y-1457720D01*
X1512540Y-1459280D01*
X1511955Y-1461360D01*
X1511760Y-1463700D01*
X1511955Y-1466040D01*
X1512540Y-1468120D01*
X1513320Y-1469680D01*
X1514490Y-1470980D01*
X1516050Y-1471500D01*
X1517610Y-1470980D01*
X1518780Y-1469680D01*
X1519560Y-1468120D01*
X1520145Y-1466040D01*
X1520340Y-1463700D01*
X1520145Y-1461360D01*
X1519560Y-1459280D01*
X1518780Y-1457720D01*
X1517610Y-1456420D01*
X1516050Y-1455900D01*
G01X1530245Y-1465000D02*
X1531610Y-1463180D01*
X1532780Y-1462140D01*
X1534340Y-1461620D01*
X1535705Y-1462140D01*
X1536680Y-1463180D01*
X1537460Y-1464740D01*
X1537655Y-1466560D01*
X1537460Y-1468120D01*
X1536680Y-1469680D01*
X1535510Y-1470980D01*
X1534145Y-1471500D01*
X1532585Y-1470980D01*
X1531220Y-1469420D01*
X1530440Y-1467080D01*
X1530245Y-1464480D01*
X1530635Y-1461100D01*
X1531220Y-1459280D01*
X1532195Y-1457460D01*
X1533560Y-1456160D01*
X1534925Y-1455900D01*
X1536290Y-1456420D01*
X1537265Y-1457720D01*
G01X1549315Y-1466300D02*
X1554385D01*
G01X1571310Y-1463180D02*
X1572090Y-1462400D01*
X1572675Y-1461100D01*
X1573065Y-1459280D01*
X1572675Y-1457720D01*
X1571895Y-1456680D01*
X1570530Y-1455900D01*
X1565265D01*
Y-1471500D01*
X1571700D01*
X1573065Y-1470460D01*
X1573845Y-1468900D01*
X1574235Y-1467080D01*
X1573845Y-1465260D01*
X1572675Y-1463700D01*
X1571310Y-1463180D01*
X1565265D01*
G01X1587650Y-1455900D02*
X1586090Y-1456420D01*
X1584920Y-1457720D01*
X1584140Y-1459280D01*
X1583555Y-1461360D01*
X1583360Y-1463700D01*
X1583555Y-1466040D01*
X1584140Y-1468120D01*
X1584920Y-1469680D01*
X1586090Y-1470980D01*
X1587650Y-1471500D01*
X1589210Y-1470980D01*
X1590380Y-1469680D01*
X1591160Y-1468120D01*
X1591745Y-1466040D01*
X1591940Y-1463700D01*
X1591745Y-1461360D01*
X1591160Y-1459280D01*
X1590380Y-1457720D01*
X1589210Y-1456420D01*
X1587650Y-1455900D01*
G01X1605550D02*
X1603990Y-1456420D01*
X1602820Y-1457720D01*
X1602040Y-1459280D01*
X1601455Y-1461360D01*
X1601260Y-1463700D01*
X1601455Y-1466040D01*
X1602040Y-1468120D01*
X1602820Y-1469680D01*
X1603990Y-1470980D01*
X1605550Y-1471500D01*
X1607110Y-1470980D01*
X1608280Y-1469680D01*
X1609060Y-1468120D01*
X1609645Y-1466040D01*
X1609840Y-1463700D01*
X1609645Y-1461360D01*
X1609060Y-1459280D01*
X1608280Y-1457720D01*
X1607110Y-1456420D01*
X1605550Y-1455900D01*
G01X1623450D02*
X1621890Y-1456420D01*
X1620720Y-1457720D01*
X1619940Y-1459280D01*
X1619355Y-1461360D01*
X1619160Y-1463700D01*
X1619355Y-1466040D01*
X1619940Y-1468120D01*
X1620720Y-1469680D01*
X1621890Y-1470980D01*
X1623450Y-1471500D01*
X1625010Y-1470980D01*
X1626180Y-1469680D01*
X1626960Y-1468120D01*
X1627545Y-1466040D01*
X1627740Y-1463700D01*
X1627545Y-1461360D01*
X1626960Y-1459280D01*
X1626180Y-1457720D01*
X1625010Y-1456420D01*
X1623450Y-1455900D01*
G01X1641350Y-1471500D02*
Y-1455900D01*
X1639010Y-1459020D01*
G01Y-1471500D02*
X1643690D01*
G01X1656715Y-1466300D02*
X1661785D01*
G01X1677150Y-1455900D02*
X1675590Y-1456420D01*
X1674420Y-1457720D01*
X1673640Y-1459280D01*
X1673055Y-1461360D01*
X1672860Y-1463700D01*
X1673055Y-1466040D01*
X1673640Y-1468120D01*
X1674420Y-1469680D01*
X1675590Y-1470980D01*
X1677150Y-1471500D01*
X1678710Y-1470980D01*
X1679880Y-1469680D01*
X1680660Y-1468120D01*
X1681245Y-1466040D01*
X1681440Y-1463700D01*
X1681245Y-1461360D01*
X1680660Y-1459280D01*
X1679880Y-1457720D01*
X1678710Y-1456420D01*
X1677150Y-1455900D01*
G01X1691345Y-1458500D02*
X1692515Y-1456940D01*
X1693880Y-1456160D01*
X1695440Y-1455900D01*
X1697390Y-1456420D01*
X1698755Y-1457720D01*
X1699145Y-1459280D01*
X1698950Y-1460840D01*
X1698170Y-1462140D01*
X1694270Y-1464740D01*
X1692515Y-1466560D01*
X1691345Y-1469160D01*
X1690955Y-1471500D01*
X1699145D01*
G01X1509250Y-1567000D02*
X1515500Y-1547000D01*
X1521750Y-1567000D01*
G01X1519500Y-1560000D02*
X1511500D01*
G01X1530250Y-1564334D02*
X1532250Y-1566000D01*
X1534500Y-1567000D01*
X1536500D01*
X1538500Y-1566000D01*
X1540000Y-1564334D01*
X1540750Y-1562000D01*
X1540250Y-1559667D01*
X1539000Y-1557667D01*
X1536750Y-1556333D01*
X1533750Y-1555667D01*
X1532000Y-1554334D01*
X1531250Y-1552000D01*
X1531750Y-1549667D01*
X1533000Y-1548000D01*
X1534750Y-1547000D01*
X1536500D01*
X1538250Y-1547667D01*
X1539750Y-1549333D01*
G01X1550250Y-1564334D02*
X1552250Y-1566000D01*
X1554500Y-1567000D01*
X1556500D01*
X1558500Y-1566000D01*
X1560000Y-1564334D01*
X1560750Y-1562000D01*
X1560250Y-1559667D01*
X1559000Y-1557667D01*
X1556750Y-1556333D01*
X1553750Y-1555667D01*
X1552000Y-1554334D01*
X1551250Y-1552000D01*
X1551750Y-1549667D01*
X1553000Y-1548000D01*
X1554750Y-1547000D01*
X1556500D01*
X1558250Y-1547667D01*
X1559750Y-1549333D01*
G01X1580500Y-1567000D02*
X1570500D01*
Y-1547000D01*
X1580500D01*
G01X1576500Y-1556666D02*
X1570500D01*
G01X1589000Y-1567000D02*
Y-1547000D01*
X1595500Y-1563667D01*
X1602000Y-1547000D01*
Y-1567000D01*
G01X1617500Y-1556333D02*
X1618500Y-1555333D01*
X1619250Y-1553667D01*
X1619750Y-1551333D01*
X1619250Y-1549333D01*
X1618250Y-1548000D01*
X1616500Y-1547000D01*
X1609750D01*
Y-1567000D01*
X1618000D01*
X1619750Y-1565667D01*
X1620750Y-1563667D01*
X1621250Y-1561333D01*
X1620750Y-1559000D01*
X1619250Y-1557000D01*
X1617500Y-1556333D01*
X1609750D01*
G01X1630500Y-1547000D02*
Y-1567000D01*
X1640500D01*
G01X1655500D02*
Y-1558000D01*
X1650500Y-1547000D01*
G01X1660500D02*
X1655500Y-1558000D01*
G01X1690000Y-1567000D02*
Y-1547000D01*
X1695000D01*
X1697000Y-1548000D01*
X1698500Y-1549333D01*
X1699750Y-1551333D01*
X1700750Y-1553667D01*
X1701000Y-1557000D01*
X1700750Y-1560334D01*
X1699750Y-1562667D01*
X1698500Y-1564667D01*
X1697000Y-1566000D01*
X1695000Y-1567000D01*
X1690000D01*
G01X1710500D02*
Y-1547000D01*
X1716750D01*
X1718750Y-1548000D01*
X1720000Y-1549333D01*
X1720500Y-1552000D01*
X1720000Y-1554667D01*
X1718500Y-1556333D01*
X1716750Y-1557334D01*
X1710500D01*
G01X1716750D02*
X1720500Y-1567000D01*
G01X1729250D02*
X1735500Y-1547000D01*
X1741750Y-1567000D01*
G01X1739500Y-1560000D02*
X1731500D01*
G01X1748000Y-1547000D02*
X1751500Y-1567000D01*
X1755500Y-1547000D01*
X1759500Y-1567000D01*
X1763000Y-1547000D01*
G01X1772500D02*
X1778500D01*
G01X1775500D02*
Y-1567000D01*
G01X1772500D02*
X1778500D01*
G01X1789750D02*
Y-1547000D01*
X1801250Y-1567000D01*
Y-1547000D01*
G01X1817000Y-1557000D02*
X1822000D01*
Y-1563000D01*
X1820500Y-1565000D01*
X1818750Y-1566333D01*
X1816250Y-1567000D01*
X1813750Y-1566333D01*
X1812000Y-1565000D01*
X1810500Y-1563000D01*
X1809500Y-1560667D01*
X1809000Y-1558000D01*
Y-1555667D01*
X1809500Y-1553667D01*
X1810500Y-1551333D01*
X1812000Y-1549333D01*
X1813500Y-1548000D01*
X1815500Y-1547000D01*
X1817250D01*
X1819250Y-1547667D01*
X1820750Y-1549000D01*
G01X1553500Y-1504000D02*
Y-1524000D01*
G01X1547750Y-1504000D02*
X1559250D01*
G01X1570500D02*
X1576500D01*
G01X1573500D02*
Y-1524000D01*
G01X1570500D02*
X1576500D01*
G01X1587000D02*
Y-1504000D01*
X1593500Y-1520667D01*
X1600000Y-1504000D01*
Y-1524000D01*
G01X1610500Y-1504000D02*
X1616500D01*
G01X1613500D02*
Y-1524000D01*
G01X1610500D02*
X1616500D01*
G01X1627750D02*
Y-1504000D01*
X1639250Y-1524000D01*
Y-1504000D01*
G01X1655000Y-1514000D02*
X1660000D01*
Y-1520000D01*
X1658500Y-1522000D01*
X1656750Y-1523333D01*
X1654250Y-1524000D01*
X1651750Y-1523333D01*
X1650000Y-1522000D01*
X1648500Y-1520000D01*
X1647500Y-1517667D01*
X1647000Y-1515000D01*
Y-1512667D01*
X1647500Y-1510667D01*
X1648500Y-1508333D01*
X1650000Y-1506333D01*
X1651500Y-1505000D01*
X1653500Y-1504000D01*
X1655250D01*
X1657250Y-1504667D01*
X1658750Y-1506000D01*
G01X1699000Y-1505667D02*
X1697500Y-1504667D01*
X1695750Y-1504000D01*
X1693750D01*
X1691500Y-1505000D01*
X1689750Y-1506667D01*
X1688500Y-1508667D01*
X1687500Y-1512000D01*
X1687250Y-1515000D01*
X1687750Y-1518000D01*
X1688500Y-1520000D01*
X1690000Y-1522000D01*
X1691750Y-1523333D01*
X1693500Y-1524000D01*
X1695250D01*
X1697000Y-1523333D01*
X1698500Y-1522334D01*
X1699750Y-1521001D01*
G01X1707250Y-1524000D02*
X1713500Y-1504000D01*
X1719750Y-1524000D01*
G01X1717500Y-1517000D02*
X1709500D01*
G01X1728500Y-1524000D02*
Y-1504000D01*
X1734750D01*
X1736750Y-1505000D01*
X1738000Y-1506333D01*
X1738500Y-1509000D01*
X1738000Y-1511667D01*
X1736500Y-1513333D01*
X1734750Y-1514334D01*
X1728500D01*
G01X1734750D02*
X1738500Y-1524000D01*
G01X1748000D02*
Y-1504000D01*
X1753000D01*
X1755000Y-1505000D01*
X1756500Y-1506333D01*
X1757750Y-1508333D01*
X1758750Y-1510667D01*
X1759000Y-1514000D01*
X1758750Y-1517334D01*
X1757750Y-1519667D01*
X1756500Y-1521667D01*
X1755000Y-1523000D01*
X1753000Y-1524000D01*
X1748000D01*
G01X1569650Y1507500D02*
Y1532500D01*
X1577525D01*
X1580045Y1531250D01*
X1581620Y1529583D01*
X1582250Y1526250D01*
X1581620Y1522916D01*
X1579730Y1520834D01*
X1577525Y1519583D01*
X1569650D01*
G01X1577525D02*
X1582250Y1507500D01*
G01X1604930D02*
Y1532500D01*
X1593275Y1514583D01*
X1609025D01*
G01X1626350Y1532500D02*
X1623830Y1531667D01*
X1621940Y1529583D01*
X1620680Y1527084D01*
X1619735Y1523750D01*
X1619420Y1520000D01*
X1619735Y1516250D01*
X1620680Y1512916D01*
X1621940Y1510416D01*
X1623830Y1508333D01*
X1626350Y1507500D01*
X1628870Y1508333D01*
X1630760Y1510416D01*
X1632020Y1512916D01*
X1632965Y1516250D01*
X1633280Y1520000D01*
X1632965Y1523750D01*
X1632020Y1527084D01*
X1630760Y1529583D01*
X1628870Y1531667D01*
X1626350Y1532500D01*
G01X1651550D02*
X1649030Y1531667D01*
X1647140Y1529583D01*
X1645880Y1527084D01*
X1644935Y1523750D01*
X1644620Y1520000D01*
X1644935Y1516250D01*
X1645880Y1512916D01*
X1647140Y1510416D01*
X1649030Y1508333D01*
X1651550Y1507500D01*
X1654070Y1508333D01*
X1655960Y1510416D01*
X1657220Y1512916D01*
X1658165Y1516250D01*
X1658480Y1520000D01*
X1658165Y1523750D01*
X1657220Y1527084D01*
X1655960Y1529583D01*
X1654070Y1531667D01*
X1651550Y1532500D01*
G01X1670765Y1517916D02*
X1672970Y1520834D01*
X1674860Y1522500D01*
X1677380Y1523333D01*
X1679585Y1522500D01*
X1681160Y1520834D01*
X1682420Y1518333D01*
X1682735Y1515417D01*
X1682420Y1512916D01*
X1681160Y1510416D01*
X1679270Y1508333D01*
X1677065Y1507500D01*
X1674545Y1508333D01*
X1672340Y1510833D01*
X1671080Y1514583D01*
X1670765Y1518750D01*
X1671395Y1524166D01*
X1672340Y1527084D01*
X1673915Y1530000D01*
X1676120Y1532083D01*
X1678325Y1532500D01*
X1680530Y1531667D01*
X1682105Y1529583D01*
G01X1697855Y1515833D02*
X1706045D01*
G01X1729670Y1520834D02*
X1730930Y1522083D01*
X1731875Y1524166D01*
X1732505Y1527084D01*
X1731875Y1529583D01*
X1730615Y1531250D01*
X1728410Y1532500D01*
X1719905D01*
Y1507500D01*
X1730300D01*
X1732505Y1509166D01*
X1733765Y1511667D01*
X1734395Y1514583D01*
X1733765Y1517499D01*
X1731875Y1520000D01*
X1729670Y1520834D01*
X1719905D01*
G01X1752350Y1532500D02*
X1749830Y1531667D01*
X1747940Y1529583D01*
X1746680Y1527084D01*
X1745735Y1523750D01*
X1745420Y1520000D01*
X1745735Y1516250D01*
X1746680Y1512916D01*
X1747940Y1510416D01*
X1749830Y1508333D01*
X1752350Y1507500D01*
X1754870Y1508333D01*
X1756760Y1510416D01*
X1758020Y1512916D01*
X1758965Y1516250D01*
X1759280Y1520000D01*
X1758965Y1523750D01*
X1758020Y1527084D01*
X1756760Y1529583D01*
X1754870Y1531667D01*
X1752350Y1532500D01*
G01X1777550D02*
X1775030Y1531667D01*
X1773140Y1529583D01*
X1771880Y1527084D01*
X1770935Y1523750D01*
X1770620Y1520000D01*
X1770935Y1516250D01*
X1771880Y1512916D01*
X1773140Y1510416D01*
X1775030Y1508333D01*
X1777550Y1507500D01*
X1780070Y1508333D01*
X1781960Y1510416D01*
X1783220Y1512916D01*
X1784165Y1516250D01*
X1784480Y1520000D01*
X1784165Y1523750D01*
X1783220Y1527084D01*
X1781960Y1529583D01*
X1780070Y1531667D01*
X1777550Y1532500D01*
G01X1802750D02*
X1800230Y1531667D01*
X1798340Y1529583D01*
X1797080Y1527084D01*
X1796135Y1523750D01*
X1795820Y1520000D01*
X1796135Y1516250D01*
X1797080Y1512916D01*
X1798340Y1510416D01*
X1800230Y1508333D01*
X1802750Y1507500D01*
X1805270Y1508333D01*
X1807160Y1510416D01*
X1808420Y1512916D01*
X1809365Y1516250D01*
X1809680Y1520000D01*
X1809365Y1523750D01*
X1808420Y1527084D01*
X1807160Y1529583D01*
X1805270Y1531667D01*
X1802750Y1532500D01*
G01X1827950Y1507500D02*
Y1532500D01*
X1824170Y1527500D01*
G01Y1507500D02*
X1831729D01*
G01X1849055Y1515833D02*
X1857245D01*
G01X1878350Y1532500D02*
X1875830Y1531667D01*
X1873940Y1529583D01*
X1872680Y1527084D01*
X1871735Y1523750D01*
X1871420Y1520000D01*
X1871735Y1516250D01*
X1872680Y1512916D01*
X1873940Y1510416D01*
X1875830Y1508333D01*
X1878350Y1507500D01*
X1880870Y1508333D01*
X1882760Y1510416D01*
X1884020Y1512916D01*
X1884965Y1516250D01*
X1885280Y1520000D01*
X1884965Y1523750D01*
X1884020Y1527084D01*
X1882760Y1529583D01*
X1880870Y1531667D01*
X1878350Y1532500D01*
G01X1897565Y1528333D02*
X1899455Y1530833D01*
X1901660Y1532083D01*
X1904180Y1532500D01*
X1907330Y1531667D01*
X1909535Y1529583D01*
X1910165Y1527084D01*
X1909850Y1524583D01*
X1908590Y1522500D01*
X1902290Y1518333D01*
X1899455Y1515417D01*
X1897565Y1511249D01*
X1896935Y1507500D01*
X1910165D01*
G01X1621500Y-1683333D02*
X1622500Y-1682333D01*
X1623250Y-1680667D01*
X1623750Y-1678333D01*
X1623250Y-1676333D01*
X1622250Y-1675000D01*
X1620500Y-1674000D01*
X1613750D01*
Y-1694000D01*
X1622000D01*
X1623750Y-1692667D01*
X1624750Y-1690667D01*
X1625250Y-1688333D01*
X1624750Y-1686000D01*
X1623250Y-1684000D01*
X1621500Y-1683333D01*
X1613750D01*
G01X1634250Y-1691334D02*
X1636250Y-1693000D01*
X1638500Y-1694000D01*
X1640500D01*
X1642500Y-1693000D01*
X1644000Y-1691334D01*
X1644750Y-1689000D01*
X1644250Y-1686667D01*
X1643000Y-1684667D01*
X1640750Y-1683333D01*
X1637750Y-1682667D01*
X1636000Y-1681334D01*
X1635250Y-1679000D01*
X1635750Y-1676667D01*
X1637000Y-1675000D01*
X1638750Y-1674000D01*
X1640500D01*
X1642250Y-1674667D01*
X1643750Y-1676333D01*
G01X1654250Y-1694000D02*
Y-1674000D01*
G01X1664750D02*
Y-1694000D01*
G01Y-1684000D02*
X1654250D01*
G01X1673250Y-1694000D02*
X1679500Y-1674000D01*
X1685750Y-1694000D01*
G01X1683500Y-1687000D02*
X1675500D01*
G01X1693750Y-1694000D02*
Y-1674000D01*
X1705250Y-1694000D01*
Y-1674000D01*
G01X1621500Y-1639833D02*
X1622500Y-1638833D01*
X1623250Y-1637167D01*
X1623750Y-1634833D01*
X1623250Y-1632833D01*
X1622250Y-1631500D01*
X1620500Y-1630500D01*
X1613750D01*
Y-1650500D01*
X1622000D01*
X1623750Y-1649167D01*
X1624750Y-1647167D01*
X1625250Y-1644833D01*
X1624750Y-1642500D01*
X1623250Y-1640500D01*
X1621500Y-1639833D01*
X1613750D01*
G01X1634250Y-1650500D02*
Y-1630500D01*
G01X1644750D02*
Y-1650500D01*
G01Y-1640500D02*
X1634250D01*
G01X1654000Y-1630500D02*
Y-1644833D01*
X1655000Y-1647834D01*
X1657000Y-1649833D01*
X1659500Y-1650500D01*
X1662000Y-1649833D01*
X1664000Y-1647834D01*
X1665000Y-1644833D01*
Y-1630500D01*
G01X1673000Y-1650500D02*
Y-1630500D01*
X1679500Y-1647167D01*
X1686000Y-1630500D01*
Y-1650500D01*
G01X1693250D02*
X1699500Y-1630500D01*
X1705750Y-1650500D01*
G01X1703500Y-1643500D02*
X1695500D01*
G01X1714500Y-1650500D02*
Y-1630500D01*
X1720750D01*
X1722750Y-1631500D01*
X1724000Y-1632833D01*
X1724500Y-1635500D01*
X1724000Y-1638167D01*
X1722500Y-1639833D01*
X1720750Y-1640834D01*
X1714500D01*
G01X1720750D02*
X1724500Y-1650500D01*
G01X1736500Y-1630500D02*
X1742500D01*
G01X1739500D02*
Y-1650500D01*
G01X1736500D02*
X1742500D01*
G01X1753750D02*
Y-1630500D01*
X1765250Y-1650500D01*
Y-1630500D01*
G01X1619500Y-1592167D02*
X1618000Y-1591167D01*
X1616250Y-1590500D01*
X1614250D01*
X1612000Y-1591500D01*
X1610250Y-1593167D01*
X1609000Y-1595167D01*
X1608000Y-1598500D01*
X1607750Y-1601500D01*
X1608250Y-1604500D01*
X1609000Y-1606500D01*
X1610500Y-1608500D01*
X1612250Y-1609833D01*
X1614000Y-1610500D01*
X1615750D01*
X1617500Y-1609833D01*
X1619000Y-1608834D01*
X1620250Y-1607501D01*
G01X1627750Y-1610500D02*
X1634000Y-1590500D01*
X1640250Y-1610500D01*
G01X1638000Y-1603500D02*
X1630000D01*
G01X1654000Y-1590500D02*
Y-1610500D01*
G01X1648250Y-1590500D02*
X1659750D01*
G01X1668750Y-1610500D02*
Y-1590500D01*
G01X1679250D02*
Y-1610500D01*
G01Y-1600500D02*
X1668750D01*
G01X1694000Y-1610500D02*
Y-1601500D01*
X1689000Y-1590500D01*
G01X1699000D02*
X1694000Y-1601500D01*
G01X1728750Y-1610500D02*
Y-1590500D01*
G01X1739250D02*
Y-1610500D01*
G01Y-1600500D02*
X1728750D01*
G01X1748500Y-1590500D02*
Y-1604833D01*
X1749500Y-1607834D01*
X1751500Y-1609833D01*
X1754000Y-1610500D01*
X1756500Y-1609833D01*
X1758500Y-1607834D01*
X1759500Y-1604833D01*
Y-1590500D01*
G01X1767750Y-1610500D02*
X1774000Y-1590500D01*
X1780250Y-1610500D01*
G01X1778000Y-1603500D02*
X1770000D01*
G01X1788250Y-1610500D02*
Y-1590500D01*
X1799750Y-1610500D01*
Y-1590500D01*
G01X1815500Y-1600500D02*
X1820500D01*
Y-1606500D01*
X1819000Y-1608500D01*
X1817250Y-1609833D01*
X1814750Y-1610500D01*
X1812250Y-1609833D01*
X1810500Y-1608500D01*
X1809000Y-1606500D01*
X1808000Y-1604167D01*
X1807500Y-1601500D01*
Y-1599167D01*
X1808000Y-1597167D01*
X1809000Y-1594833D01*
X1810500Y-1592833D01*
X1812000Y-1591500D01*
X1814000Y-1590500D01*
X1815750D01*
X1817750Y-1591167D01*
X1819250Y-1592500D01*
G01X1778350Y-1451900D02*
X1776790Y-1452420D01*
X1775620Y-1453720D01*
X1774840Y-1455280D01*
X1774255Y-1457360D01*
X1774060Y-1459700D01*
X1774255Y-1462040D01*
X1774840Y-1464120D01*
X1775620Y-1465680D01*
X1776790Y-1466980D01*
X1778350Y-1467500D01*
X1779910Y-1466980D01*
X1781080Y-1465680D01*
X1781860Y-1464120D01*
X1782445Y-1462040D01*
X1782640Y-1459700D01*
X1782445Y-1457360D01*
X1781860Y-1455280D01*
X1781080Y-1453720D01*
X1779910Y-1452420D01*
X1778350Y-1451900D01*
G01X1796250Y-1467500D02*
Y-1451900D01*
X1793910Y-1455020D01*
G01Y-1467500D02*
X1798590D01*
G01X1837750Y-1674833D02*
X1839250Y-1672834D01*
X1841000Y-1671833D01*
X1843000Y-1671500D01*
X1845500Y-1672167D01*
X1847250Y-1673833D01*
X1847750Y-1675833D01*
X1847500Y-1677834D01*
X1846500Y-1679500D01*
X1841500Y-1682833D01*
X1839250Y-1685167D01*
X1837750Y-1688501D01*
X1837250Y-1691500D01*
X1847750D01*
G01X1862500Y-1671500D02*
X1860500Y-1672167D01*
X1859000Y-1673833D01*
X1858000Y-1675833D01*
X1857250Y-1678500D01*
X1857000Y-1681500D01*
X1857250Y-1684500D01*
X1858000Y-1687167D01*
X1859000Y-1689167D01*
X1860500Y-1690833D01*
X1862500Y-1691500D01*
X1864500Y-1690833D01*
X1866000Y-1689167D01*
X1867000Y-1687167D01*
X1867750Y-1684500D01*
X1868000Y-1681500D01*
X1867750Y-1678500D01*
X1867000Y-1675833D01*
X1866000Y-1673833D01*
X1864500Y-1672167D01*
X1862500Y-1671500D01*
G01X1877750Y-1674833D02*
X1879250Y-1672834D01*
X1881000Y-1671833D01*
X1883000Y-1671500D01*
X1885500Y-1672167D01*
X1887250Y-1673833D01*
X1887750Y-1675833D01*
X1887500Y-1677834D01*
X1886500Y-1679500D01*
X1881500Y-1682833D01*
X1879250Y-1685167D01*
X1877750Y-1688501D01*
X1877250Y-1691500D01*
X1887750D01*
G01X1897750Y-1674833D02*
X1899250Y-1672834D01*
X1901000Y-1671833D01*
X1903000Y-1671500D01*
X1905500Y-1672167D01*
X1907250Y-1673833D01*
X1907750Y-1675833D01*
X1907500Y-1677834D01*
X1906500Y-1679500D01*
X1901500Y-1682833D01*
X1899250Y-1685167D01*
X1897750Y-1688501D01*
X1897250Y-1691500D01*
X1907750D01*
G01X1919250Y-1684834D02*
X1925750D01*
G01X1942500Y-1671500D02*
X1940500Y-1672167D01*
X1939000Y-1673833D01*
X1938000Y-1675833D01*
X1937250Y-1678500D01*
X1937000Y-1681500D01*
X1937250Y-1684500D01*
X1938000Y-1687167D01*
X1939000Y-1689167D01*
X1940500Y-1690833D01*
X1942500Y-1691500D01*
X1944500Y-1690833D01*
X1946000Y-1689167D01*
X1947000Y-1687167D01*
X1947750Y-1684500D01*
X1948000Y-1681500D01*
X1947750Y-1678500D01*
X1947000Y-1675833D01*
X1946000Y-1673833D01*
X1944500Y-1672167D01*
X1942500Y-1671500D01*
G01X1957750Y-1674833D02*
X1959250Y-1672834D01*
X1961000Y-1671833D01*
X1963000Y-1671500D01*
X1965500Y-1672167D01*
X1967250Y-1673833D01*
X1967750Y-1675833D01*
X1967500Y-1677834D01*
X1966500Y-1679500D01*
X1961500Y-1682833D01*
X1959250Y-1685167D01*
X1957750Y-1688501D01*
X1957250Y-1691500D01*
X1967750D01*
G01X1979250Y-1684834D02*
X1985750D01*
G01X1997750Y-1674833D02*
X1999250Y-1672834D01*
X2001000Y-1671833D01*
X2003000Y-1671500D01*
X2005500Y-1672167D01*
X2007250Y-1673833D01*
X2007750Y-1675833D01*
X2007500Y-1677834D01*
X2006500Y-1679500D01*
X2001500Y-1682833D01*
X1999250Y-1685167D01*
X1997750Y-1688501D01*
X1997250Y-1691500D01*
X2007750D01*
G01X2017000Y-1688501D02*
X2018500Y-1690167D01*
X2020250Y-1691167D01*
X2022500Y-1691500D01*
X2024750Y-1690833D01*
X2026500Y-1689500D01*
X2027750Y-1687167D01*
X2028000Y-1684500D01*
X2027500Y-1681834D01*
X2026250Y-1680167D01*
X2024500Y-1678834D01*
X2022750Y-1678500D01*
X2021000Y-1678834D01*
X2018750Y-1680167D01*
X2019500Y-1671500D01*
X2026250D01*
G01X1834250Y-1636333D02*
X1835750Y-1634334D01*
X1837500Y-1633333D01*
X1839500Y-1633000D01*
X1842000Y-1633667D01*
X1843750Y-1635333D01*
X1844250Y-1637333D01*
X1844000Y-1639334D01*
X1843000Y-1641000D01*
X1838000Y-1644333D01*
X1835750Y-1646667D01*
X1834250Y-1650001D01*
X1833750Y-1653000D01*
X1844250D01*
G01X1859000Y-1633000D02*
X1857000Y-1633667D01*
X1855500Y-1635333D01*
X1854500Y-1637333D01*
X1853750Y-1640000D01*
X1853500Y-1643000D01*
X1853750Y-1646000D01*
X1854500Y-1648667D01*
X1855500Y-1650667D01*
X1857000Y-1652333D01*
X1859000Y-1653000D01*
X1861000Y-1652333D01*
X1862500Y-1650667D01*
X1863500Y-1648667D01*
X1864250Y-1646000D01*
X1864500Y-1643000D01*
X1864250Y-1640000D01*
X1863500Y-1637333D01*
X1862500Y-1635333D01*
X1861000Y-1633667D01*
X1859000Y-1633000D01*
G01X1874250Y-1636333D02*
X1875750Y-1634334D01*
X1877500Y-1633333D01*
X1879500Y-1633000D01*
X1882000Y-1633667D01*
X1883750Y-1635333D01*
X1884250Y-1637333D01*
X1884000Y-1639334D01*
X1883000Y-1641000D01*
X1878000Y-1644333D01*
X1875750Y-1646667D01*
X1874250Y-1650001D01*
X1873750Y-1653000D01*
X1884250D01*
G01X1894250Y-1636333D02*
X1895750Y-1634334D01*
X1897500Y-1633333D01*
X1899500Y-1633000D01*
X1902000Y-1633667D01*
X1903750Y-1635333D01*
X1904250Y-1637333D01*
X1904000Y-1639334D01*
X1903000Y-1641000D01*
X1898000Y-1644333D01*
X1895750Y-1646667D01*
X1894250Y-1650001D01*
X1893750Y-1653000D01*
X1904250D01*
G01X1915750Y-1646334D02*
X1922250D01*
G01X1939000Y-1633000D02*
X1937000Y-1633667D01*
X1935500Y-1635333D01*
X1934500Y-1637333D01*
X1933750Y-1640000D01*
X1933500Y-1643000D01*
X1933750Y-1646000D01*
X1934500Y-1648667D01*
X1935500Y-1650667D01*
X1937000Y-1652333D01*
X1939000Y-1653000D01*
X1941000Y-1652333D01*
X1942500Y-1650667D01*
X1943500Y-1648667D01*
X1944250Y-1646000D01*
X1944500Y-1643000D01*
X1944250Y-1640000D01*
X1943500Y-1637333D01*
X1942500Y-1635333D01*
X1941000Y-1633667D01*
X1939000Y-1633000D01*
G01X1954250Y-1636333D02*
X1955750Y-1634334D01*
X1957500Y-1633333D01*
X1959500Y-1633000D01*
X1962000Y-1633667D01*
X1963750Y-1635333D01*
X1964250Y-1637333D01*
X1964000Y-1639334D01*
X1963000Y-1641000D01*
X1958000Y-1644333D01*
X1955750Y-1646667D01*
X1954250Y-1650001D01*
X1953750Y-1653000D01*
X1964250D01*
G01X1975750Y-1646334D02*
X1982250D01*
G01X1994250Y-1636333D02*
X1995750Y-1634334D01*
X1997500Y-1633333D01*
X1999500Y-1633000D01*
X2002000Y-1633667D01*
X2003750Y-1635333D01*
X2004250Y-1637333D01*
X2004000Y-1639334D01*
X2003000Y-1641000D01*
X1998000Y-1644333D01*
X1995750Y-1646667D01*
X1994250Y-1650001D01*
X1993750Y-1653000D01*
X2004250D01*
G01X2013500Y-1650001D02*
X2015000Y-1651667D01*
X2016750Y-1652667D01*
X2019000Y-1653000D01*
X2021250Y-1652333D01*
X2023000Y-1651000D01*
X2024250Y-1648667D01*
X2024500Y-1646000D01*
X2024000Y-1643334D01*
X2022750Y-1641667D01*
X2021000Y-1640334D01*
X2019250Y-1640000D01*
X2017500Y-1640334D01*
X2015250Y-1641667D01*
X2016000Y-1633000D01*
X2022750D01*
G01X1834250Y-1592333D02*
X1835750Y-1590334D01*
X1837500Y-1589333D01*
X1839500Y-1589000D01*
X1842000Y-1589667D01*
X1843750Y-1591333D01*
X1844250Y-1593333D01*
X1844000Y-1595334D01*
X1843000Y-1597000D01*
X1838000Y-1600333D01*
X1835750Y-1602667D01*
X1834250Y-1606001D01*
X1833750Y-1609000D01*
X1844250D01*
G01X1859000Y-1589000D02*
X1857000Y-1589667D01*
X1855500Y-1591333D01*
X1854500Y-1593333D01*
X1853750Y-1596000D01*
X1853500Y-1599000D01*
X1853750Y-1602000D01*
X1854500Y-1604667D01*
X1855500Y-1606667D01*
X1857000Y-1608333D01*
X1859000Y-1609000D01*
X1861000Y-1608333D01*
X1862500Y-1606667D01*
X1863500Y-1604667D01*
X1864250Y-1602000D01*
X1864500Y-1599000D01*
X1864250Y-1596000D01*
X1863500Y-1593333D01*
X1862500Y-1591333D01*
X1861000Y-1589667D01*
X1859000Y-1589000D01*
G01X1874250Y-1592333D02*
X1875750Y-1590334D01*
X1877500Y-1589333D01*
X1879500Y-1589000D01*
X1882000Y-1589667D01*
X1883750Y-1591333D01*
X1884250Y-1593333D01*
X1884000Y-1595334D01*
X1883000Y-1597000D01*
X1878000Y-1600333D01*
X1875750Y-1602667D01*
X1874250Y-1606001D01*
X1873750Y-1609000D01*
X1884250D01*
G01X1894250Y-1592333D02*
X1895750Y-1590334D01*
X1897500Y-1589333D01*
X1899500Y-1589000D01*
X1902000Y-1589667D01*
X1903750Y-1591333D01*
X1904250Y-1593333D01*
X1904000Y-1595334D01*
X1903000Y-1597000D01*
X1898000Y-1600333D01*
X1895750Y-1602667D01*
X1894250Y-1606001D01*
X1893750Y-1609000D01*
X1904250D01*
G01X1915750Y-1602334D02*
X1922250D01*
G01X1939000Y-1589000D02*
X1937000Y-1589667D01*
X1935500Y-1591333D01*
X1934500Y-1593333D01*
X1933750Y-1596000D01*
X1933500Y-1599000D01*
X1933750Y-1602000D01*
X1934500Y-1604667D01*
X1935500Y-1606667D01*
X1937000Y-1608333D01*
X1939000Y-1609000D01*
X1941000Y-1608333D01*
X1942500Y-1606667D01*
X1943500Y-1604667D01*
X1944250Y-1602000D01*
X1944500Y-1599000D01*
X1944250Y-1596000D01*
X1943500Y-1593333D01*
X1942500Y-1591333D01*
X1941000Y-1589667D01*
X1939000Y-1589000D01*
G01X1954250Y-1592333D02*
X1955750Y-1590334D01*
X1957500Y-1589333D01*
X1959500Y-1589000D01*
X1962000Y-1589667D01*
X1963750Y-1591333D01*
X1964250Y-1593333D01*
X1964000Y-1595334D01*
X1963000Y-1597000D01*
X1958000Y-1600333D01*
X1955750Y-1602667D01*
X1954250Y-1606001D01*
X1953750Y-1609000D01*
X1964250D01*
G01X1975750Y-1602334D02*
X1982250D01*
G01X1994250Y-1592333D02*
X1995750Y-1590334D01*
X1997500Y-1589333D01*
X1999500Y-1589000D01*
X2002000Y-1589667D01*
X2003750Y-1591333D01*
X2004250Y-1593333D01*
X2004000Y-1595334D01*
X2003000Y-1597000D01*
X1998000Y-1600333D01*
X1995750Y-1602667D01*
X1994250Y-1606001D01*
X1993750Y-1609000D01*
X2004250D01*
G01X2013500Y-1606001D02*
X2015000Y-1607667D01*
X2016750Y-1608667D01*
X2019000Y-1609000D01*
X2021250Y-1608333D01*
X2023000Y-1607000D01*
X2024250Y-1604667D01*
X2024500Y-1602000D01*
X2024000Y-1599334D01*
X2022750Y-1597667D01*
X2021000Y-1596334D01*
X2019250Y-1596000D01*
X2017500Y-1596334D01*
X2015250Y-1597667D01*
X2016000Y-1589000D01*
X2022750D01*
G01X1858627Y-1448882D02*
G02I-672J0D01*
G01X1875355Y-1468526D02*
G02I-1546J0D01*
G01X1876368Y-1456700D02*
G02I-1679J0D01*
G01X1871955Y-1471484D02*
G02I-1102J0D01*
G01X1867974Y-1459892D02*
G02I-947J0D01*
G01X1871883Y-1458435D02*
G02I-1361J0D01*
G01X1869167Y-1473846D02*
G02I-671J0D01*
G01X1876358Y-1441092D02*
G02I-1680J0D01*
G01X1879013Y-1448882D02*
G02I-2314J0D01*
G01X1871871Y-1439368D02*
G02I-1360J0D01*
G01X1862587Y-1448882D02*
G02I-1102J0D01*
G01X1867219D02*
G02I-1548J0D01*
G01X1872728D02*
G02I-1981J0D01*
G01X1875362Y-1429242D02*
G02I-1546J0D01*
G01X1865174Y-1436751D02*
G02I-671J0D01*
G01X1867963Y-1437911D02*
G02I-947J0D01*
G01X1871955Y-1426281D02*
G02I-1102J0D01*
G01X1883402Y-1475307D02*
G02I-946J0D01*
G01X1882013Y-1477878D02*
G02I-673J0D01*
G01X1894998Y-1476663D02*
G02I-1545J0D01*
G01X1894558Y-1480852D02*
G02I-1105J0D01*
G01X1887322Y-1467653D02*
G02I-1680J0D01*
G01X1895767Y-1465638D02*
G02I-2314J0D01*
G01X1896254Y-1459023D02*
G02I-2801J0D01*
G01X1883918Y-1460732D02*
G02I-2313J0D01*
G01X1889819Y-1462630D02*
G02I-2087J0D01*
G01X1889086Y-1456049D02*
G02I-2800J0D01*
G01X1885267Y-1471813D02*
G02I-1360J0D01*
G01X1895438Y-1471590D02*
G02I-1985J0D01*
G01X1879381Y-1464936D02*
G02I-1983J0D01*
G01X1896254Y-1438740D02*
G02I-2801J0D01*
G01X1881802Y-1454605D02*
G02I-2091J0D01*
G01X1889086Y-1441714D02*
G02I-2800J0D01*
G01X1881790Y-1443176D02*
G02I-2090J0D01*
G01X1886116Y-1448882D02*
G02I-2802J0D01*
G01X1889903Y-1435100D02*
G02I-2087J0D01*
G01X1883923Y-1437038D02*
G02I-2314J0D01*
G01X1885412Y-1425893D02*
G02I-1360J0D01*
G01X1887434Y-1430066D02*
G02I-1680J0D01*
G01X1895438Y-1426173D02*
G02I-1985J0D01*
G01X1895767Y-1432126D02*
G02I-2314J0D01*
G01X1879381Y-1432827D02*
G02I-1983J0D01*
G01X1894998Y-1421100D02*
G02I-1545J0D01*
G01X1894558Y-1416911D02*
G02I-1105J0D01*
G01X1907598Y-1477162D02*
G02I-670J0D01*
G01X1906496Y-1474911D02*
G02I-946J0D01*
G01X1894126Y-1484380D02*
G02I-673J0D01*
G01X1911493Y-1464936D02*
G02I-1983J0D01*
G01X1907612Y-1460725D02*
G02I-2313J0D01*
G01X1904980Y-1471573D02*
G02I-1361J0D01*
G01X1903136Y-1467637D02*
G02I-1680J0D01*
G01X1901278Y-1462624D02*
G02I-2090J0D01*
G01X1903423Y-1456049D02*
G02I-2800J0D01*
G01Y-1441714D02*
G02I-2800J0D01*
G01X1911493Y-1432827D02*
G02I-1983J0D01*
G01X1905529Y-1422506D02*
G02I-949J0D01*
G01X1907612Y-1437038D02*
G02I-2313J0D01*
G01X1901329Y-1435157D02*
G02I-2091J0D01*
G01X1903041Y-1430150D02*
G02I-1679J0D01*
G01X1904475Y-1425994D02*
G02I-1361J0D01*
G01X1906507Y-1419830D02*
G02I-672J0D01*
G01X1894126Y-1413383D02*
G02I-673J0D01*
G01X1924922Y-1457729D02*
G03X1931063Y-1454761I-1189J10298D01*
G01X1919488Y-1456387D02*
G03X1924922Y-1457729I4820J7843D01*
G01X1914639Y-1468521D02*
G02I-1546J0D01*
G01X1925329Y-1455818D02*
G02X1922008Y-1455310I-608J7138D01*
G01X1930060Y-1453479D02*
G02X1925329Y-1455818I-7363J8939D01*
G01X1916520Y-1452948D02*
G03X1919488Y-1456387I7684J3631D01*
G01X1916681Y-1444340D02*
G03X1916520Y-1452948I9517J-4484D01*
G01X1924726Y-1439861D02*
G03X1916681Y-1444340I-232J-9047D01*
G01X1930974Y-1442340D02*
G03X1924726Y-1439861I-6790J-8000D01*
G01X1924455Y-1441787D02*
G02X1929887Y-1443607I0J-9017D01*
G01X1918112Y-1446910D02*
G02X1924455Y-1441787I6291J-1301D01*
G01X1922008Y-1455310D02*
G02X1918112Y-1446910I3570J6759D01*
G01X1936175Y-1457305D02*
G03X1944141Y-1455621I2822J6334D01*
G01X1942654Y-1450260D02*
Y-1450241D01*
G01X1935105Y-1450260D02*
X1942654D01*
G01X1935105Y-1450241D02*
Y-1450260D01*
G01X1942654Y-1450241D02*
G03X1935105I-3775J169D01*
G01X1942784Y-1454282D02*
G02X1936178Y-1454858I-3590J3000D01*
G01X1944141Y-1455621D02*
G03X1942784Y-1454282I-867J479D01*
G01X1932808Y-1453020D02*
G03X1936175Y-1457305I6565J1693D01*
G01X1932808Y-1450703D02*
Y-1453020D01*
G01X1945013Y-1450703D02*
G03X1932808I-6103J236D01*
G01X1935108Y-1451799D02*
X1945013D01*
G01X1936178Y-1454858D02*
G02X1935108Y-1451799I3537J2954D01*
G01X1931063Y-1454761D02*
G03X1930060Y-1453479I-758J440D01*
G01X1929887Y-1443607D02*
G03X1930974Y-1442340I435J727D01*
G01X1956083Y-1457305D02*
G03X1964049Y-1455621I2822J6334D01*
G01X1955013Y-1450260D02*
X1962562D01*
G01X1955013Y-1450241D02*
Y-1450260D01*
G01X1962562Y-1450241D02*
G03X1955013I-3774J169D01*
G01X1955016Y-1451799D02*
X1964921D01*
G01X1956086Y-1454858D02*
G02X1955016Y-1451799I3537J2954D01*
G01X1962692Y-1454282D02*
G02X1956086Y-1454858I-3590J3000D01*
G01X1952716Y-1453020D02*
G03X1956083Y-1457305I6565J1693D01*
G01X1952716Y-1450703D02*
Y-1453020D01*
G01X1964921Y-1450703D02*
G03X1952716I-6102J236D01*
G01X1947820Y-1440308D02*
G02X1949965Y-1440315I1072J-257D01*
G01X1947820Y-1456844D02*
Y-1440308D01*
G01X1949965Y-1456844D02*
G02X1947820I-1073J253D01*
G01X1949965Y-1440315D02*
Y-1456844D01*
G01X1945013Y-1451799D02*
Y-1450703D01*
G01X1973539Y-1450360D02*
G02X1969860Y-1448867I1911J9989D01*
G01X1976453Y-1452712D02*
G03X1973539Y-1450360I-3681J-1579D01*
G01X1976296Y-1455619D02*
G03X1976453Y-1452712I-3334J1638D01*
G01X1973551Y-1457602D02*
G03X1976296Y-1455619I-1336J4741D01*
G01X1969271Y-1457333D02*
G03X1973551Y-1457602I2765J9804D01*
G01X1966741Y-1455590D02*
G03X1969271Y-1457333I3982J3072D01*
G01X1968512Y-1454621D02*
G03X1966741Y-1455590I-793J-654D01*
G01X1971419Y-1455926D02*
G02X1968512Y-1454621I259J4466D01*
G01X1971994Y-1455937D02*
G02X1971419Y-1455926I-192J4985D01*
G01X1974161Y-1455009D02*
G02X1971994Y-1455937I-2245J2248D01*
G01X1974277Y-1453346D02*
G02X1974161Y-1455009I-927J-771D01*
G01X1971859Y-1451922D02*
G02X1974277Y-1453346I-1337J-5035D01*
G01X1968925Y-1450910D02*
G03X1971859Y-1451922I8703J20473D01*
G01X1967420Y-1448489D02*
G03X1968925Y-1450910I2813J70D01*
G01X1967420Y-1446900D02*
Y-1448489D01*
G01X1969162Y-1444895D02*
G03X1967420Y-1446900I2913J-4290D01*
G01X1976273Y-1445965D02*
G03X1969162Y-1444895I-4404J-5102D01*
G01X1974918Y-1447291D02*
G03X1976273Y-1445965I635J707D01*
G01X1972802Y-1446305D02*
G02X1974918Y-1447291I-1190J-5318D01*
G01X1970118Y-1446581D02*
G02X1972802Y-1446305I1763J-3957D01*
G01X1969860Y-1448867D02*
G02X1970118Y-1446581I1112J1032D01*
G01X1979558Y-1446587D02*
G02X1979503Y-1444442I262J1080D01*
G01X1980590Y-1446587D02*
X1979558D01*
G01X1979503Y-1444442D02*
X1980590D01*
G01X1962562Y-1450260D02*
Y-1450241D01*
G01X1964049Y-1455621D02*
G03X1962692Y-1454282I-867J479D01*
G01X1964921Y-1451799D02*
Y-1450703D01*
G01X1988450Y1534500D02*
X1985930Y1533667D01*
X1984040Y1531583D01*
X1982780Y1529084D01*
X1981835Y1525750D01*
X1981520Y1522000D01*
X1981835Y1518250D01*
X1982780Y1514916D01*
X1984040Y1512416D01*
X1985930Y1510333D01*
X1988450Y1509500D01*
X1990970Y1510333D01*
X1992860Y1512416D01*
X1994120Y1514916D01*
X1995065Y1518250D01*
X1995380Y1522000D01*
X1995065Y1525750D01*
X1994120Y1529084D01*
X1992860Y1531583D01*
X1990970Y1533667D01*
X1988450Y1534500D01*
G01X2013650Y1509500D02*
Y1534500D01*
X2009870Y1529500D01*
G01Y1509500D02*
X2017429D01*
G01X1997020Y-1450948D02*
G02X1997447Y-1448685I6225J-3D01*
G01X1997020Y-1451877D02*
Y-1450948D01*
G01X1997435Y-1453322D02*
G02X1997020Y-1451877I3999J1930D01*
G01X1996428Y-1455590D02*
G03X2000335Y-1457613I4656J4209D01*
G01X1994987Y-1452539D02*
G03X1996428Y-1455590I6065J999D01*
G01X1994987Y-1450707D02*
Y-1452539D01*
G01X1995486Y-1447987D02*
G03X1994987Y-1450707I10590J-3349D01*
G01X2000303Y-1444278D02*
G03X1995486Y-1447987I1335J-6717D01*
G01X1992271Y-1440634D02*
G02I-1265J0D01*
G01X1980590Y-1455164D02*
Y-1446587D01*
G01X1983995Y-1457613D02*
G02X1980590Y-1455164I-269J3217D01*
G01X1985372Y-1457613D02*
X1983995D01*
G01X1986856Y-1456577D02*
G02X1985372Y-1457613I-1509J580D01*
G01X1985943Y-1455470D02*
G02X1986856Y-1456577I104J-844D01*
G01X1982736Y-1454550D02*
G03X1985943Y-1455470I2170J1514D01*
G01X1982736Y-1446587D02*
Y-1454550D01*
G01X1985945Y-1446587D02*
X1982736D01*
G01X1985950Y-1444442D02*
G02X1985945Y-1446587I-192J-1072D01*
G01X1982736Y-1444442D02*
X1985950D01*
G01X1982729Y-1441776D02*
X1982736Y-1444442D01*
G01X1980590Y-1441853D02*
G02X1982729Y-1441776I1074J-74D01*
G01X1980590Y-1444442D02*
Y-1441853D01*
G01X1989779Y-1445359D02*
Y-1456693D01*
G01X1992227Y-1445359D02*
G03X1989779I-1224J-434D01*
G01X1992227Y-1456693D02*
Y-1445359D01*
G01X1989779Y-1456693D02*
G03X1992227I1224J207D01*
G01X2016046Y-1455778D02*
X2013361D01*
G01Y-1451183D02*
X2016122D01*
G01X2013361Y-1455778D02*
G02Y-1451183I204J2298D01*
G01X2013053Y-1444442D02*
X2016732D01*
G01X2010455Y-1445665D02*
G02X2013053Y-1444442I3218J-3465D01*
G01X2011205Y-1447187D02*
G02X2010455Y-1445665I-130J882D01*
G01X2012443Y-1446587D02*
G03X2011205Y-1447187I1530J-4735D01*
G01X2016424Y-1446587D02*
X2012443D01*
G01X2014449Y-1449325D02*
G02X2018261Y-1449648I361J-18399D01*
G01X2012107Y-1449650D02*
G02X2014449Y-1449325I2637J-10399D01*
G01X2012140Y-1457613D02*
G02X2012107Y-1449650I880J3985D01*
G01X2015814Y-1457613D02*
X2012140D01*
G01X2003613Y-1446848D02*
G02X2004856Y-1447987I-8597J-10630D01*
G01X2000828Y-1446148D02*
G02X2003613Y-1446848I332J-4570D01*
G01X1997447Y-1448685D02*
G02X2000828Y-1446148I4085J-1923D01*
G01X1999613Y-1455435D02*
G02X1997435Y-1453322I2138J4383D01*
G01X2002391Y-1455836D02*
G02X1999613Y-1455435I-717J4853D01*
G01X2004996Y-1454284D02*
G02X2002391Y-1455836I-3653J3170D01*
G01X2006306Y-1455659D02*
G03X2004996Y-1454284I-736J610D01*
G01X2005588Y-1456352D02*
X2006306Y-1455659D01*
G01X2002301Y-1457613D02*
G03X2005588Y-1456352I0J4916D01*
G01X2000335Y-1457613D02*
X2002301D01*
G01X2001765Y-1444278D02*
X2000303D01*
G01X2006519Y-1446748D02*
G03X2001765Y-1444278I-5065J-3938D01*
G01X2004856Y-1447987D02*
G03X2006519Y-1446748I619J904D01*
G01X2020406Y-1456844D02*
G02X2018261I-1073J194D01*
G01X2026573Y-1447212D02*
X2026336D01*
G01X2027187Y-1445437D02*
X2026573Y-1447212D01*
G01X2027486D02*
X2027187Y-1445437D01*
G01X2028061Y-1447212D02*
X2027486D01*
G01X2027479Y-1444515D02*
X2028061Y-1447212D01*
G01X2027019Y-1444515D02*
X2027479D01*
G01X2026448Y-1446245D02*
X2027019Y-1444515D01*
G01X2025871D02*
X2026448Y-1446245D01*
G01X2025442Y-1444515D02*
X2025871D01*
G01X2024863Y-1447212D02*
X2025442Y-1444515D01*
G01X2025423Y-1447212D02*
X2024863D01*
G01X2025715Y-1445455D02*
X2025423Y-1447212D01*
G01X2026336D02*
X2025715Y-1445455D01*
G01X2022238Y-1445052D02*
X2023133D01*
G01X2022238Y-1444515D02*
Y-1445052D01*
G01X2024613Y-1444515D02*
X2022238D01*
G01X2024613Y-1445052D02*
Y-1444515D01*
G01X2023715Y-1445052D02*
X2024613D01*
G01X2023715Y-1447201D02*
Y-1445052D01*
G01X2023133Y-1447201D02*
X2023715D01*
G01X2023133Y-1445052D02*
Y-1447201D01*
G01X2016122Y-1451183D02*
G02X2016046Y-1455778I0J-2298D01*
G01X2016732Y-1444442D02*
G02X2020406Y-1448114I-528J-4202D01*
G01X2018261Y-1448423D02*
G03X2016424Y-1446587I-1696J140D01*
G01X2018261Y-1449648D02*
Y-1448423D01*
G01Y-1456420D02*
G02X2015814Y-1457613I-3601J4281D01*
G01X2018261Y-1456844D02*
Y-1456420D01*
G01X2020406Y-1448114D02*
Y-1456844D01*
G54D14*
G01X-2006444Y-241106D02*
X-2004911D01*
Y-242966D01*
X-2005371Y-243586D01*
X-2005907Y-243999D01*
X-2006674Y-244206D01*
X-2007441Y-243999D01*
X-2007977Y-243586D01*
X-2008437Y-242966D01*
X-2008744Y-242243D01*
X-2008897Y-241416D01*
Y-240693D01*
X-2008744Y-240073D01*
X-2008437Y-239349D01*
X-2007977Y-238729D01*
X-2007517Y-238316D01*
X-2006904Y-238006D01*
X-2006367D01*
X-2005754Y-238213D01*
X-2005294Y-238626D01*
G01X-2002314Y-244206D02*
Y-238006D01*
G01X-1999094D02*
Y-244206D01*
G01Y-241106D02*
X-2002314D01*
G01X-1996191Y-242966D02*
X-1995731Y-243689D01*
X-1995117Y-244103D01*
X-1994427Y-244206D01*
X-1993814Y-244103D01*
X-1993201Y-243586D01*
X-1992817Y-242966D01*
X-1992741Y-242346D01*
X-1992894Y-241623D01*
X-1993431Y-241106D01*
X-1993967Y-240899D01*
X-1994657D01*
G01X-1993967D02*
X-1993507Y-240589D01*
X-1993124Y-240073D01*
X-1992971Y-239453D01*
X-1993124Y-238833D01*
X-1993507Y-238316D01*
X-1994197Y-238006D01*
X-1994887Y-238109D01*
X-1995577Y-238523D01*
G01X-2002444Y-175962D02*
X-2000911D01*
Y-177822D01*
X-2001371Y-178442D01*
X-2001907Y-178855D01*
X-2002674Y-179062D01*
X-2003441Y-178855D01*
X-2003977Y-178442D01*
X-2004437Y-177822D01*
X-2004744Y-177099D01*
X-2004897Y-176272D01*
Y-175549D01*
X-2004744Y-174929D01*
X-2004437Y-174205D01*
X-2003977Y-173585D01*
X-2003517Y-173172D01*
X-2002904Y-172862D01*
X-2002367D01*
X-2001754Y-173069D01*
X-2001294Y-173482D01*
G01X-1998314Y-179062D02*
Y-172862D01*
G01X-1995094D02*
Y-179062D01*
G01Y-175962D02*
X-1998314D01*
G01X-1990504Y-179062D02*
Y-172862D01*
X-1991424Y-174102D01*
G01Y-179062D02*
X-1989584D01*
G01X-1995604Y-166949D02*
X-2001804D01*
Y-165415D01*
X-2001494Y-164802D01*
X-2001081Y-164342D01*
X-2000461Y-163959D01*
X-1999737Y-163652D01*
X-1998704Y-163575D01*
X-1997671Y-163652D01*
X-1996947Y-163959D01*
X-1996327Y-164342D01*
X-1995914Y-164802D01*
X-1995604Y-165415D01*
Y-166949D01*
G01X-1996430Y-160672D02*
X-1995914Y-160059D01*
X-1995604Y-159369D01*
Y-158755D01*
X-1995914Y-158142D01*
X-1996430Y-157682D01*
X-1997154Y-157452D01*
X-1997877Y-157605D01*
X-1998497Y-157989D01*
X-1998911Y-158679D01*
X-1999117Y-159599D01*
X-1999531Y-160135D01*
X-2000254Y-160365D01*
X-2000977Y-160212D01*
X-2001494Y-159829D01*
X-2001804Y-159292D01*
Y-158755D01*
X-2001597Y-158219D01*
X-2001081Y-157759D01*
G01X-1995604Y-152862D02*
X-2001804D01*
X-2000564Y-153782D01*
G01X-1995604D02*
Y-151942D01*
G01X-1996534Y-148349D02*
X-1996017Y-147889D01*
X-1995707Y-147352D01*
X-1995604Y-146662D01*
X-1995811Y-145972D01*
X-1996224Y-145435D01*
X-1996947Y-145052D01*
X-1997774Y-144975D01*
X-1998601Y-145129D01*
X-1999117Y-145512D01*
X-1999531Y-146049D01*
X-1999634Y-146585D01*
X-1999531Y-147122D01*
X-1999117Y-147812D01*
X-2001804Y-147582D01*
Y-145512D01*
G01X-2006444Y-127044D02*
X-2004911D01*
Y-128904D01*
X-2005371Y-129524D01*
X-2005907Y-129937D01*
X-2006674Y-130144D01*
X-2007441Y-129937D01*
X-2007977Y-129524D01*
X-2008437Y-128904D01*
X-2008744Y-128181D01*
X-2008897Y-127354D01*
Y-126631D01*
X-2008744Y-126011D01*
X-2008437Y-125287D01*
X-2007977Y-124667D01*
X-2007517Y-124254D01*
X-2006904Y-123944D01*
X-2006367D01*
X-2005754Y-124151D01*
X-2005294Y-124564D01*
G01X-2002314Y-130144D02*
Y-123944D01*
G01X-1999094D02*
Y-130144D01*
G01Y-127044D02*
X-2002314D01*
G01X-1996191Y-128904D02*
X-1995731Y-129627D01*
X-1995117Y-130041D01*
X-1994427Y-130144D01*
X-1993814Y-130041D01*
X-1993201Y-129524D01*
X-1992817Y-128904D01*
X-1992741Y-128284D01*
X-1992894Y-127561D01*
X-1993431Y-127044D01*
X-1993967Y-126837D01*
X-1994657D01*
G01X-1993967D02*
X-1993507Y-126527D01*
X-1993124Y-126011D01*
X-1992971Y-125391D01*
X-1993124Y-124771D01*
X-1993507Y-124254D01*
X-1994197Y-123944D01*
X-1994887Y-124047D01*
X-1995577Y-124461D01*
G01X-2005444Y-61962D02*
X-2003911D01*
Y-63822D01*
X-2004371Y-64442D01*
X-2004907Y-64855D01*
X-2005674Y-65062D01*
X-2006441Y-64855D01*
X-2006977Y-64442D01*
X-2007437Y-63822D01*
X-2007744Y-63099D01*
X-2007897Y-62272D01*
Y-61549D01*
X-2007744Y-60929D01*
X-2007437Y-60205D01*
X-2006977Y-59585D01*
X-2006517Y-59172D01*
X-2005904Y-58862D01*
X-2005367D01*
X-2004754Y-59069D01*
X-2004294Y-59482D01*
G01X-2001314Y-65062D02*
Y-58862D01*
G01X-1998094D02*
Y-65062D01*
G01Y-61962D02*
X-2001314D01*
G01X-1993504Y-65062D02*
Y-58862D01*
X-1994424Y-60102D01*
G01Y-65062D02*
X-1992584D01*
G01X-1995604Y-50949D02*
X-2001804D01*
Y-49415D01*
X-2001494Y-48802D01*
X-2001081Y-48342D01*
X-2000461Y-47959D01*
X-1999737Y-47652D01*
X-1998704Y-47575D01*
X-1997671Y-47652D01*
X-1996947Y-47959D01*
X-1996327Y-48342D01*
X-1995914Y-48802D01*
X-1995604Y-49415D01*
Y-50949D01*
G01X-1996430Y-44672D02*
X-1995914Y-44059D01*
X-1995604Y-43369D01*
Y-42755D01*
X-1995914Y-42142D01*
X-1996430Y-41682D01*
X-1997154Y-41452D01*
X-1997877Y-41605D01*
X-1998497Y-41989D01*
X-1998911Y-42679D01*
X-1999117Y-43599D01*
X-1999531Y-44135D01*
X-2000254Y-44365D01*
X-2000977Y-44212D01*
X-2001494Y-43829D01*
X-2001804Y-43292D01*
Y-42755D01*
X-2001597Y-42219D01*
X-2001081Y-41759D01*
G01X-1995604Y-36862D02*
X-2001804D01*
X-2000564Y-37782D01*
G01X-1995604D02*
Y-35942D01*
G01Y-29742D02*
X-2001804D01*
X-1997361Y-32579D01*
Y-28745D01*
G01X-2004444Y-12980D02*
X-2002911D01*
Y-14840D01*
X-2003371Y-15460D01*
X-2003907Y-15873D01*
X-2004674Y-16080D01*
X-2005441Y-15873D01*
X-2005977Y-15460D01*
X-2006437Y-14840D01*
X-2006744Y-14117D01*
X-2006897Y-13290D01*
Y-12567D01*
X-2006744Y-11947D01*
X-2006437Y-11223D01*
X-2005977Y-10603D01*
X-2005517Y-10190D01*
X-2004904Y-9880D01*
X-2004367D01*
X-2003754Y-10087D01*
X-2003294Y-10500D01*
G01X-2000314Y-16080D02*
Y-9880D01*
G01X-1997094D02*
Y-16080D01*
G01Y-12980D02*
X-2000314D01*
G01X-1994191Y-14840D02*
X-1993731Y-15563D01*
X-1993117Y-15977D01*
X-1992427Y-16080D01*
X-1991814Y-15977D01*
X-1991201Y-15460D01*
X-1990817Y-14840D01*
X-1990741Y-14220D01*
X-1990894Y-13497D01*
X-1991431Y-12980D01*
X-1991967Y-12773D01*
X-1992657D01*
G01X-1991967D02*
X-1991507Y-12463D01*
X-1991124Y-11947D01*
X-1990971Y-11327D01*
X-1991124Y-10707D01*
X-1991507Y-10190D01*
X-1992197Y-9880D01*
X-1992887Y-9983D01*
X-1993577Y-10397D01*
G01X-2004444Y54038D02*
X-2002911D01*
Y52178D01*
X-2003371Y51558D01*
X-2003907Y51145D01*
X-2004674Y50938D01*
X-2005441Y51145D01*
X-2005977Y51558D01*
X-2006437Y52178D01*
X-2006744Y52901D01*
X-2006897Y53728D01*
Y54451D01*
X-2006744Y55071D01*
X-2006437Y55795D01*
X-2005977Y56415D01*
X-2005517Y56828D01*
X-2004904Y57138D01*
X-2004367D01*
X-2003754Y56931D01*
X-2003294Y56518D01*
G01X-2000314Y50938D02*
Y57138D01*
G01X-1997094D02*
Y50938D01*
G01Y54038D02*
X-2000314D01*
G01X-1992504Y50938D02*
Y57138D01*
X-1993424Y55898D01*
G01Y50938D02*
X-1991584D01*
G01X-1995604Y62051D02*
X-2001804D01*
Y63585D01*
X-2001494Y64198D01*
X-2001081Y64658D01*
X-2000461Y65041D01*
X-1999737Y65348D01*
X-1998704Y65425D01*
X-1997671Y65348D01*
X-1996947Y65041D01*
X-1996327Y64658D01*
X-1995914Y64198D01*
X-1995604Y63585D01*
Y62051D01*
G01X-1996430Y68328D02*
X-1995914Y68941D01*
X-1995604Y69631D01*
Y70245D01*
X-1995914Y70858D01*
X-1996430Y71318D01*
X-1997154Y71548D01*
X-1997877Y71395D01*
X-1998497Y71011D01*
X-1998911Y70321D01*
X-1999117Y69401D01*
X-1999531Y68865D01*
X-2000254Y68635D01*
X-2000977Y68788D01*
X-2001494Y69171D01*
X-2001804Y69708D01*
Y70245D01*
X-2001597Y70781D01*
X-2001081Y71241D01*
G01X-1995604Y76138D02*
X-2001804D01*
X-2000564Y75218D01*
G01X-1995604D02*
Y77058D01*
G01Y82185D02*
X-1996947Y82338D01*
X-1998084Y82568D01*
X-1999117Y82875D01*
X-2000254Y83258D01*
X-2001804Y83871D01*
Y80805D01*
G01X-2003444Y101084D02*
X-2001911D01*
Y99224D01*
X-2002371Y98604D01*
X-2002907Y98191D01*
X-2003674Y97984D01*
X-2004441Y98191D01*
X-2004977Y98604D01*
X-2005437Y99224D01*
X-2005744Y99947D01*
X-2005897Y100774D01*
Y101497D01*
X-2005744Y102117D01*
X-2005437Y102841D01*
X-2004977Y103461D01*
X-2004517Y103874D01*
X-2003904Y104184D01*
X-2003367D01*
X-2002754Y103977D01*
X-2002294Y103564D01*
G01X-1999314Y97984D02*
Y104184D01*
G01X-1996094D02*
Y97984D01*
G01Y101084D02*
X-1999314D01*
G01X-1993191Y99224D02*
X-1992731Y98501D01*
X-1992117Y98087D01*
X-1991427Y97984D01*
X-1990814Y98087D01*
X-1990201Y98604D01*
X-1989817Y99224D01*
X-1989741Y99844D01*
X-1989894Y100567D01*
X-1990431Y101084D01*
X-1990967Y101291D01*
X-1991657D01*
G01X-1990967D02*
X-1990507Y101601D01*
X-1990124Y102117D01*
X-1989971Y102737D01*
X-1990124Y103357D01*
X-1990507Y103874D01*
X-1991197Y104184D01*
X-1991887Y104081D01*
X-1992577Y103667D01*
G01X-2004444Y167038D02*
X-2002911D01*
Y165178D01*
X-2003371Y164558D01*
X-2003907Y164145D01*
X-2004674Y163938D01*
X-2005441Y164145D01*
X-2005977Y164558D01*
X-2006437Y165178D01*
X-2006744Y165901D01*
X-2006897Y166728D01*
Y167451D01*
X-2006744Y168071D01*
X-2006437Y168795D01*
X-2005977Y169415D01*
X-2005517Y169828D01*
X-2004904Y170138D01*
X-2004367D01*
X-2003754Y169931D01*
X-2003294Y169518D01*
G01X-2000314Y163938D02*
Y170138D01*
G01X-1997094D02*
Y163938D01*
G01Y167038D02*
X-2000314D01*
G01X-1992504Y163938D02*
Y170138D01*
X-1993424Y168898D01*
G01Y163938D02*
X-1991584D01*
G01X-1995604Y178051D02*
X-2001804D01*
Y179585D01*
X-2001494Y180198D01*
X-2001081Y180658D01*
X-2000461Y181041D01*
X-1999737Y181348D01*
X-1998704Y181425D01*
X-1997671Y181348D01*
X-1996947Y181041D01*
X-1996327Y180658D01*
X-1995914Y180198D01*
X-1995604Y179585D01*
Y178051D01*
G01X-1996430Y184328D02*
X-1995914Y184941D01*
X-1995604Y185631D01*
Y186245D01*
X-1995914Y186858D01*
X-1996430Y187318D01*
X-1997154Y187548D01*
X-1997877Y187395D01*
X-1998497Y187011D01*
X-1998911Y186321D01*
X-1999117Y185401D01*
X-1999531Y184865D01*
X-2000254Y184635D01*
X-2000977Y184788D01*
X-2001494Y185171D01*
X-2001804Y185708D01*
Y186245D01*
X-2001597Y186781D01*
X-2001081Y187241D01*
G01X-1995604Y192138D02*
X-2001804D01*
X-2000564Y191218D01*
G01X-1995604D02*
Y193058D01*
G01X-1998187Y196881D02*
X-1998911Y197418D01*
X-1999324Y197878D01*
X-1999531Y198491D01*
X-1999324Y199028D01*
X-1998911Y199411D01*
X-1998291Y199718D01*
X-1997567Y199795D01*
X-1996947Y199718D01*
X-1996327Y199411D01*
X-1995811Y198951D01*
X-1995604Y198415D01*
X-1995811Y197801D01*
X-1996430Y197265D01*
X-1997361Y196958D01*
X-1998394Y196881D01*
X-1999737Y197035D01*
X-2000461Y197265D01*
X-2001184Y197648D01*
X-2001701Y198185D01*
X-2001804Y198721D01*
X-2001597Y199258D01*
X-2001081Y199641D01*
G01X-1993136Y280724D02*
X-1999336D01*
X-1998096Y279804D01*
G01X-1993136D02*
Y281644D01*
G01X-1996604Y288051D02*
X-2002804D01*
Y289585D01*
X-2002494Y290198D01*
X-2002081Y290658D01*
X-2001461Y291041D01*
X-2000737Y291348D01*
X-1999704Y291425D01*
X-1998671Y291348D01*
X-1997947Y291041D01*
X-1997327Y290658D01*
X-1996914Y290198D01*
X-1996604Y289585D01*
Y288051D01*
G01X-1997430Y294328D02*
X-1996914Y294941D01*
X-1996604Y295631D01*
Y296245D01*
X-1996914Y296858D01*
X-1997430Y297318D01*
X-1998154Y297548D01*
X-1998877Y297395D01*
X-1999497Y297011D01*
X-1999911Y296321D01*
X-2000117Y295401D01*
X-2000531Y294865D01*
X-2001254Y294635D01*
X-2001977Y294788D01*
X-2002494Y295171D01*
X-2002804Y295708D01*
Y296245D01*
X-2002597Y296781D01*
X-2002081Y297241D01*
G01X-1996604Y302138D02*
X-2002804D01*
X-2001564Y301218D01*
G01X-1996604D02*
Y303058D01*
G01Y308338D02*
X-1996707Y308875D01*
X-1997017Y309488D01*
X-1997534Y309871D01*
X-1998257Y310025D01*
X-1998981Y309871D01*
X-1999601Y309411D01*
X-1999911Y308721D01*
Y307955D01*
X-2000117Y307495D01*
X-2000634Y307111D01*
X-2001357Y306958D01*
X-2002081Y307188D01*
X-2002597Y307725D01*
X-2002804Y308338D01*
X-2002597Y308951D01*
X-2002081Y309488D01*
X-2001357Y309718D01*
X-2000634Y309565D01*
X-2000117Y309181D01*
X-1999911Y308721D01*
Y307955D01*
X-1999601Y307265D01*
X-1998981Y306805D01*
X-1998257Y306651D01*
X-1997534Y306805D01*
X-1997017Y307188D01*
X-1996707Y307801D01*
X-1996604Y308338D01*
G01X-1983259Y-210302D02*
X-1982876Y-210922D01*
X-1982416Y-211335D01*
X-1981879Y-211542D01*
X-1981266Y-211335D01*
X-1980806Y-210922D01*
X-1980346Y-210302D01*
X-1980193Y-209475D01*
Y-205342D01*
G01X-1976983Y-206375D02*
X-1976523Y-205755D01*
X-1975986Y-205445D01*
X-1975373Y-205342D01*
X-1974606Y-205549D01*
X-1974069Y-206065D01*
X-1973916Y-206685D01*
X-1973993Y-207305D01*
X-1974299Y-207822D01*
X-1975833Y-208855D01*
X-1976523Y-209579D01*
X-1976983Y-210612D01*
X-1977136Y-211542D01*
X-1973916D01*
G01X-1986704Y-171062D02*
Y-164862D01*
X-1987624Y-166102D01*
G01Y-171062D02*
X-1985784D01*
G01X-1989161Y-157615D02*
X-1988701Y-156995D01*
X-1988164Y-156685D01*
X-1987551Y-156582D01*
X-1986784Y-156789D01*
X-1986247Y-157305D01*
X-1986094Y-157925D01*
X-1986171Y-158545D01*
X-1986477Y-159062D01*
X-1988011Y-160095D01*
X-1988701Y-160819D01*
X-1989161Y-161852D01*
X-1989314Y-162782D01*
X-1986094D01*
G01X-1989391Y-152542D02*
X-1988931Y-153265D01*
X-1988317Y-153679D01*
X-1987627Y-153782D01*
X-1987014Y-153679D01*
X-1986401Y-153162D01*
X-1986017Y-152542D01*
X-1985941Y-151922D01*
X-1986094Y-151199D01*
X-1986631Y-150682D01*
X-1987167Y-150475D01*
X-1987857D01*
G01X-1987167D02*
X-1986707Y-150165D01*
X-1986324Y-149649D01*
X-1986171Y-149029D01*
X-1986324Y-148409D01*
X-1986707Y-147892D01*
X-1987397Y-147582D01*
X-1988087Y-147685D01*
X-1988777Y-148099D01*
G01X-1986784Y-144782D02*
Y-138582D01*
X-1989621Y-143025D01*
X-1985787D01*
G01X-1983259Y-96130D02*
X-1982876Y-96750D01*
X-1982416Y-97163D01*
X-1981879Y-97370D01*
X-1981266Y-97163D01*
X-1980806Y-96750D01*
X-1980346Y-96130D01*
X-1980193Y-95303D01*
Y-91170D01*
G01X-1975526Y-97370D02*
Y-91170D01*
X-1976446Y-92410D01*
G01Y-97370D02*
X-1974606D01*
G01X-1988704Y-59062D02*
Y-52862D01*
X-1989624Y-54102D01*
G01Y-59062D02*
X-1987784D01*
G01X-1990161Y-44895D02*
X-1989701Y-44275D01*
X-1989164Y-43965D01*
X-1988551Y-43862D01*
X-1987784Y-44069D01*
X-1987247Y-44585D01*
X-1987094Y-45205D01*
X-1987171Y-45825D01*
X-1987477Y-46342D01*
X-1989011Y-47375D01*
X-1989701Y-48099D01*
X-1990161Y-49132D01*
X-1990314Y-50062D01*
X-1987094D01*
G01X-1991391Y-38822D02*
X-1990931Y-39545D01*
X-1990317Y-39959D01*
X-1989627Y-40062D01*
X-1989014Y-39959D01*
X-1988401Y-39442D01*
X-1988017Y-38822D01*
X-1987941Y-38202D01*
X-1988094Y-37479D01*
X-1988631Y-36962D01*
X-1989167Y-36755D01*
X-1989857D01*
G01X-1989167D02*
X-1988707Y-36445D01*
X-1988324Y-35929D01*
X-1988171Y-35309D01*
X-1988324Y-34689D01*
X-1988707Y-34172D01*
X-1989397Y-33862D01*
X-1990087Y-33965D01*
X-1990777Y-34379D01*
G01X-1988784Y-30718D02*
Y-24518D01*
X-1991621Y-28961D01*
X-1987787D01*
G01X-1983259Y18044D02*
X-1982876Y17424D01*
X-1982416Y17011D01*
X-1981879Y16804D01*
X-1981266Y17011D01*
X-1980806Y17424D01*
X-1980346Y18044D01*
X-1980193Y18871D01*
Y23004D01*
G01X-1974606Y16804D02*
Y23004D01*
X-1977443Y18561D01*
X-1973609D01*
G01X-1989704Y59938D02*
Y66138D01*
X-1990624Y64898D01*
G01Y59938D02*
X-1988784D01*
G01X-1991161Y73513D02*
X-1990701Y74133D01*
X-1990164Y74443D01*
X-1989551Y74546D01*
X-1988784Y74339D01*
X-1988247Y73823D01*
X-1988094Y73203D01*
X-1988171Y72583D01*
X-1988477Y72066D01*
X-1990011Y71033D01*
X-1990701Y70309D01*
X-1991161Y69276D01*
X-1991314Y68346D01*
X-1988094D01*
G01X-1991391Y77586D02*
X-1990931Y76863D01*
X-1990317Y76449D01*
X-1989627Y76346D01*
X-1989014Y76449D01*
X-1988401Y76966D01*
X-1988017Y77586D01*
X-1987941Y78206D01*
X-1988094Y78929D01*
X-1988631Y79446D01*
X-1989167Y79653D01*
X-1989857D01*
G01X-1989167D02*
X-1988707Y79963D01*
X-1988324Y80479D01*
X-1988171Y81099D01*
X-1988324Y81719D01*
X-1988707Y82236D01*
X-1989397Y82546D01*
X-1990087Y82443D01*
X-1990777Y82029D01*
G01X-1988784Y84346D02*
Y90546D01*
X-1991621Y86103D01*
X-1987787D01*
G01X-1974836Y87386D02*
Y93586D01*
X-1977673Y89143D01*
X-1973839D01*
G01X-1983259Y132218D02*
X-1982876Y131598D01*
X-1982416Y131185D01*
X-1981879Y130978D01*
X-1981266Y131185D01*
X-1980806Y131598D01*
X-1980346Y132218D01*
X-1980193Y133045D01*
Y137178D01*
G01X-1977213Y132218D02*
X-1976753Y131495D01*
X-1976139Y131081D01*
X-1975449Y130978D01*
X-1974836Y131081D01*
X-1974223Y131598D01*
X-1973839Y132218D01*
X-1973763Y132838D01*
X-1973916Y133561D01*
X-1974453Y134078D01*
X-1974989Y134285D01*
X-1975679D01*
G01X-1974989D02*
X-1974529Y134595D01*
X-1974146Y135111D01*
X-1973993Y135731D01*
X-1974146Y136351D01*
X-1974529Y136868D01*
X-1975219Y137178D01*
X-1975909Y137075D01*
X-1976599Y136661D01*
G01X-1988704Y170938D02*
Y177138D01*
X-1989624Y175898D01*
G01Y170938D02*
X-1987784D01*
G01X-1991161Y184575D02*
X-1990701Y185195D01*
X-1990164Y185505D01*
X-1989551Y185608D01*
X-1988784Y185401D01*
X-1988247Y184885D01*
X-1988094Y184265D01*
X-1988171Y183645D01*
X-1988477Y183128D01*
X-1990011Y182095D01*
X-1990701Y181371D01*
X-1991161Y180338D01*
X-1991314Y179408D01*
X-1988094D01*
G01X-1991391Y189648D02*
X-1990931Y188925D01*
X-1990317Y188511D01*
X-1989627Y188408D01*
X-1989014Y188511D01*
X-1988401Y189028D01*
X-1988017Y189648D01*
X-1987941Y190268D01*
X-1988094Y190991D01*
X-1988631Y191508D01*
X-1989167Y191715D01*
X-1989857D01*
G01X-1989167D02*
X-1988707Y192025D01*
X-1988324Y192541D01*
X-1988171Y193161D01*
X-1988324Y193781D01*
X-1988707Y194298D01*
X-1989397Y194608D01*
X-1990087Y194505D01*
X-1990777Y194091D01*
G01X-1988784Y196408D02*
Y202608D01*
X-1991621Y198165D01*
X-1987787D01*
G01X-1973672Y280205D02*
X-1979872D01*
Y282121D01*
X-1979562Y282735D01*
X-1979149Y283118D01*
X-1978322Y283271D01*
X-1977495Y283118D01*
X-1976979Y282658D01*
X-1976669Y282121D01*
Y280205D01*
G01Y282121D02*
X-1973672Y283271D01*
G01X-1974912Y286251D02*
X-1974189Y286711D01*
X-1973775Y287325D01*
X-1973672Y288015D01*
X-1973775Y288628D01*
X-1974292Y289241D01*
X-1974912Y289625D01*
X-1975532Y289701D01*
X-1976255Y289548D01*
X-1976772Y289011D01*
X-1976979Y288475D01*
Y287785D01*
G01Y288475D02*
X-1977289Y288935D01*
X-1977805Y289318D01*
X-1978425Y289471D01*
X-1979045Y289318D01*
X-1979562Y288935D01*
X-1979872Y288245D01*
X-1979769Y287555D01*
X-1979355Y286865D01*
G01X-1974395Y292835D02*
X-1973879Y293371D01*
X-1973672Y293985D01*
X-1973879Y294598D01*
X-1974498Y295135D01*
X-1975429Y295518D01*
X-1976359Y295671D01*
X-1977495D01*
X-1978425Y295518D01*
X-1979252Y295135D01*
X-1979665Y294675D01*
X-1979872Y294138D01*
X-1979665Y293525D01*
X-1979252Y293065D01*
X-1978632Y292758D01*
X-1977805Y292605D01*
X-1977082Y292758D01*
X-1976359Y293141D01*
X-1975945Y293601D01*
X-1975842Y294138D01*
X-1976049Y294751D01*
X-1976565Y295211D01*
X-1977495Y295671D01*
G01X-1973672Y300185D02*
X-1975015Y300338D01*
X-1976152Y300568D01*
X-1977185Y300875D01*
X-1978322Y301258D01*
X-1979872Y301871D01*
Y298805D01*
G01X-1987238Y301645D02*
X-1986515Y302105D01*
X-1986101Y302719D01*
X-1985998Y303409D01*
X-1986101Y304022D01*
X-1986618Y304635D01*
X-1987238Y305019D01*
X-1987858Y305095D01*
X-1988581Y304942D01*
X-1989098Y304405D01*
X-1989305Y303869D01*
Y303179D01*
G01Y303869D02*
X-1989615Y304329D01*
X-1990131Y304712D01*
X-1990751Y304865D01*
X-1991371Y304712D01*
X-1991888Y304329D01*
X-1992198Y303639D01*
X-1992095Y302949D01*
X-1991681Y302259D01*
G01X-1990981Y293829D02*
X-1991601Y294289D01*
X-1991911Y294826D01*
X-1992014Y295439D01*
X-1991807Y296206D01*
X-1991291Y296743D01*
X-1990671Y296896D01*
X-1990051Y296819D01*
X-1989534Y296513D01*
X-1988501Y294979D01*
X-1987777Y294289D01*
X-1986744Y293829D01*
X-1985814Y293676D01*
Y296896D01*
G01X-1988604Y313958D02*
X-1994804D01*
X-1990361Y311121D01*
Y314955D01*
G01X-1978291Y309245D02*
X-1977984Y309555D01*
X-1977754Y310071D01*
X-1977601Y310795D01*
X-1977754Y311415D01*
X-1978061Y311828D01*
X-1978597Y312138D01*
X-1980667D01*
Y305938D01*
X-1978137D01*
X-1977601Y306351D01*
X-1977294Y306971D01*
X-1977141Y307695D01*
X-1977294Y308418D01*
X-1977754Y309038D01*
X-1978291Y309245D01*
X-1980667D01*
G01X-1972704Y305938D02*
Y312138D01*
X-1973624Y310898D01*
G01Y305938D02*
X-1971784D01*
G01X-1967961Y311105D02*
X-1967501Y311725D01*
X-1966964Y312035D01*
X-1966351Y312138D01*
X-1965584Y311931D01*
X-1965047Y311415D01*
X-1964894Y310795D01*
X-1964971Y310175D01*
X-1965277Y309658D01*
X-1966811Y308625D01*
X-1967501Y307901D01*
X-1967961Y306868D01*
X-1968114Y305938D01*
X-1964894D01*
G01X-1983437Y332178D02*
X-1983054Y331558D01*
X-1982594Y331145D01*
X-1982057Y330938D01*
X-1981444Y331145D01*
X-1980984Y331558D01*
X-1980524Y332178D01*
X-1980371Y333005D01*
Y337138D01*
G01X-1975704Y330938D02*
Y337138D01*
X-1976624Y335898D01*
G01Y330938D02*
X-1974784D01*
G01X-1971191Y332178D02*
X-1970731Y331455D01*
X-1970117Y331041D01*
X-1969427Y330938D01*
X-1968814Y331041D01*
X-1968201Y331558D01*
X-1967817Y332178D01*
X-1967741Y332798D01*
X-1967894Y333521D01*
X-1968431Y334038D01*
X-1968967Y334245D01*
X-1969657D01*
G01X-1968967D02*
X-1968507Y334555D01*
X-1968124Y335071D01*
X-1967971Y335691D01*
X-1968124Y336311D01*
X-1968507Y336828D01*
X-1969197Y337138D01*
X-1969887Y337035D01*
X-1970577Y336621D01*
G01X-1962941Y-280440D02*
Y-274240D01*
X-1960948Y-279407D01*
X-1958955Y-274240D01*
Y-280440D01*
G01X-1953215D02*
X-1956281D01*
Y-274240D01*
X-1953215D01*
G01X-1954441Y-277237D02*
X-1956281D01*
G01X-1948548Y-280440D02*
Y-274240D01*
X-1949468Y-275480D01*
G01Y-280440D02*
X-1947628D01*
G01X-1942348Y-274240D02*
X-1942961Y-274447D01*
X-1943421Y-274963D01*
X-1943728Y-275583D01*
X-1943958Y-276410D01*
X-1944035Y-277340D01*
X-1943958Y-278270D01*
X-1943728Y-279097D01*
X-1943421Y-279717D01*
X-1942961Y-280233D01*
X-1942348Y-280440D01*
X-1941735Y-280233D01*
X-1941275Y-279717D01*
X-1940968Y-279097D01*
X-1940738Y-278270D01*
X-1940661Y-277340D01*
X-1940738Y-276410D01*
X-1940968Y-275583D01*
X-1941275Y-274963D01*
X-1941735Y-274447D01*
X-1942348Y-274240D01*
G01X-1964366Y-244742D02*
X-1962833D01*
Y-246602D01*
X-1963293Y-247222D01*
X-1963829Y-247635D01*
X-1964596Y-247842D01*
X-1965363Y-247635D01*
X-1965899Y-247222D01*
X-1966359Y-246602D01*
X-1966666Y-245879D01*
X-1966819Y-245052D01*
Y-244329D01*
X-1966666Y-243709D01*
X-1966359Y-242985D01*
X-1965899Y-242365D01*
X-1965439Y-241952D01*
X-1964826Y-241642D01*
X-1964289D01*
X-1963676Y-241849D01*
X-1963216Y-242262D01*
G01X-1960236Y-247842D02*
Y-241642D01*
G01X-1957016D02*
Y-247842D01*
G01Y-244742D02*
X-1960236D01*
G01X-1951506Y-247842D02*
Y-241642D01*
X-1954343Y-246085D01*
X-1950509D01*
G01X-1964444Y-175962D02*
X-1962911D01*
Y-177822D01*
X-1963371Y-178442D01*
X-1963907Y-178855D01*
X-1964674Y-179062D01*
X-1965441Y-178855D01*
X-1965977Y-178442D01*
X-1966437Y-177822D01*
X-1966744Y-177099D01*
X-1966897Y-176272D01*
Y-175549D01*
X-1966744Y-174929D01*
X-1966437Y-174205D01*
X-1965977Y-173585D01*
X-1965517Y-173172D01*
X-1964904Y-172862D01*
X-1964367D01*
X-1963754Y-173069D01*
X-1963294Y-173482D01*
G01X-1960314Y-179062D02*
Y-172862D01*
G01X-1957094D02*
Y-179062D01*
G01Y-175962D02*
X-1960314D01*
G01X-1953961Y-173895D02*
X-1953501Y-173275D01*
X-1952964Y-172965D01*
X-1952351Y-172862D01*
X-1951584Y-173069D01*
X-1951047Y-173585D01*
X-1950894Y-174205D01*
X-1950971Y-174825D01*
X-1951277Y-175342D01*
X-1952811Y-176375D01*
X-1953501Y-177099D01*
X-1953961Y-178132D01*
X-1954114Y-179062D01*
X-1950894D01*
G01X-1965217Y-147379D02*
X-1965677Y-147069D01*
X-1966214Y-146862D01*
X-1966827D01*
X-1967517Y-147172D01*
X-1968054Y-147689D01*
X-1968437Y-148309D01*
X-1968744Y-149342D01*
X-1968821Y-150272D01*
X-1968667Y-151202D01*
X-1968437Y-151822D01*
X-1967977Y-152442D01*
X-1967441Y-152855D01*
X-1966904Y-153062D01*
X-1966367D01*
X-1965831Y-152855D01*
X-1965371Y-152545D01*
X-1964987Y-152132D01*
G01X-1962237Y-153062D02*
Y-146862D01*
X-1960321D01*
X-1959707Y-147172D01*
X-1959324Y-147585D01*
X-1959171Y-148412D01*
X-1959324Y-149239D01*
X-1959784Y-149755D01*
X-1960321Y-150065D01*
X-1962237D01*
G01X-1960321D02*
X-1959171Y-153062D01*
G01X-1956191Y-152132D02*
X-1955731Y-152649D01*
X-1955194Y-152959D01*
X-1954504Y-153062D01*
X-1953814Y-152855D01*
X-1953277Y-152442D01*
X-1952894Y-151719D01*
X-1952817Y-150892D01*
X-1952971Y-150065D01*
X-1953354Y-149549D01*
X-1953891Y-149135D01*
X-1954427Y-149032D01*
X-1954964Y-149135D01*
X-1955654Y-149549D01*
X-1955424Y-146862D01*
X-1953354D01*
G01X-1970512Y-139348D02*
Y-133148D01*
X-1973349Y-137591D01*
X-1969515D01*
G01X-1963444Y-126962D02*
X-1961911D01*
Y-128822D01*
X-1962371Y-129442D01*
X-1962907Y-129855D01*
X-1963674Y-130062D01*
X-1964441Y-129855D01*
X-1964977Y-129442D01*
X-1965437Y-128822D01*
X-1965744Y-128099D01*
X-1965897Y-127272D01*
Y-126549D01*
X-1965744Y-125929D01*
X-1965437Y-125205D01*
X-1964977Y-124585D01*
X-1964517Y-124172D01*
X-1963904Y-123862D01*
X-1963367D01*
X-1962754Y-124069D01*
X-1962294Y-124482D01*
G01X-1959314Y-130062D02*
Y-123862D01*
G01X-1956094D02*
Y-130062D01*
G01Y-126962D02*
X-1959314D01*
G01X-1950584Y-130062D02*
Y-123862D01*
X-1953421Y-128305D01*
X-1949587D01*
G01X-1964366Y-57970D02*
X-1962833D01*
Y-59830D01*
X-1963293Y-60450D01*
X-1963829Y-60863D01*
X-1964596Y-61070D01*
X-1965363Y-60863D01*
X-1965899Y-60450D01*
X-1966359Y-59830D01*
X-1966666Y-59107D01*
X-1966819Y-58280D01*
Y-57557D01*
X-1966666Y-56937D01*
X-1966359Y-56213D01*
X-1965899Y-55593D01*
X-1965439Y-55180D01*
X-1964826Y-54870D01*
X-1964289D01*
X-1963676Y-55077D01*
X-1963216Y-55490D01*
G01X-1960236Y-61070D02*
Y-54870D01*
G01X-1957016D02*
Y-61070D01*
G01Y-57970D02*
X-1960236D01*
G01X-1953883Y-55903D02*
X-1953423Y-55283D01*
X-1952886Y-54973D01*
X-1952273Y-54870D01*
X-1951506Y-55077D01*
X-1950969Y-55593D01*
X-1950816Y-56213D01*
X-1950893Y-56833D01*
X-1951199Y-57350D01*
X-1952733Y-58383D01*
X-1953423Y-59107D01*
X-1953883Y-60140D01*
X-1954036Y-61070D01*
X-1950816D01*
G01X-1969404Y-52199D02*
X-1975604D01*
Y-50283D01*
X-1975294Y-49669D01*
X-1974881Y-49286D01*
X-1974054Y-49133D01*
X-1973227Y-49286D01*
X-1972711Y-49746D01*
X-1972401Y-50283D01*
Y-52199D01*
G01Y-50283D02*
X-1969404Y-49133D01*
G01X-1970644Y-46153D02*
X-1969921Y-45693D01*
X-1969507Y-45079D01*
X-1969404Y-44389D01*
X-1969507Y-43776D01*
X-1970024Y-43163D01*
X-1970644Y-42779D01*
X-1971264Y-42703D01*
X-1971987Y-42856D01*
X-1972504Y-43393D01*
X-1972711Y-43929D01*
Y-44619D01*
G01Y-43929D02*
X-1973021Y-43469D01*
X-1973537Y-43086D01*
X-1974157Y-42933D01*
X-1974777Y-43086D01*
X-1975294Y-43469D01*
X-1975604Y-44159D01*
X-1975501Y-44849D01*
X-1975087Y-45539D01*
G01X-1969404Y-38266D02*
X-1969507Y-37729D01*
X-1969817Y-37116D01*
X-1970334Y-36733D01*
X-1971057Y-36579D01*
X-1971781Y-36733D01*
X-1972401Y-37193D01*
X-1972711Y-37883D01*
Y-38649D01*
X-1972917Y-39109D01*
X-1973434Y-39493D01*
X-1974157Y-39646D01*
X-1974881Y-39416D01*
X-1975397Y-38879D01*
X-1975604Y-38266D01*
X-1975397Y-37653D01*
X-1974881Y-37116D01*
X-1974157Y-36886D01*
X-1973434Y-37039D01*
X-1972917Y-37423D01*
X-1972711Y-37883D01*
Y-38649D01*
X-1972401Y-39339D01*
X-1971781Y-39799D01*
X-1971057Y-39953D01*
X-1970334Y-39799D01*
X-1969817Y-39416D01*
X-1969507Y-38803D01*
X-1969404Y-38266D01*
G01X-1970334Y-33753D02*
X-1969817Y-33293D01*
X-1969507Y-32756D01*
X-1969404Y-32066D01*
X-1969611Y-31376D01*
X-1970024Y-30839D01*
X-1970747Y-30456D01*
X-1971574Y-30379D01*
X-1972401Y-30533D01*
X-1972917Y-30916D01*
X-1973331Y-31453D01*
X-1973434Y-31989D01*
X-1973331Y-32526D01*
X-1972917Y-33216D01*
X-1975604Y-32986D01*
Y-30916D01*
G01X-1960404Y-52199D02*
X-1966604D01*
Y-50283D01*
X-1966294Y-49669D01*
X-1965881Y-49286D01*
X-1965054Y-49133D01*
X-1964227Y-49286D01*
X-1963711Y-49746D01*
X-1963401Y-50283D01*
Y-52199D01*
G01Y-50283D02*
X-1960404Y-49133D01*
G01Y-44466D02*
X-1966604D01*
X-1965364Y-45386D01*
G01X-1960404D02*
Y-43546D01*
G01X-1965571Y-39723D02*
X-1966191Y-39263D01*
X-1966501Y-38726D01*
X-1966604Y-38113D01*
X-1966397Y-37346D01*
X-1965881Y-36809D01*
X-1965261Y-36656D01*
X-1964641Y-36733D01*
X-1964124Y-37039D01*
X-1963091Y-38573D01*
X-1962367Y-39263D01*
X-1961334Y-39723D01*
X-1960404Y-39876D01*
Y-36656D01*
G01Y-31146D02*
X-1966604D01*
X-1962161Y-33983D01*
Y-30149D01*
G01X-1964366Y-16396D02*
X-1962833D01*
Y-18256D01*
X-1963293Y-18876D01*
X-1963829Y-19289D01*
X-1964596Y-19496D01*
X-1965363Y-19289D01*
X-1965899Y-18876D01*
X-1966359Y-18256D01*
X-1966666Y-17533D01*
X-1966819Y-16706D01*
Y-15983D01*
X-1966666Y-15363D01*
X-1966359Y-14639D01*
X-1965899Y-14019D01*
X-1965439Y-13606D01*
X-1964826Y-13296D01*
X-1964289D01*
X-1963676Y-13503D01*
X-1963216Y-13916D01*
G01X-1960236Y-19496D02*
Y-13296D01*
G01X-1957016D02*
Y-19496D01*
G01Y-16396D02*
X-1960236D01*
G01X-1951506Y-19496D02*
Y-13296D01*
X-1954343Y-17739D01*
X-1950509D01*
G01X-1967444Y53038D02*
X-1965911D01*
Y51178D01*
X-1966371Y50558D01*
X-1966907Y50145D01*
X-1967674Y49938D01*
X-1968441Y50145D01*
X-1968977Y50558D01*
X-1969437Y51178D01*
X-1969744Y51901D01*
X-1969897Y52728D01*
Y53451D01*
X-1969744Y54071D01*
X-1969437Y54795D01*
X-1968977Y55415D01*
X-1968517Y55828D01*
X-1967904Y56138D01*
X-1967367D01*
X-1966754Y55931D01*
X-1966294Y55518D01*
G01X-1963314Y49938D02*
Y56138D01*
G01X-1960094D02*
Y49938D01*
G01Y53038D02*
X-1963314D01*
G01X-1956961Y55105D02*
X-1956501Y55725D01*
X-1955964Y56035D01*
X-1955351Y56138D01*
X-1954584Y55931D01*
X-1954047Y55415D01*
X-1953894Y54795D01*
X-1953971Y54175D01*
X-1954277Y53658D01*
X-1955811Y52625D01*
X-1956501Y51901D01*
X-1956961Y50868D01*
X-1957114Y49938D01*
X-1953894D01*
G01X-1960217Y78621D02*
X-1960677Y78931D01*
X-1961214Y79138D01*
X-1961827D01*
X-1962517Y78828D01*
X-1963054Y78311D01*
X-1963437Y77691D01*
X-1963744Y76658D01*
X-1963821Y75728D01*
X-1963667Y74798D01*
X-1963437Y74178D01*
X-1962977Y73558D01*
X-1962441Y73145D01*
X-1961904Y72938D01*
X-1961367D01*
X-1960831Y73145D01*
X-1960371Y73455D01*
X-1959987Y73868D01*
G01X-1957237Y72938D02*
Y79138D01*
X-1955321D01*
X-1954707Y78828D01*
X-1954324Y78415D01*
X-1954171Y77588D01*
X-1954324Y76761D01*
X-1954784Y76245D01*
X-1955321Y75935D01*
X-1957237D01*
G01X-1955321D02*
X-1954171Y72938D01*
G01X-1948584D02*
Y79138D01*
X-1951421Y74695D01*
X-1947587D01*
G01X-1965444Y101084D02*
X-1963911D01*
Y99224D01*
X-1964371Y98604D01*
X-1964907Y98191D01*
X-1965674Y97984D01*
X-1966441Y98191D01*
X-1966977Y98604D01*
X-1967437Y99224D01*
X-1967744Y99947D01*
X-1967897Y100774D01*
Y101497D01*
X-1967744Y102117D01*
X-1967437Y102841D01*
X-1966977Y103461D01*
X-1966517Y103874D01*
X-1965904Y104184D01*
X-1965367D01*
X-1964754Y103977D01*
X-1964294Y103564D01*
G01X-1961314Y97984D02*
Y104184D01*
G01X-1958094D02*
Y97984D01*
G01Y101084D02*
X-1961314D01*
G01X-1952584Y97984D02*
Y104184D01*
X-1955421Y99741D01*
X-1951587D01*
G01X-1964366Y170378D02*
X-1962833D01*
Y168518D01*
X-1963293Y167898D01*
X-1963829Y167485D01*
X-1964596Y167278D01*
X-1965363Y167485D01*
X-1965899Y167898D01*
X-1966359Y168518D01*
X-1966666Y169241D01*
X-1966819Y170068D01*
Y170791D01*
X-1966666Y171411D01*
X-1966359Y172135D01*
X-1965899Y172755D01*
X-1965439Y173168D01*
X-1964826Y173478D01*
X-1964289D01*
X-1963676Y173271D01*
X-1963216Y172858D01*
G01X-1960236Y167278D02*
Y173478D01*
G01X-1957016D02*
Y167278D01*
G01Y170378D02*
X-1960236D01*
G01X-1953883Y172445D02*
X-1953423Y173065D01*
X-1952886Y173375D01*
X-1952273Y173478D01*
X-1951506Y173271D01*
X-1950969Y172755D01*
X-1950816Y172135D01*
X-1950893Y171515D01*
X-1951199Y170998D01*
X-1952733Y169965D01*
X-1953423Y169241D01*
X-1953883Y168208D01*
X-1954036Y167278D01*
X-1950816D01*
G01X-1968204Y175221D02*
X-1974404D01*
Y177137D01*
X-1974094Y177751D01*
X-1973681Y178134D01*
X-1972854Y178287D01*
X-1972027Y178134D01*
X-1971511Y177674D01*
X-1971201Y177137D01*
Y175221D01*
G01Y177137D02*
X-1968204Y178287D01*
G01X-1969444Y181267D02*
X-1968721Y181727D01*
X-1968307Y182341D01*
X-1968204Y183031D01*
X-1968307Y183644D01*
X-1968824Y184257D01*
X-1969444Y184641D01*
X-1970064Y184717D01*
X-1970787Y184564D01*
X-1971304Y184027D01*
X-1971511Y183491D01*
Y182801D01*
G01Y183491D02*
X-1971821Y183951D01*
X-1972337Y184334D01*
X-1972957Y184487D01*
X-1973577Y184334D01*
X-1974094Y183951D01*
X-1974404Y183261D01*
X-1974301Y182571D01*
X-1973887Y181881D01*
G01X-1968927Y187851D02*
X-1968411Y188387D01*
X-1968204Y189001D01*
X-1968411Y189614D01*
X-1969030Y190151D01*
X-1969961Y190534D01*
X-1970891Y190687D01*
X-1972027D01*
X-1972957Y190534D01*
X-1973784Y190151D01*
X-1974197Y189691D01*
X-1974404Y189154D01*
X-1974197Y188541D01*
X-1973784Y188081D01*
X-1973164Y187774D01*
X-1972337Y187621D01*
X-1971614Y187774D01*
X-1970891Y188157D01*
X-1970477Y188617D01*
X-1970374Y189154D01*
X-1970581Y189767D01*
X-1971097Y190227D01*
X-1972027Y190687D01*
G01X-1968204Y195354D02*
X-1974404D01*
X-1973164Y194434D01*
G01X-1968204D02*
Y196274D01*
G01X-1959204Y175221D02*
X-1965404D01*
Y177137D01*
X-1965094Y177751D01*
X-1964681Y178134D01*
X-1963854Y178287D01*
X-1963027Y178134D01*
X-1962511Y177674D01*
X-1962201Y177137D01*
Y175221D01*
G01Y177137D02*
X-1959204Y178287D01*
G01X-1960444Y181267D02*
X-1959721Y181727D01*
X-1959307Y182341D01*
X-1959204Y183031D01*
X-1959307Y183644D01*
X-1959824Y184257D01*
X-1960444Y184641D01*
X-1961064Y184717D01*
X-1961787Y184564D01*
X-1962304Y184027D01*
X-1962511Y183491D01*
Y182801D01*
G01Y183491D02*
X-1962821Y183951D01*
X-1963337Y184334D01*
X-1963957Y184487D01*
X-1964577Y184334D01*
X-1965094Y183951D01*
X-1965404Y183261D01*
X-1965301Y182571D01*
X-1964887Y181881D01*
G01X-1959204Y189001D02*
X-1960547Y189154D01*
X-1961684Y189384D01*
X-1962717Y189691D01*
X-1963854Y190074D01*
X-1965404Y190687D01*
Y187621D01*
G01X-1959204Y196274D02*
X-1965404D01*
X-1960961Y193437D01*
Y197271D01*
G01X-1963672Y280205D02*
X-1969872D01*
Y282121D01*
X-1969562Y282735D01*
X-1969149Y283118D01*
X-1968322Y283271D01*
X-1967495Y283118D01*
X-1966979Y282658D01*
X-1966669Y282121D01*
Y280205D01*
G01Y282121D02*
X-1963672Y283271D01*
G01Y288858D02*
X-1969872D01*
X-1965429Y286021D01*
Y289855D01*
G01X-1968839Y292681D02*
X-1969459Y293141D01*
X-1969769Y293678D01*
X-1969872Y294291D01*
X-1969665Y295058D01*
X-1969149Y295595D01*
X-1968529Y295748D01*
X-1967909Y295671D01*
X-1967392Y295365D01*
X-1966359Y293831D01*
X-1965635Y293141D01*
X-1964602Y292681D01*
X-1963672Y292528D01*
Y295748D01*
G01X-1964602Y298651D02*
X-1964085Y299111D01*
X-1963775Y299648D01*
X-1963672Y300338D01*
X-1963879Y301028D01*
X-1964292Y301565D01*
X-1965015Y301948D01*
X-1965842Y302025D01*
X-1966669Y301871D01*
X-1967185Y301488D01*
X-1967599Y300951D01*
X-1967702Y300415D01*
X-1967599Y299878D01*
X-1967185Y299188D01*
X-1969872Y299418D01*
Y301488D01*
G01X-1960444Y310038D02*
X-1958911D01*
Y308178D01*
X-1959371Y307558D01*
X-1959907Y307145D01*
X-1960674Y306938D01*
X-1961441Y307145D01*
X-1961977Y307558D01*
X-1962437Y308178D01*
X-1962744Y308901D01*
X-1962897Y309728D01*
Y310451D01*
X-1962744Y311071D01*
X-1962437Y311795D01*
X-1961977Y312415D01*
X-1961517Y312828D01*
X-1960904Y313138D01*
X-1960367D01*
X-1959754Y312931D01*
X-1959294Y312518D01*
G01X-1956314Y306938D02*
Y313138D01*
G01X-1953094D02*
Y306938D01*
G01Y310038D02*
X-1956314D01*
G01X-1947584Y306938D02*
Y313138D01*
X-1950421Y308695D01*
X-1946587D01*
G01X-1964444Y354038D02*
X-1962911D01*
Y352178D01*
X-1963371Y351558D01*
X-1963907Y351145D01*
X-1964674Y350938D01*
X-1965441Y351145D01*
X-1965977Y351558D01*
X-1966437Y352178D01*
X-1966744Y352901D01*
X-1966897Y353728D01*
Y354451D01*
X-1966744Y355071D01*
X-1966437Y355795D01*
X-1965977Y356415D01*
X-1965517Y356828D01*
X-1964904Y357138D01*
X-1964367D01*
X-1963754Y356931D01*
X-1963294Y356518D01*
G01X-1960314Y350938D02*
Y357138D01*
G01X-1957094D02*
Y350938D01*
G01Y354038D02*
X-1960314D01*
G01X-1954191Y352178D02*
X-1953731Y351455D01*
X-1953117Y351041D01*
X-1952427Y350938D01*
X-1951814Y351041D01*
X-1951201Y351558D01*
X-1950817Y352178D01*
X-1950741Y352798D01*
X-1950894Y353521D01*
X-1951431Y354038D01*
X-1951967Y354245D01*
X-1952657D01*
G01X-1951967D02*
X-1951507Y354555D01*
X-1951124Y355071D01*
X-1950971Y355691D01*
X-1951124Y356311D01*
X-1951507Y356828D01*
X-1952197Y357138D01*
X-1952887Y357035D01*
X-1953577Y356621D01*
G01X-1969604Y351021D02*
X-1975804Y352938D01*
X-1969604Y354855D01*
G01X-1971774Y354165D02*
Y351711D01*
G01X-1969604Y359138D02*
X-1975804D01*
X-1974564Y358218D01*
G01X-1969604D02*
Y360058D01*
G01X-1959841Y392000D02*
Y398200D01*
X-1957848Y393033D01*
X-1955855Y398200D01*
Y392000D01*
G01X-1950115D02*
X-1953181D01*
Y398200D01*
X-1950115D01*
G01X-1951341Y395203D02*
X-1953181D01*
G01X-1946751Y392723D02*
X-1946215Y392207D01*
X-1945601Y392000D01*
X-1944988Y392207D01*
X-1944451Y392826D01*
X-1944068Y393757D01*
X-1943915Y394687D01*
Y395823D01*
X-1944068Y396753D01*
X-1944451Y397580D01*
X-1944911Y397993D01*
X-1945448Y398200D01*
X-1946061Y397993D01*
X-1946521Y397580D01*
X-1946828Y396960D01*
X-1946981Y396133D01*
X-1946828Y395410D01*
X-1946445Y394687D01*
X-1945985Y394273D01*
X-1945448Y394170D01*
X-1944835Y394377D01*
X-1944375Y394893D01*
X-1943915Y395823D01*
G01X-1943326Y-208442D02*
Y-202242D01*
X-1944246Y-203482D01*
G01Y-208442D02*
X-1942406D01*
G01X-1957161Y-162895D02*
X-1956701Y-162275D01*
X-1956164Y-161965D01*
X-1955551Y-161862D01*
X-1954784Y-162069D01*
X-1954247Y-162585D01*
X-1954094Y-163205D01*
X-1954171Y-163825D01*
X-1954477Y-164342D01*
X-1956011Y-165375D01*
X-1956701Y-166099D01*
X-1957161Y-167132D01*
X-1957314Y-168062D01*
X-1954094D01*
G01X-1957119Y-138108D02*
X-1956659Y-138831D01*
X-1956045Y-139245D01*
X-1955355Y-139348D01*
X-1954742Y-139245D01*
X-1954129Y-138728D01*
X-1953745Y-138108D01*
X-1953669Y-137488D01*
X-1953822Y-136765D01*
X-1954359Y-136248D01*
X-1954895Y-136041D01*
X-1955585D01*
G01X-1954895D02*
X-1954435Y-135731D01*
X-1954052Y-135215D01*
X-1953899Y-134595D01*
X-1954052Y-133975D01*
X-1954435Y-133458D01*
X-1955125Y-133148D01*
X-1955815Y-133251D01*
X-1956505Y-133665D01*
G01X-1943326Y-94270D02*
Y-88070D01*
X-1944246Y-89310D01*
G01Y-94270D02*
X-1942406D01*
G01X-1951404Y-52199D02*
X-1957604D01*
Y-50283D01*
X-1957294Y-49669D01*
X-1956881Y-49286D01*
X-1956054Y-49133D01*
X-1955227Y-49286D01*
X-1954711Y-49746D01*
X-1954401Y-50283D01*
Y-52199D01*
G01Y-50283D02*
X-1951404Y-49133D01*
G01X-1956571Y-45923D02*
X-1957191Y-45463D01*
X-1957501Y-44926D01*
X-1957604Y-44313D01*
X-1957397Y-43546D01*
X-1956881Y-43009D01*
X-1956261Y-42856D01*
X-1955641Y-42933D01*
X-1955124Y-43239D01*
X-1954091Y-44773D01*
X-1953367Y-45463D01*
X-1952334Y-45923D01*
X-1951404Y-46076D01*
Y-42856D01*
G01Y-38419D02*
X-1952747Y-38266D01*
X-1953884Y-38036D01*
X-1954917Y-37729D01*
X-1956054Y-37346D01*
X-1957604Y-36733D01*
Y-39799D01*
G01X-1956571Y-33523D02*
X-1957191Y-33063D01*
X-1957501Y-32526D01*
X-1957604Y-31913D01*
X-1957397Y-31146D01*
X-1956881Y-30609D01*
X-1956261Y-30456D01*
X-1955641Y-30533D01*
X-1955124Y-30839D01*
X-1954091Y-32373D01*
X-1953367Y-33063D01*
X-1952334Y-33523D01*
X-1951404Y-33676D01*
Y-30456D01*
G01X-1942404Y-52199D02*
X-1948604D01*
Y-50283D01*
X-1948294Y-49669D01*
X-1947881Y-49286D01*
X-1947054Y-49133D01*
X-1946227Y-49286D01*
X-1945711Y-49746D01*
X-1945401Y-50283D01*
Y-52199D01*
G01Y-50283D02*
X-1942404Y-49133D01*
G01X-1943644Y-46153D02*
X-1942921Y-45693D01*
X-1942507Y-45079D01*
X-1942404Y-44389D01*
X-1942507Y-43776D01*
X-1943024Y-43163D01*
X-1943644Y-42779D01*
X-1944264Y-42703D01*
X-1944987Y-42856D01*
X-1945504Y-43393D01*
X-1945711Y-43929D01*
Y-44619D01*
G01Y-43929D02*
X-1946021Y-43469D01*
X-1946537Y-43086D01*
X-1947157Y-42933D01*
X-1947777Y-43086D01*
X-1948294Y-43469D01*
X-1948604Y-44159D01*
X-1948501Y-44849D01*
X-1948087Y-45539D01*
G01X-1942404Y-38266D02*
X-1942507Y-37729D01*
X-1942817Y-37116D01*
X-1943334Y-36733D01*
X-1944057Y-36579D01*
X-1944781Y-36733D01*
X-1945401Y-37193D01*
X-1945711Y-37883D01*
Y-38649D01*
X-1945917Y-39109D01*
X-1946434Y-39493D01*
X-1947157Y-39646D01*
X-1947881Y-39416D01*
X-1948397Y-38879D01*
X-1948604Y-38266D01*
X-1948397Y-37653D01*
X-1947881Y-37116D01*
X-1947157Y-36886D01*
X-1946434Y-37039D01*
X-1945917Y-37423D01*
X-1945711Y-37883D01*
Y-38649D01*
X-1945401Y-39339D01*
X-1944781Y-39799D01*
X-1944057Y-39953D01*
X-1943334Y-39799D01*
X-1942817Y-39416D01*
X-1942507Y-38803D01*
X-1942404Y-38266D01*
G01Y-32219D02*
X-1943747Y-32066D01*
X-1944884Y-31836D01*
X-1945917Y-31529D01*
X-1947054Y-31146D01*
X-1948604Y-30533D01*
Y-33599D01*
G01X-1946404Y19920D02*
Y26120D01*
X-1947324Y24880D01*
G01Y19920D02*
X-1945484D01*
G01X-1956213Y64553D02*
X-1955753Y65173D01*
X-1955216Y65483D01*
X-1954603Y65586D01*
X-1953836Y65379D01*
X-1953299Y64863D01*
X-1953146Y64243D01*
X-1953223Y63623D01*
X-1953529Y63106D01*
X-1955063Y62073D01*
X-1955753Y61349D01*
X-1956213Y60316D01*
X-1956366Y59386D01*
X-1953146D01*
G01X-1951443Y85626D02*
X-1950983Y84903D01*
X-1950369Y84489D01*
X-1949679Y84386D01*
X-1949066Y84489D01*
X-1948453Y85006D01*
X-1948069Y85626D01*
X-1947993Y86246D01*
X-1948146Y86969D01*
X-1948683Y87486D01*
X-1949219Y87693D01*
X-1949909D01*
G01X-1949219D02*
X-1948759Y88003D01*
X-1948376Y88519D01*
X-1948223Y89139D01*
X-1948376Y89759D01*
X-1948759Y90276D01*
X-1949449Y90586D01*
X-1950139Y90483D01*
X-1950829Y90069D01*
G01X-1943326Y134078D02*
Y140278D01*
X-1944246Y139038D01*
G01Y134078D02*
X-1942406D01*
G01X-1950204Y175221D02*
X-1956404D01*
Y177137D01*
X-1956094Y177751D01*
X-1955681Y178134D01*
X-1954854Y178287D01*
X-1954027Y178134D01*
X-1953511Y177674D01*
X-1953201Y177137D01*
Y175221D01*
G01Y177137D02*
X-1950204Y178287D01*
G01X-1951444Y181267D02*
X-1950721Y181727D01*
X-1950307Y182341D01*
X-1950204Y183031D01*
X-1950307Y183644D01*
X-1950824Y184257D01*
X-1951444Y184641D01*
X-1952064Y184717D01*
X-1952787Y184564D01*
X-1953304Y184027D01*
X-1953511Y183491D01*
Y182801D01*
G01Y183491D02*
X-1953821Y183951D01*
X-1954337Y184334D01*
X-1954957Y184487D01*
X-1955577Y184334D01*
X-1956094Y183951D01*
X-1956404Y183261D01*
X-1956301Y182571D01*
X-1955887Y181881D01*
G01X-1950204Y189001D02*
X-1951547Y189154D01*
X-1952684Y189384D01*
X-1953717Y189691D01*
X-1954854Y190074D01*
X-1956404Y190687D01*
Y187621D01*
G01X-1952787Y193897D02*
X-1953511Y194434D01*
X-1953924Y194894D01*
X-1954131Y195507D01*
X-1953924Y196044D01*
X-1953511Y196427D01*
X-1952891Y196734D01*
X-1952167Y196811D01*
X-1951547Y196734D01*
X-1950927Y196427D01*
X-1950411Y195967D01*
X-1950204Y195431D01*
X-1950411Y194817D01*
X-1951030Y194281D01*
X-1951961Y193974D01*
X-1952994Y193897D01*
X-1954337Y194051D01*
X-1955061Y194281D01*
X-1955784Y194664D01*
X-1956301Y195201D01*
X-1956404Y195737D01*
X-1956197Y196274D01*
X-1955681Y196657D01*
G01X-1941204Y175221D02*
X-1947404D01*
Y177137D01*
X-1947094Y177751D01*
X-1946681Y178134D01*
X-1945854Y178287D01*
X-1945027Y178134D01*
X-1944511Y177674D01*
X-1944201Y177137D01*
Y175221D01*
G01Y177137D02*
X-1941204Y178287D01*
G01X-1942444Y181267D02*
X-1941721Y181727D01*
X-1941307Y182341D01*
X-1941204Y183031D01*
X-1941307Y183644D01*
X-1941824Y184257D01*
X-1942444Y184641D01*
X-1943064Y184717D01*
X-1943787Y184564D01*
X-1944304Y184027D01*
X-1944511Y183491D01*
Y182801D01*
G01Y183491D02*
X-1944821Y183951D01*
X-1945337Y184334D01*
X-1945957Y184487D01*
X-1946577Y184334D01*
X-1947094Y183951D01*
X-1947404Y183261D01*
X-1947301Y182571D01*
X-1946887Y181881D01*
G01X-1941927Y187851D02*
X-1941411Y188387D01*
X-1941204Y189001D01*
X-1941411Y189614D01*
X-1942030Y190151D01*
X-1942961Y190534D01*
X-1943891Y190687D01*
X-1945027D01*
X-1945957Y190534D01*
X-1946784Y190151D01*
X-1947197Y189691D01*
X-1947404Y189154D01*
X-1947197Y188541D01*
X-1946784Y188081D01*
X-1946164Y187774D01*
X-1945337Y187621D01*
X-1944614Y187774D01*
X-1943891Y188157D01*
X-1943477Y188617D01*
X-1943374Y189154D01*
X-1943581Y189767D01*
X-1944097Y190227D01*
X-1945027Y190687D01*
G01X-1942444Y193667D02*
X-1941721Y194127D01*
X-1941307Y194741D01*
X-1941204Y195431D01*
X-1941307Y196044D01*
X-1941824Y196657D01*
X-1942444Y197041D01*
X-1943064Y197117D01*
X-1943787Y196964D01*
X-1944304Y196427D01*
X-1944511Y195891D01*
Y195201D01*
G01Y195891D02*
X-1944821Y196351D01*
X-1945337Y196734D01*
X-1945957Y196887D01*
X-1946577Y196734D01*
X-1947094Y196351D01*
X-1947404Y195661D01*
X-1947301Y194971D01*
X-1946887Y194281D01*
G01X-1953672Y280205D02*
X-1959872D01*
Y282121D01*
X-1959562Y282735D01*
X-1959149Y283118D01*
X-1958322Y283271D01*
X-1957495Y283118D01*
X-1956979Y282658D01*
X-1956669Y282121D01*
Y280205D01*
G01Y282121D02*
X-1953672Y283271D01*
G01Y288858D02*
X-1959872D01*
X-1955429Y286021D01*
Y289855D01*
G01X-1958839Y292681D02*
X-1959459Y293141D01*
X-1959769Y293678D01*
X-1959872Y294291D01*
X-1959665Y295058D01*
X-1959149Y295595D01*
X-1958529Y295748D01*
X-1957909Y295671D01*
X-1957392Y295365D01*
X-1956359Y293831D01*
X-1955635Y293141D01*
X-1954602Y292681D01*
X-1953672Y292528D01*
Y295748D01*
G01Y300185D02*
X-1955015Y300338D01*
X-1956152Y300568D01*
X-1957185Y300875D01*
X-1958322Y301258D01*
X-1959872Y301871D01*
Y298805D01*
G01X-1943668Y280205D02*
X-1949868D01*
Y282121D01*
X-1949558Y282735D01*
X-1949145Y283118D01*
X-1948318Y283271D01*
X-1947491Y283118D01*
X-1946975Y282658D01*
X-1946665Y282121D01*
Y280205D01*
G01Y282121D02*
X-1943668Y283271D01*
G01X-1944908Y286251D02*
X-1944185Y286711D01*
X-1943771Y287325D01*
X-1943668Y288015D01*
X-1943771Y288628D01*
X-1944288Y289241D01*
X-1944908Y289625D01*
X-1945528Y289701D01*
X-1946251Y289548D01*
X-1946768Y289011D01*
X-1946975Y288475D01*
Y287785D01*
G01Y288475D02*
X-1947285Y288935D01*
X-1947801Y289318D01*
X-1948421Y289471D01*
X-1949041Y289318D01*
X-1949558Y288935D01*
X-1949868Y288245D01*
X-1949765Y287555D01*
X-1949351Y286865D01*
G01X-1944391Y292835D02*
X-1943875Y293371D01*
X-1943668Y293985D01*
X-1943875Y294598D01*
X-1944494Y295135D01*
X-1945425Y295518D01*
X-1946355Y295671D01*
X-1947491D01*
X-1948421Y295518D01*
X-1949248Y295135D01*
X-1949661Y294675D01*
X-1949868Y294138D01*
X-1949661Y293525D01*
X-1949248Y293065D01*
X-1948628Y292758D01*
X-1947801Y292605D01*
X-1947078Y292758D01*
X-1946355Y293141D01*
X-1945941Y293601D01*
X-1945838Y294138D01*
X-1946045Y294751D01*
X-1946561Y295211D01*
X-1947491Y295671D01*
G01X-1944391Y299035D02*
X-1943875Y299571D01*
X-1943668Y300185D01*
X-1943875Y300798D01*
X-1944494Y301335D01*
X-1945425Y301718D01*
X-1946355Y301871D01*
X-1947491D01*
X-1948421Y301718D01*
X-1949248Y301335D01*
X-1949661Y300875D01*
X-1949868Y300338D01*
X-1949661Y299725D01*
X-1949248Y299265D01*
X-1948628Y298958D01*
X-1947801Y298805D01*
X-1947078Y298958D01*
X-1946355Y299341D01*
X-1945941Y299801D01*
X-1945838Y300338D01*
X-1946045Y300951D01*
X-1946561Y301411D01*
X-1947491Y301871D01*
G01X-1920036Y-228195D02*
X-1926236D01*
Y-226279D01*
X-1925926Y-225665D01*
X-1925513Y-225282D01*
X-1924686Y-225129D01*
X-1923859Y-225282D01*
X-1923343Y-225742D01*
X-1923033Y-226279D01*
Y-228195D01*
G01Y-226279D02*
X-1920036Y-225129D01*
G01Y-219542D02*
X-1926236D01*
X-1921793Y-222379D01*
Y-218545D01*
G01X-1920759Y-215565D02*
X-1920243Y-215029D01*
X-1920036Y-214415D01*
X-1920243Y-213802D01*
X-1920862Y-213265D01*
X-1921793Y-212882D01*
X-1922723Y-212729D01*
X-1923859D01*
X-1924789Y-212882D01*
X-1925616Y-213265D01*
X-1926029Y-213725D01*
X-1926236Y-214262D01*
X-1926029Y-214875D01*
X-1925616Y-215335D01*
X-1924996Y-215642D01*
X-1924169Y-215795D01*
X-1923446Y-215642D01*
X-1922723Y-215259D01*
X-1922309Y-214799D01*
X-1922206Y-214262D01*
X-1922413Y-213649D01*
X-1922929Y-213189D01*
X-1923859Y-212729D01*
G01X-1920036Y-208215D02*
X-1921379Y-208062D01*
X-1922516Y-207832D01*
X-1923549Y-207525D01*
X-1924686Y-207142D01*
X-1926236Y-206529D01*
Y-209595D01*
G01X-1924404Y-52199D02*
X-1930604D01*
Y-50283D01*
X-1930294Y-49669D01*
X-1929881Y-49286D01*
X-1929054Y-49133D01*
X-1928227Y-49286D01*
X-1927711Y-49746D01*
X-1927401Y-50283D01*
Y-52199D01*
G01Y-50283D02*
X-1924404Y-49133D01*
G01X-1925644Y-46153D02*
X-1924921Y-45693D01*
X-1924507Y-45079D01*
X-1924404Y-44389D01*
X-1924507Y-43776D01*
X-1925024Y-43163D01*
X-1925644Y-42779D01*
X-1926264Y-42703D01*
X-1926987Y-42856D01*
X-1927504Y-43393D01*
X-1927711Y-43929D01*
Y-44619D01*
G01Y-43929D02*
X-1928021Y-43469D01*
X-1928537Y-43086D01*
X-1929157Y-42933D01*
X-1929777Y-43086D01*
X-1930294Y-43469D01*
X-1930604Y-44159D01*
X-1930501Y-44849D01*
X-1930087Y-45539D01*
G01X-1924404Y-38266D02*
X-1924507Y-37729D01*
X-1924817Y-37116D01*
X-1925334Y-36733D01*
X-1926057Y-36579D01*
X-1926781Y-36733D01*
X-1927401Y-37193D01*
X-1927711Y-37883D01*
Y-38649D01*
X-1927917Y-39109D01*
X-1928434Y-39493D01*
X-1929157Y-39646D01*
X-1929881Y-39416D01*
X-1930397Y-38879D01*
X-1930604Y-38266D01*
X-1930397Y-37653D01*
X-1929881Y-37116D01*
X-1929157Y-36886D01*
X-1928434Y-37039D01*
X-1927917Y-37423D01*
X-1927711Y-37883D01*
Y-38649D01*
X-1927401Y-39339D01*
X-1926781Y-39799D01*
X-1926057Y-39953D01*
X-1925334Y-39799D01*
X-1924817Y-39416D01*
X-1924507Y-38803D01*
X-1924404Y-38266D01*
G01X-1926987Y-33523D02*
X-1927711Y-32986D01*
X-1928124Y-32526D01*
X-1928331Y-31913D01*
X-1928124Y-31376D01*
X-1927711Y-30993D01*
X-1927091Y-30686D01*
X-1926367Y-30609D01*
X-1925747Y-30686D01*
X-1925127Y-30993D01*
X-1924611Y-31453D01*
X-1924404Y-31989D01*
X-1924611Y-32603D01*
X-1925230Y-33139D01*
X-1926161Y-33446D01*
X-1927194Y-33523D01*
X-1928537Y-33369D01*
X-1929261Y-33139D01*
X-1929984Y-32756D01*
X-1930501Y-32219D01*
X-1930604Y-31683D01*
X-1930397Y-31146D01*
X-1929881Y-30763D01*
G01X-1933404Y-52199D02*
X-1939604D01*
Y-50283D01*
X-1939294Y-49669D01*
X-1938881Y-49286D01*
X-1938054Y-49133D01*
X-1937227Y-49286D01*
X-1936711Y-49746D01*
X-1936401Y-50283D01*
Y-52199D01*
G01Y-50283D02*
X-1933404Y-49133D01*
G01Y-44466D02*
X-1939604D01*
X-1938364Y-45386D01*
G01X-1933404D02*
Y-43546D01*
G01X-1938571Y-39723D02*
X-1939191Y-39263D01*
X-1939501Y-38726D01*
X-1939604Y-38113D01*
X-1939397Y-37346D01*
X-1938881Y-36809D01*
X-1938261Y-36656D01*
X-1937641Y-36733D01*
X-1937124Y-37039D01*
X-1936091Y-38573D01*
X-1935367Y-39263D01*
X-1934334Y-39723D01*
X-1933404Y-39876D01*
Y-36656D01*
G01X-1934334Y-33753D02*
X-1933817Y-33293D01*
X-1933507Y-32756D01*
X-1933404Y-32066D01*
X-1933611Y-31376D01*
X-1934024Y-30839D01*
X-1934747Y-30456D01*
X-1935574Y-30379D01*
X-1936401Y-30533D01*
X-1936917Y-30916D01*
X-1937331Y-31453D01*
X-1937434Y-31989D01*
X-1937331Y-32526D01*
X-1936917Y-33216D01*
X-1939604Y-32986D01*
Y-30916D01*
G01X-1923204Y175221D02*
X-1929404D01*
Y177137D01*
X-1929094Y177751D01*
X-1928681Y178134D01*
X-1927854Y178287D01*
X-1927027Y178134D01*
X-1926511Y177674D01*
X-1926201Y177137D01*
Y175221D01*
G01Y177137D02*
X-1923204Y178287D01*
G01X-1924444Y181267D02*
X-1923721Y181727D01*
X-1923307Y182341D01*
X-1923204Y183031D01*
X-1923307Y183644D01*
X-1923824Y184257D01*
X-1924444Y184641D01*
X-1925064Y184717D01*
X-1925787Y184564D01*
X-1926304Y184027D01*
X-1926511Y183491D01*
Y182801D01*
G01Y183491D02*
X-1926821Y183951D01*
X-1927337Y184334D01*
X-1927957Y184487D01*
X-1928577Y184334D01*
X-1929094Y183951D01*
X-1929404Y183261D01*
X-1929301Y182571D01*
X-1928887Y181881D01*
G01X-1923204Y189001D02*
X-1924547Y189154D01*
X-1925684Y189384D01*
X-1926717Y189691D01*
X-1927854Y190074D01*
X-1929404Y190687D01*
Y187621D01*
G01X-1924134Y193667D02*
X-1923617Y194127D01*
X-1923307Y194664D01*
X-1923204Y195354D01*
X-1923411Y196044D01*
X-1923824Y196581D01*
X-1924547Y196964D01*
X-1925374Y197041D01*
X-1926201Y196887D01*
X-1926717Y196504D01*
X-1927131Y195967D01*
X-1927234Y195431D01*
X-1927131Y194894D01*
X-1926717Y194204D01*
X-1929404Y194434D01*
Y196504D01*
G01X-1932204Y175221D02*
X-1938404D01*
Y177137D01*
X-1938094Y177751D01*
X-1937681Y178134D01*
X-1936854Y178287D01*
X-1936027Y178134D01*
X-1935511Y177674D01*
X-1935201Y177137D01*
Y175221D01*
G01Y177137D02*
X-1932204Y178287D01*
G01X-1933444Y181267D02*
X-1932721Y181727D01*
X-1932307Y182341D01*
X-1932204Y183031D01*
X-1932307Y183644D01*
X-1932824Y184257D01*
X-1933444Y184641D01*
X-1934064Y184717D01*
X-1934787Y184564D01*
X-1935304Y184027D01*
X-1935511Y183491D01*
Y182801D01*
G01Y183491D02*
X-1935821Y183951D01*
X-1936337Y184334D01*
X-1936957Y184487D01*
X-1937577Y184334D01*
X-1938094Y183951D01*
X-1938404Y183261D01*
X-1938301Y182571D01*
X-1937887Y181881D01*
G01X-1932927Y187851D02*
X-1932411Y188387D01*
X-1932204Y189001D01*
X-1932411Y189614D01*
X-1933030Y190151D01*
X-1933961Y190534D01*
X-1934891Y190687D01*
X-1936027D01*
X-1936957Y190534D01*
X-1937784Y190151D01*
X-1938197Y189691D01*
X-1938404Y189154D01*
X-1938197Y188541D01*
X-1937784Y188081D01*
X-1937164Y187774D01*
X-1936337Y187621D01*
X-1935614Y187774D01*
X-1934891Y188157D01*
X-1934477Y188617D01*
X-1934374Y189154D01*
X-1934581Y189767D01*
X-1935097Y190227D01*
X-1936027Y190687D01*
G01X-1937371Y193897D02*
X-1937991Y194357D01*
X-1938301Y194894D01*
X-1938404Y195507D01*
X-1938197Y196274D01*
X-1937681Y196811D01*
X-1937061Y196964D01*
X-1936441Y196887D01*
X-1935924Y196581D01*
X-1934891Y195047D01*
X-1934167Y194357D01*
X-1933134Y193897D01*
X-1932204Y193744D01*
Y196964D01*
G01X-1923668Y280205D02*
X-1929868D01*
Y282121D01*
X-1929558Y282735D01*
X-1929145Y283118D01*
X-1928318Y283271D01*
X-1927491Y283118D01*
X-1926975Y282658D01*
X-1926665Y282121D01*
Y280205D01*
G01Y282121D02*
X-1923668Y283271D01*
G01X-1924908Y286251D02*
X-1924185Y286711D01*
X-1923771Y287325D01*
X-1923668Y288015D01*
X-1923771Y288628D01*
X-1924288Y289241D01*
X-1924908Y289625D01*
X-1925528Y289701D01*
X-1926251Y289548D01*
X-1926768Y289011D01*
X-1926975Y288475D01*
Y287785D01*
G01Y288475D02*
X-1927285Y288935D01*
X-1927801Y289318D01*
X-1928421Y289471D01*
X-1929041Y289318D01*
X-1929558Y288935D01*
X-1929868Y288245D01*
X-1929765Y287555D01*
X-1929351Y286865D01*
G01X-1924391Y292835D02*
X-1923875Y293371D01*
X-1923668Y293985D01*
X-1923875Y294598D01*
X-1924494Y295135D01*
X-1925425Y295518D01*
X-1926355Y295671D01*
X-1927491D01*
X-1928421Y295518D01*
X-1929248Y295135D01*
X-1929661Y294675D01*
X-1929868Y294138D01*
X-1929661Y293525D01*
X-1929248Y293065D01*
X-1928628Y292758D01*
X-1927801Y292605D01*
X-1927078Y292758D01*
X-1926355Y293141D01*
X-1925941Y293601D01*
X-1925838Y294138D01*
X-1926045Y294751D01*
X-1926561Y295211D01*
X-1927491Y295671D01*
G01X-1923668Y300338D02*
X-1923771Y300875D01*
X-1924081Y301488D01*
X-1924598Y301871D01*
X-1925321Y302025D01*
X-1926045Y301871D01*
X-1926665Y301411D01*
X-1926975Y300721D01*
Y299955D01*
X-1927181Y299495D01*
X-1927698Y299111D01*
X-1928421Y298958D01*
X-1929145Y299188D01*
X-1929661Y299725D01*
X-1929868Y300338D01*
X-1929661Y300951D01*
X-1929145Y301488D01*
X-1928421Y301718D01*
X-1927698Y301565D01*
X-1927181Y301181D01*
X-1926975Y300721D01*
Y299955D01*
X-1926665Y299265D01*
X-1926045Y298805D01*
X-1925321Y298651D01*
X-1924598Y298805D01*
X-1924081Y299188D01*
X-1923771Y299801D01*
X-1923668Y300338D01*
G01X-1933668Y280205D02*
X-1939868D01*
Y282121D01*
X-1939558Y282735D01*
X-1939145Y283118D01*
X-1938318Y283271D01*
X-1937491Y283118D01*
X-1936975Y282658D01*
X-1936665Y282121D01*
Y280205D01*
G01Y282121D02*
X-1933668Y283271D01*
G01Y288858D02*
X-1939868D01*
X-1935425Y286021D01*
Y289855D01*
G01X-1938835Y292681D02*
X-1939455Y293141D01*
X-1939765Y293678D01*
X-1939868Y294291D01*
X-1939661Y295058D01*
X-1939145Y295595D01*
X-1938525Y295748D01*
X-1937905Y295671D01*
X-1937388Y295365D01*
X-1936355Y293831D01*
X-1935631Y293141D01*
X-1934598Y292681D01*
X-1933668Y292528D01*
Y295748D01*
G01X-1936251Y298881D02*
X-1936975Y299418D01*
X-1937388Y299878D01*
X-1937595Y300491D01*
X-1937388Y301028D01*
X-1936975Y301411D01*
X-1936355Y301718D01*
X-1935631Y301795D01*
X-1935011Y301718D01*
X-1934391Y301411D01*
X-1933875Y300951D01*
X-1933668Y300415D01*
X-1933875Y299801D01*
X-1934494Y299265D01*
X-1935425Y298958D01*
X-1936458Y298881D01*
X-1937801Y299035D01*
X-1938525Y299265D01*
X-1939248Y299648D01*
X-1939765Y300185D01*
X-1939868Y300721D01*
X-1939661Y301258D01*
X-1939145Y301641D01*
G01X-1925444Y309038D02*
X-1923911D01*
Y307178D01*
X-1924371Y306558D01*
X-1924907Y306145D01*
X-1925674Y305938D01*
X-1926441Y306145D01*
X-1926977Y306558D01*
X-1927437Y307178D01*
X-1927744Y307901D01*
X-1927897Y308728D01*
Y309451D01*
X-1927744Y310071D01*
X-1927437Y310795D01*
X-1926977Y311415D01*
X-1926517Y311828D01*
X-1925904Y312138D01*
X-1925367D01*
X-1924754Y311931D01*
X-1924294Y311518D01*
G01X-1921314Y305938D02*
Y312138D01*
G01X-1918094D02*
Y305938D01*
G01Y309038D02*
X-1921314D01*
G01X-1914961Y311105D02*
X-1914501Y311725D01*
X-1913964Y312035D01*
X-1913351Y312138D01*
X-1912584Y311931D01*
X-1912047Y311415D01*
X-1911894Y310795D01*
X-1911971Y310175D01*
X-1912277Y309658D01*
X-1913811Y308625D01*
X-1914501Y307901D01*
X-1914961Y306868D01*
X-1915114Y305938D01*
X-1911894D01*
G01X-1928444Y356038D02*
X-1926911D01*
Y354178D01*
X-1927371Y353558D01*
X-1927907Y353145D01*
X-1928674Y352938D01*
X-1929441Y353145D01*
X-1929977Y353558D01*
X-1930437Y354178D01*
X-1930744Y354901D01*
X-1930897Y355728D01*
Y356451D01*
X-1930744Y357071D01*
X-1930437Y357795D01*
X-1929977Y358415D01*
X-1929517Y358828D01*
X-1928904Y359138D01*
X-1928367D01*
X-1927754Y358931D01*
X-1927294Y358518D01*
G01X-1924314Y352938D02*
Y359138D01*
G01X-1921094D02*
Y352938D01*
G01Y356038D02*
X-1924314D01*
G01X-1916504Y352938D02*
Y359138D01*
X-1917424Y357898D01*
G01Y352938D02*
X-1915584D01*
G01X-1908535Y-225640D02*
X-1908075Y-226157D01*
X-1907538Y-226467D01*
X-1906848Y-226570D01*
X-1906158Y-226363D01*
X-1905621Y-225950D01*
X-1905238Y-225227D01*
X-1905161Y-224400D01*
X-1905315Y-223573D01*
X-1905698Y-223057D01*
X-1906235Y-222643D01*
X-1906771Y-222540D01*
X-1907308Y-222643D01*
X-1907998Y-223057D01*
X-1907768Y-220370D01*
X-1905698D01*
G01X-1909784Y-197206D02*
Y-191006D01*
X-1912621Y-195449D01*
X-1908787D01*
G01X-1911636Y-180795D02*
X-1917836D01*
Y-178879D01*
X-1917526Y-178265D01*
X-1917113Y-177882D01*
X-1916286Y-177729D01*
X-1915459Y-177882D01*
X-1914943Y-178342D01*
X-1914633Y-178879D01*
Y-180795D01*
G01Y-178879D02*
X-1911636Y-177729D01*
G01X-1912876Y-174749D02*
X-1912153Y-174289D01*
X-1911739Y-173675D01*
X-1911636Y-172985D01*
X-1911739Y-172372D01*
X-1912256Y-171759D01*
X-1912876Y-171375D01*
X-1913496Y-171299D01*
X-1914219Y-171452D01*
X-1914736Y-171989D01*
X-1914943Y-172525D01*
Y-173215D01*
G01Y-172525D02*
X-1915253Y-172065D01*
X-1915769Y-171682D01*
X-1916389Y-171529D01*
X-1917009Y-171682D01*
X-1917526Y-172065D01*
X-1917836Y-172755D01*
X-1917733Y-173445D01*
X-1917319Y-174135D01*
G01X-1911636Y-167015D02*
X-1912979Y-166862D01*
X-1914116Y-166632D01*
X-1915149Y-166325D01*
X-1916286Y-165942D01*
X-1917836Y-165329D01*
Y-168395D01*
G01Y-160662D02*
X-1917629Y-161275D01*
X-1917113Y-161735D01*
X-1916493Y-162042D01*
X-1915666Y-162272D01*
X-1914736Y-162349D01*
X-1913806Y-162272D01*
X-1912979Y-162042D01*
X-1912359Y-161735D01*
X-1911843Y-161275D01*
X-1911636Y-160662D01*
X-1911843Y-160049D01*
X-1912359Y-159589D01*
X-1912979Y-159282D01*
X-1913806Y-159052D01*
X-1914736Y-158975D01*
X-1915666Y-159052D01*
X-1916493Y-159282D01*
X-1917113Y-159589D01*
X-1917629Y-160049D01*
X-1917836Y-160662D01*
G01X-1901636Y-180795D02*
X-1907836D01*
Y-178879D01*
X-1907526Y-178265D01*
X-1907113Y-177882D01*
X-1906286Y-177729D01*
X-1905459Y-177882D01*
X-1904943Y-178342D01*
X-1904633Y-178879D01*
Y-180795D01*
G01Y-178879D02*
X-1901636Y-177729D01*
G01Y-173062D02*
X-1907836D01*
X-1906596Y-173982D01*
G01X-1901636D02*
Y-172142D01*
G01X-1902566Y-168549D02*
X-1902049Y-168089D01*
X-1901739Y-167552D01*
X-1901636Y-166862D01*
X-1901843Y-166172D01*
X-1902256Y-165635D01*
X-1902979Y-165252D01*
X-1903806Y-165175D01*
X-1904633Y-165329D01*
X-1905149Y-165712D01*
X-1905563Y-166249D01*
X-1905666Y-166785D01*
X-1905563Y-167322D01*
X-1905149Y-168012D01*
X-1907836Y-167782D01*
Y-165712D01*
G01X-1901636Y-160815D02*
X-1902979Y-160662D01*
X-1904116Y-160432D01*
X-1905149Y-160125D01*
X-1906286Y-159742D01*
X-1907836Y-159129D01*
Y-162195D01*
G01X-1914459Y-148293D02*
X-1914919Y-147983D01*
X-1915456Y-147776D01*
X-1916069D01*
X-1916759Y-148086D01*
X-1917296Y-148603D01*
X-1917679Y-149223D01*
X-1917986Y-150256D01*
X-1918063Y-151186D01*
X-1917909Y-152116D01*
X-1917679Y-152736D01*
X-1917219Y-153356D01*
X-1916683Y-153769D01*
X-1916146Y-153976D01*
X-1915609D01*
X-1915073Y-153769D01*
X-1914613Y-153459D01*
X-1914229Y-153046D01*
G01X-1911633Y-152736D02*
X-1911173Y-153459D01*
X-1910559Y-153873D01*
X-1909869Y-153976D01*
X-1909256Y-153873D01*
X-1908643Y-153356D01*
X-1908259Y-152736D01*
X-1908183Y-152116D01*
X-1908336Y-151393D01*
X-1908873Y-150876D01*
X-1909409Y-150669D01*
X-1910099D01*
G01X-1909409D02*
X-1908949Y-150359D01*
X-1908566Y-149843D01*
X-1908413Y-149223D01*
X-1908566Y-148603D01*
X-1908949Y-148086D01*
X-1909639Y-147776D01*
X-1910329Y-147879D01*
X-1911019Y-148293D01*
G01X-1903746Y-153976D02*
Y-147776D01*
X-1904666Y-149016D01*
G01Y-153976D02*
X-1902826D01*
G01X-1897546D02*
Y-147776D01*
X-1898466Y-149016D01*
G01Y-153976D02*
X-1896626D01*
G01X-1916604Y-142795D02*
X-1922804D01*
Y-140879D01*
X-1922494Y-140265D01*
X-1922081Y-139882D01*
X-1921254Y-139729D01*
X-1920427Y-139882D01*
X-1919911Y-140342D01*
X-1919601Y-140879D01*
Y-142795D01*
G01Y-140879D02*
X-1916604Y-139729D01*
G01Y-135062D02*
X-1922804D01*
X-1921564Y-135982D01*
G01X-1916604D02*
Y-134142D01*
G01X-1921771Y-130319D02*
X-1922391Y-129859D01*
X-1922701Y-129322D01*
X-1922804Y-128709D01*
X-1922597Y-127942D01*
X-1922081Y-127405D01*
X-1921461Y-127252D01*
X-1920841Y-127329D01*
X-1920324Y-127635D01*
X-1919291Y-129169D01*
X-1918567Y-129859D01*
X-1917534Y-130319D01*
X-1916604Y-130472D01*
Y-127252D01*
G01X-1921771Y-124119D02*
X-1922391Y-123659D01*
X-1922701Y-123122D01*
X-1922804Y-122509D01*
X-1922597Y-121742D01*
X-1922081Y-121205D01*
X-1921461Y-121052D01*
X-1920841Y-121129D01*
X-1920324Y-121435D01*
X-1919291Y-122969D01*
X-1918567Y-123659D01*
X-1917534Y-124119D01*
X-1916604Y-124272D01*
Y-121052D01*
G01X-1906604Y-142795D02*
X-1912804D01*
Y-140879D01*
X-1912494Y-140265D01*
X-1912081Y-139882D01*
X-1911254Y-139729D01*
X-1910427Y-139882D01*
X-1909911Y-140342D01*
X-1909601Y-140879D01*
Y-142795D01*
G01Y-140879D02*
X-1906604Y-139729D01*
G01X-1907844Y-136749D02*
X-1907121Y-136289D01*
X-1906707Y-135675D01*
X-1906604Y-134985D01*
X-1906707Y-134372D01*
X-1907224Y-133759D01*
X-1907844Y-133375D01*
X-1908464Y-133299D01*
X-1909187Y-133452D01*
X-1909704Y-133989D01*
X-1909911Y-134525D01*
Y-135215D01*
G01Y-134525D02*
X-1910221Y-134065D01*
X-1910737Y-133682D01*
X-1911357Y-133529D01*
X-1911977Y-133682D01*
X-1912494Y-134065D01*
X-1912804Y-134755D01*
X-1912701Y-135445D01*
X-1912287Y-136135D01*
G01X-1906604Y-129015D02*
X-1907947Y-128862D01*
X-1909084Y-128632D01*
X-1910117Y-128325D01*
X-1911254Y-127942D01*
X-1912804Y-127329D01*
Y-130395D01*
G01X-1906604Y-122815D02*
X-1907947Y-122662D01*
X-1909084Y-122432D01*
X-1910117Y-122125D01*
X-1911254Y-121742D01*
X-1912804Y-121129D01*
Y-124195D01*
G01X-1916604Y-117795D02*
X-1922804D01*
Y-115879D01*
X-1922494Y-115265D01*
X-1922081Y-114882D01*
X-1921254Y-114729D01*
X-1920427Y-114882D01*
X-1919911Y-115342D01*
X-1919601Y-115879D01*
Y-117795D01*
G01Y-115879D02*
X-1916604Y-114729D01*
G01Y-109142D02*
X-1922804D01*
X-1918361Y-111979D01*
Y-108145D01*
G01X-1917327Y-105165D02*
X-1916811Y-104629D01*
X-1916604Y-104015D01*
X-1916811Y-103402D01*
X-1917430Y-102865D01*
X-1918361Y-102482D01*
X-1919291Y-102329D01*
X-1920427D01*
X-1921357Y-102482D01*
X-1922184Y-102865D01*
X-1922597Y-103325D01*
X-1922804Y-103862D01*
X-1922597Y-104475D01*
X-1922184Y-104935D01*
X-1921564Y-105242D01*
X-1920737Y-105395D01*
X-1920014Y-105242D01*
X-1919291Y-104859D01*
X-1918877Y-104399D01*
X-1918774Y-103862D01*
X-1918981Y-103249D01*
X-1919497Y-102789D01*
X-1920427Y-102329D01*
G01X-1919187Y-99119D02*
X-1919911Y-98582D01*
X-1920324Y-98122D01*
X-1920531Y-97509D01*
X-1920324Y-96972D01*
X-1919911Y-96589D01*
X-1919291Y-96282D01*
X-1918567Y-96205D01*
X-1917947Y-96282D01*
X-1917327Y-96589D01*
X-1916811Y-97049D01*
X-1916604Y-97585D01*
X-1916811Y-98199D01*
X-1917430Y-98735D01*
X-1918361Y-99042D01*
X-1919394Y-99119D01*
X-1920737Y-98965D01*
X-1921461Y-98735D01*
X-1922184Y-98352D01*
X-1922701Y-97815D01*
X-1922804Y-97279D01*
X-1922597Y-96742D01*
X-1922081Y-96359D01*
G01X-1908535Y-111468D02*
X-1908075Y-111985D01*
X-1907538Y-112295D01*
X-1906848Y-112398D01*
X-1906158Y-112191D01*
X-1905621Y-111778D01*
X-1905238Y-111055D01*
X-1905161Y-110228D01*
X-1905315Y-109401D01*
X-1905698Y-108885D01*
X-1906235Y-108471D01*
X-1906771Y-108368D01*
X-1907308Y-108471D01*
X-1907998Y-108885D01*
X-1907768Y-106198D01*
X-1905698D01*
G01X-1907784Y-83144D02*
Y-76944D01*
X-1910621Y-81387D01*
X-1906787D01*
G01X-1912636Y-68795D02*
X-1918836D01*
Y-66879D01*
X-1918526Y-66265D01*
X-1918113Y-65882D01*
X-1917286Y-65729D01*
X-1916459Y-65882D01*
X-1915943Y-66342D01*
X-1915633Y-66879D01*
Y-68795D01*
G01Y-66879D02*
X-1912636Y-65729D01*
G01X-1913876Y-62749D02*
X-1913153Y-62289D01*
X-1912739Y-61675D01*
X-1912636Y-60985D01*
X-1912739Y-60372D01*
X-1913256Y-59759D01*
X-1913876Y-59375D01*
X-1914496Y-59299D01*
X-1915219Y-59452D01*
X-1915736Y-59989D01*
X-1915943Y-60525D01*
Y-61215D01*
G01Y-60525D02*
X-1916253Y-60065D01*
X-1916769Y-59682D01*
X-1917389Y-59529D01*
X-1918009Y-59682D01*
X-1918526Y-60065D01*
X-1918836Y-60755D01*
X-1918733Y-61445D01*
X-1918319Y-62135D01*
G01X-1915219Y-56319D02*
X-1915943Y-55782D01*
X-1916356Y-55322D01*
X-1916563Y-54709D01*
X-1916356Y-54172D01*
X-1915943Y-53789D01*
X-1915323Y-53482D01*
X-1914599Y-53405D01*
X-1913979Y-53482D01*
X-1913359Y-53789D01*
X-1912843Y-54249D01*
X-1912636Y-54785D01*
X-1912843Y-55399D01*
X-1913462Y-55935D01*
X-1914393Y-56242D01*
X-1915426Y-56319D01*
X-1916769Y-56165D01*
X-1917493Y-55935D01*
X-1918216Y-55552D01*
X-1918733Y-55015D01*
X-1918836Y-54479D01*
X-1918629Y-53942D01*
X-1918113Y-53559D01*
G01X-1912636Y-48815D02*
X-1913979Y-48662D01*
X-1915116Y-48432D01*
X-1916149Y-48125D01*
X-1917286Y-47742D01*
X-1918836Y-47129D01*
Y-50195D01*
G01X-1901604Y-68795D02*
X-1907804D01*
Y-66879D01*
X-1907494Y-66265D01*
X-1907081Y-65882D01*
X-1906254Y-65729D01*
X-1905427Y-65882D01*
X-1904911Y-66342D01*
X-1904601Y-66879D01*
Y-68795D01*
G01Y-66879D02*
X-1901604Y-65729D01*
G01Y-61062D02*
X-1907804D01*
X-1906564Y-61982D01*
G01X-1901604D02*
Y-60142D01*
G01X-1902534Y-56549D02*
X-1902017Y-56089D01*
X-1901707Y-55552D01*
X-1901604Y-54862D01*
X-1901811Y-54172D01*
X-1902224Y-53635D01*
X-1902947Y-53252D01*
X-1903774Y-53175D01*
X-1904601Y-53329D01*
X-1905117Y-53712D01*
X-1905531Y-54249D01*
X-1905634Y-54785D01*
X-1905531Y-55322D01*
X-1905117Y-56012D01*
X-1907804Y-55782D01*
Y-53712D01*
G01X-1904187Y-50119D02*
X-1904911Y-49582D01*
X-1905324Y-49122D01*
X-1905531Y-48509D01*
X-1905324Y-47972D01*
X-1904911Y-47589D01*
X-1904291Y-47282D01*
X-1903567Y-47205D01*
X-1902947Y-47282D01*
X-1902327Y-47589D01*
X-1901811Y-48049D01*
X-1901604Y-48585D01*
X-1901811Y-49199D01*
X-1902430Y-49735D01*
X-1903361Y-50042D01*
X-1904394Y-50119D01*
X-1905737Y-49965D01*
X-1906461Y-49735D01*
X-1907184Y-49352D01*
X-1907701Y-48815D01*
X-1907804Y-48279D01*
X-1907597Y-47742D01*
X-1907081Y-47359D01*
G01X-1916604Y-30795D02*
X-1922804D01*
Y-28879D01*
X-1922494Y-28265D01*
X-1922081Y-27882D01*
X-1921254Y-27729D01*
X-1920427Y-27882D01*
X-1919911Y-28342D01*
X-1919601Y-28879D01*
Y-30795D01*
G01Y-28879D02*
X-1916604Y-27729D01*
G01Y-22142D02*
X-1922804D01*
X-1918361Y-24979D01*
Y-21145D01*
G01X-1917327Y-18165D02*
X-1916811Y-17629D01*
X-1916604Y-17015D01*
X-1916811Y-16402D01*
X-1917430Y-15865D01*
X-1918361Y-15482D01*
X-1919291Y-15329D01*
X-1920427D01*
X-1921357Y-15482D01*
X-1922184Y-15865D01*
X-1922597Y-16325D01*
X-1922804Y-16862D01*
X-1922597Y-17475D01*
X-1922184Y-17935D01*
X-1921564Y-18242D01*
X-1920737Y-18395D01*
X-1920014Y-18242D01*
X-1919291Y-17859D01*
X-1918877Y-17399D01*
X-1918774Y-16862D01*
X-1918981Y-16249D01*
X-1919497Y-15789D01*
X-1920427Y-15329D01*
G01X-1917327Y-11965D02*
X-1916811Y-11429D01*
X-1916604Y-10815D01*
X-1916811Y-10202D01*
X-1917430Y-9665D01*
X-1918361Y-9282D01*
X-1919291Y-9129D01*
X-1920427D01*
X-1921357Y-9282D01*
X-1922184Y-9665D01*
X-1922597Y-10125D01*
X-1922804Y-10662D01*
X-1922597Y-11275D01*
X-1922184Y-11735D01*
X-1921564Y-12042D01*
X-1920737Y-12195D01*
X-1920014Y-12042D01*
X-1919291Y-11659D01*
X-1918877Y-11199D01*
X-1918774Y-10662D01*
X-1918981Y-10049D01*
X-1919497Y-9589D01*
X-1920427Y-9129D01*
G01X-1916317Y-33379D02*
X-1916777Y-33069D01*
X-1917314Y-32862D01*
X-1917927D01*
X-1918617Y-33172D01*
X-1919154Y-33689D01*
X-1919537Y-34309D01*
X-1919844Y-35342D01*
X-1919921Y-36272D01*
X-1919767Y-37202D01*
X-1919537Y-37822D01*
X-1919077Y-38442D01*
X-1918541Y-38855D01*
X-1918004Y-39062D01*
X-1917467D01*
X-1916931Y-38855D01*
X-1916471Y-38545D01*
X-1916087Y-38132D01*
G01X-1913491Y-37822D02*
X-1913031Y-38545D01*
X-1912417Y-38959D01*
X-1911727Y-39062D01*
X-1911114Y-38959D01*
X-1910501Y-38442D01*
X-1910117Y-37822D01*
X-1910041Y-37202D01*
X-1910194Y-36479D01*
X-1910731Y-35962D01*
X-1911267Y-35755D01*
X-1911957D01*
G01X-1911267D02*
X-1910807Y-35445D01*
X-1910424Y-34929D01*
X-1910271Y-34309D01*
X-1910424Y-33689D01*
X-1910807Y-33172D01*
X-1911497Y-32862D01*
X-1912187Y-32965D01*
X-1912877Y-33379D01*
G01X-1905604Y-39062D02*
Y-32862D01*
X-1906524Y-34102D01*
G01Y-39062D02*
X-1904684D01*
G01X-1899404Y-32862D02*
X-1900017Y-33069D01*
X-1900477Y-33585D01*
X-1900784Y-34205D01*
X-1901014Y-35032D01*
X-1901091Y-35962D01*
X-1901014Y-36892D01*
X-1900784Y-37719D01*
X-1900477Y-38339D01*
X-1900017Y-38855D01*
X-1899404Y-39062D01*
X-1898791Y-38855D01*
X-1898331Y-38339D01*
X-1898024Y-37719D01*
X-1897794Y-36892D01*
X-1897717Y-35962D01*
X-1897794Y-35032D01*
X-1898024Y-34205D01*
X-1898331Y-33585D01*
X-1898791Y-33069D01*
X-1899404Y-32862D01*
G01X-1914537Y-24062D02*
Y-17862D01*
X-1912621D01*
X-1912007Y-18172D01*
X-1911624Y-18585D01*
X-1911471Y-19412D01*
X-1911624Y-20239D01*
X-1912084Y-20755D01*
X-1912621Y-21065D01*
X-1914537D01*
G01X-1912621D02*
X-1911471Y-24062D01*
G01X-1908491Y-22822D02*
X-1908031Y-23545D01*
X-1907417Y-23959D01*
X-1906727Y-24062D01*
X-1906114Y-23959D01*
X-1905501Y-23442D01*
X-1905117Y-22822D01*
X-1905041Y-22202D01*
X-1905194Y-21479D01*
X-1905731Y-20962D01*
X-1906267Y-20755D01*
X-1906957D01*
G01X-1906267D02*
X-1905807Y-20445D01*
X-1905424Y-19929D01*
X-1905271Y-19309D01*
X-1905424Y-18689D01*
X-1905807Y-18172D01*
X-1906497Y-17862D01*
X-1907187Y-17965D01*
X-1907877Y-18379D01*
G01X-1900604Y-24062D02*
X-1900067Y-23959D01*
X-1899454Y-23649D01*
X-1899071Y-23132D01*
X-1898917Y-22409D01*
X-1899071Y-21685D01*
X-1899531Y-21065D01*
X-1900221Y-20755D01*
X-1900987D01*
X-1901447Y-20549D01*
X-1901831Y-20032D01*
X-1901984Y-19309D01*
X-1901754Y-18585D01*
X-1901217Y-18069D01*
X-1900604Y-17862D01*
X-1899991Y-18069D01*
X-1899454Y-18585D01*
X-1899224Y-19309D01*
X-1899377Y-20032D01*
X-1899761Y-20549D01*
X-1900221Y-20755D01*
X-1900987D01*
X-1901677Y-21065D01*
X-1902137Y-21685D01*
X-1902291Y-22409D01*
X-1902137Y-23132D01*
X-1901754Y-23649D01*
X-1901141Y-23959D01*
X-1900604Y-24062D01*
G01X-1896091Y-22822D02*
X-1895631Y-23545D01*
X-1895017Y-23959D01*
X-1894327Y-24062D01*
X-1893714Y-23959D01*
X-1893101Y-23442D01*
X-1892717Y-22822D01*
X-1892641Y-22202D01*
X-1892794Y-21479D01*
X-1893331Y-20962D01*
X-1893867Y-20755D01*
X-1894557D01*
G01X-1893867D02*
X-1893407Y-20445D01*
X-1893024Y-19929D01*
X-1892871Y-19309D01*
X-1893024Y-18689D01*
X-1893407Y-18172D01*
X-1894097Y-17862D01*
X-1894787Y-17965D01*
X-1895477Y-18379D01*
G01X-1913004Y-3862D02*
Y-10062D01*
G01X-1914767Y-3862D02*
X-1911241D01*
G01X-1908337Y-10062D02*
Y-3862D01*
X-1906497D01*
X-1905884Y-4172D01*
X-1905424Y-4895D01*
X-1905271Y-5722D01*
X-1905424Y-6549D01*
X-1905807Y-7169D01*
X-1906497Y-7479D01*
X-1908337D01*
G01X-1902061Y-4895D02*
X-1901601Y-4275D01*
X-1901064Y-3965D01*
X-1900451Y-3862D01*
X-1899684Y-4069D01*
X-1899147Y-4585D01*
X-1898994Y-5205D01*
X-1899071Y-5825D01*
X-1899377Y-6342D01*
X-1900911Y-7375D01*
X-1901601Y-8099D01*
X-1902061Y-9132D01*
X-1902214Y-10062D01*
X-1898994D01*
G01X-1895707Y-9339D02*
X-1895171Y-9855D01*
X-1894557Y-10062D01*
X-1893944Y-9855D01*
X-1893407Y-9236D01*
X-1893024Y-8305D01*
X-1892871Y-7375D01*
Y-6239D01*
X-1893024Y-5309D01*
X-1893407Y-4482D01*
X-1893867Y-4069D01*
X-1894404Y-3862D01*
X-1895017Y-4069D01*
X-1895477Y-4482D01*
X-1895784Y-5102D01*
X-1895937Y-5929D01*
X-1895784Y-6652D01*
X-1895401Y-7375D01*
X-1894941Y-7789D01*
X-1894404Y-7892D01*
X-1893791Y-7685D01*
X-1893331Y-7169D01*
X-1892871Y-6239D01*
G01X-1917604Y-3795D02*
X-1923804D01*
Y-1879D01*
X-1923494Y-1265D01*
X-1923081Y-882D01*
X-1922254Y-729D01*
X-1921427Y-882D01*
X-1920911Y-1342D01*
X-1920601Y-1879D01*
Y-3795D01*
G01Y-1879D02*
X-1917604Y-729D01*
G01Y3938D02*
X-1923804D01*
X-1922564Y3018D01*
G01X-1917604D02*
Y4858D01*
G01X-1922771Y8681D02*
X-1923391Y9141D01*
X-1923701Y9678D01*
X-1923804Y10291D01*
X-1923597Y11058D01*
X-1923081Y11595D01*
X-1922461Y11748D01*
X-1921841Y11671D01*
X-1921324Y11365D01*
X-1920291Y9831D01*
X-1919567Y9141D01*
X-1918534Y8681D01*
X-1917604Y8528D01*
Y11748D01*
G01X-1920187Y14881D02*
X-1920911Y15418D01*
X-1921324Y15878D01*
X-1921531Y16491D01*
X-1921324Y17028D01*
X-1920911Y17411D01*
X-1920291Y17718D01*
X-1919567Y17795D01*
X-1918947Y17718D01*
X-1918327Y17411D01*
X-1917811Y16951D01*
X-1917604Y16415D01*
X-1917811Y15801D01*
X-1918430Y15265D01*
X-1919361Y14958D01*
X-1920394Y14881D01*
X-1921737Y15035D01*
X-1922461Y15265D01*
X-1923184Y15648D01*
X-1923701Y16185D01*
X-1923804Y16721D01*
X-1923597Y17258D01*
X-1923081Y17641D01*
G01X-1912391Y868D02*
X-1911931Y351D01*
X-1911394Y41D01*
X-1910704Y-62D01*
X-1910014Y145D01*
X-1909477Y558D01*
X-1909094Y1281D01*
X-1909017Y2108D01*
X-1909171Y2935D01*
X-1909554Y3451D01*
X-1910091Y3865D01*
X-1910627Y3968D01*
X-1911164Y3865D01*
X-1911854Y3451D01*
X-1911624Y6138D01*
X-1909554D01*
G01X-1910784Y30938D02*
Y37138D01*
X-1913621Y32695D01*
X-1909787D01*
G01X-1912636Y52205D02*
X-1918836D01*
Y54121D01*
X-1918526Y54735D01*
X-1918113Y55118D01*
X-1917286Y55271D01*
X-1916459Y55118D01*
X-1915943Y54658D01*
X-1915633Y54121D01*
Y52205D01*
G01Y54121D02*
X-1912636Y55271D01*
G01X-1913876Y58251D02*
X-1913153Y58711D01*
X-1912739Y59325D01*
X-1912636Y60015D01*
X-1912739Y60628D01*
X-1913256Y61241D01*
X-1913876Y61625D01*
X-1914496Y61701D01*
X-1915219Y61548D01*
X-1915736Y61011D01*
X-1915943Y60475D01*
Y59785D01*
G01Y60475D02*
X-1916253Y60935D01*
X-1916769Y61318D01*
X-1917389Y61471D01*
X-1918009Y61318D01*
X-1918526Y60935D01*
X-1918836Y60245D01*
X-1918733Y59555D01*
X-1918319Y58865D01*
G01X-1912636Y65985D02*
X-1913979Y66138D01*
X-1915116Y66368D01*
X-1916149Y66675D01*
X-1917286Y67058D01*
X-1918836Y67671D01*
Y64605D01*
G01X-1917803Y70881D02*
X-1918423Y71341D01*
X-1918733Y71878D01*
X-1918836Y72491D01*
X-1918629Y73258D01*
X-1918113Y73795D01*
X-1917493Y73948D01*
X-1916873Y73871D01*
X-1916356Y73565D01*
X-1915323Y72031D01*
X-1914599Y71341D01*
X-1913566Y70881D01*
X-1912636Y70728D01*
Y73948D01*
G01X-1902636Y52205D02*
X-1908836D01*
Y54121D01*
X-1908526Y54735D01*
X-1908113Y55118D01*
X-1907286Y55271D01*
X-1906459Y55118D01*
X-1905943Y54658D01*
X-1905633Y54121D01*
Y52205D01*
G01Y54121D02*
X-1902636Y55271D01*
G01Y59938D02*
X-1908836D01*
X-1907596Y59018D01*
G01X-1902636D02*
Y60858D01*
G01X-1907803Y64681D02*
X-1908423Y65141D01*
X-1908733Y65678D01*
X-1908836Y66291D01*
X-1908629Y67058D01*
X-1908113Y67595D01*
X-1907493Y67748D01*
X-1906873Y67671D01*
X-1906356Y67365D01*
X-1905323Y65831D01*
X-1904599Y65141D01*
X-1903566Y64681D01*
X-1902636Y64528D01*
Y67748D01*
G01Y72338D02*
X-1908836D01*
X-1907596Y71418D01*
G01X-1902636D02*
Y73258D01*
G01X-1918317Y83621D02*
X-1918777Y83931D01*
X-1919314Y84138D01*
X-1919927D01*
X-1920617Y83828D01*
X-1921154Y83311D01*
X-1921537Y82691D01*
X-1921844Y81658D01*
X-1921921Y80728D01*
X-1921767Y79798D01*
X-1921537Y79178D01*
X-1921077Y78558D01*
X-1920541Y78145D01*
X-1920004Y77938D01*
X-1919467D01*
X-1918931Y78145D01*
X-1918471Y78455D01*
X-1918087Y78868D01*
G01X-1915491Y79178D02*
X-1915031Y78455D01*
X-1914417Y78041D01*
X-1913727Y77938D01*
X-1913114Y78041D01*
X-1912501Y78558D01*
X-1912117Y79178D01*
X-1912041Y79798D01*
X-1912194Y80521D01*
X-1912731Y81038D01*
X-1913267Y81245D01*
X-1913957D01*
G01X-1913267D02*
X-1912807Y81555D01*
X-1912424Y82071D01*
X-1912271Y82691D01*
X-1912424Y83311D01*
X-1912807Y83828D01*
X-1913497Y84138D01*
X-1914187Y84035D01*
X-1914877Y83621D01*
G01X-1907604Y77938D02*
Y84138D01*
X-1908524Y82898D01*
G01Y77938D02*
X-1906684D01*
G01X-1901404D02*
X-1900867Y78041D01*
X-1900254Y78351D01*
X-1899871Y78868D01*
X-1899717Y79591D01*
X-1899871Y80315D01*
X-1900331Y80935D01*
X-1901021Y81245D01*
X-1901787D01*
X-1902247Y81451D01*
X-1902631Y81968D01*
X-1902784Y82691D01*
X-1902554Y83415D01*
X-1902017Y83931D01*
X-1901404Y84138D01*
X-1900791Y83931D01*
X-1900254Y83415D01*
X-1900024Y82691D01*
X-1900177Y81968D01*
X-1900561Y81451D01*
X-1901021Y81245D01*
X-1901787D01*
X-1902477Y80935D01*
X-1902937Y80315D01*
X-1903091Y79591D01*
X-1902937Y78868D01*
X-1902554Y78351D01*
X-1901941Y78041D01*
X-1901404Y77938D01*
G01X-1915604Y88205D02*
X-1921804D01*
Y90121D01*
X-1921494Y90735D01*
X-1921081Y91118D01*
X-1920254Y91271D01*
X-1919427Y91118D01*
X-1918911Y90658D01*
X-1918601Y90121D01*
Y88205D01*
G01Y90121D02*
X-1915604Y91271D01*
G01Y95938D02*
X-1921804D01*
X-1920564Y95018D01*
G01X-1915604D02*
Y96858D01*
G01X-1920771Y100681D02*
X-1921391Y101141D01*
X-1921701Y101678D01*
X-1921804Y102291D01*
X-1921597Y103058D01*
X-1921081Y103595D01*
X-1920461Y103748D01*
X-1919841Y103671D01*
X-1919324Y103365D01*
X-1918291Y101831D01*
X-1917567Y101141D01*
X-1916534Y100681D01*
X-1915604Y100528D01*
Y103748D01*
G01Y108185D02*
X-1916947Y108338D01*
X-1918084Y108568D01*
X-1919117Y108875D01*
X-1920254Y109258D01*
X-1921804Y109871D01*
Y106805D01*
G01X-1904604Y88205D02*
X-1910804D01*
Y90121D01*
X-1910494Y90735D01*
X-1910081Y91118D01*
X-1909254Y91271D01*
X-1908427Y91118D01*
X-1907911Y90658D01*
X-1907601Y90121D01*
Y88205D01*
G01Y90121D02*
X-1904604Y91271D01*
G01X-1905844Y94251D02*
X-1905121Y94711D01*
X-1904707Y95325D01*
X-1904604Y96015D01*
X-1904707Y96628D01*
X-1905224Y97241D01*
X-1905844Y97625D01*
X-1906464Y97701D01*
X-1907187Y97548D01*
X-1907704Y97011D01*
X-1907911Y96475D01*
Y95785D01*
G01Y96475D02*
X-1908221Y96935D01*
X-1908737Y97318D01*
X-1909357Y97471D01*
X-1909977Y97318D01*
X-1910494Y96935D01*
X-1910804Y96245D01*
X-1910701Y95555D01*
X-1910287Y94865D01*
G01X-1904604Y102138D02*
X-1904707Y102675D01*
X-1905017Y103288D01*
X-1905534Y103671D01*
X-1906257Y103825D01*
X-1906981Y103671D01*
X-1907601Y103211D01*
X-1907911Y102521D01*
Y101755D01*
X-1908117Y101295D01*
X-1908634Y100911D01*
X-1909357Y100758D01*
X-1910081Y100988D01*
X-1910597Y101525D01*
X-1910804Y102138D01*
X-1910597Y102751D01*
X-1910081Y103288D01*
X-1909357Y103518D01*
X-1908634Y103365D01*
X-1908117Y102981D01*
X-1907911Y102521D01*
Y101755D01*
X-1907601Y101065D01*
X-1906981Y100605D01*
X-1906257Y100451D01*
X-1905534Y100605D01*
X-1905017Y100988D01*
X-1904707Y101601D01*
X-1904604Y102138D01*
G01Y108338D02*
X-1910804D01*
X-1909564Y107418D01*
G01X-1904604D02*
Y109258D01*
G01X-1917604Y113205D02*
X-1923804D01*
Y115121D01*
X-1923494Y115735D01*
X-1923081Y116118D01*
X-1922254Y116271D01*
X-1921427Y116118D01*
X-1920911Y115658D01*
X-1920601Y115121D01*
Y113205D01*
G01Y115121D02*
X-1917604Y116271D01*
G01Y121858D02*
X-1923804D01*
X-1919361Y119021D01*
Y122855D01*
G01X-1918327Y125835D02*
X-1917811Y126371D01*
X-1917604Y126985D01*
X-1917811Y127598D01*
X-1918430Y128135D01*
X-1919361Y128518D01*
X-1920291Y128671D01*
X-1921427D01*
X-1922357Y128518D01*
X-1923184Y128135D01*
X-1923597Y127675D01*
X-1923804Y127138D01*
X-1923597Y126525D01*
X-1923184Y126065D01*
X-1922564Y125758D01*
X-1921737Y125605D01*
X-1921014Y125758D01*
X-1920291Y126141D01*
X-1919877Y126601D01*
X-1919774Y127138D01*
X-1919981Y127751D01*
X-1920497Y128211D01*
X-1921427Y128671D01*
G01X-1917604Y133338D02*
X-1917707Y133875D01*
X-1918017Y134488D01*
X-1918534Y134871D01*
X-1919257Y135025D01*
X-1919981Y134871D01*
X-1920601Y134411D01*
X-1920911Y133721D01*
Y132955D01*
X-1921117Y132495D01*
X-1921634Y132111D01*
X-1922357Y131958D01*
X-1923081Y132188D01*
X-1923597Y132725D01*
X-1923804Y133338D01*
X-1923597Y133951D01*
X-1923081Y134488D01*
X-1922357Y134718D01*
X-1921634Y134565D01*
X-1921117Y134181D01*
X-1920911Y133721D01*
Y132955D01*
X-1920601Y132265D01*
X-1919981Y131805D01*
X-1919257Y131651D01*
X-1918534Y131805D01*
X-1918017Y132188D01*
X-1917707Y132801D01*
X-1917604Y133338D01*
G01X-1913391Y117914D02*
X-1912931Y117397D01*
X-1912394Y117087D01*
X-1911704Y116984D01*
X-1911014Y117191D01*
X-1910477Y117604D01*
X-1910094Y118327D01*
X-1910017Y119154D01*
X-1910171Y119981D01*
X-1910554Y120497D01*
X-1911091Y120911D01*
X-1911627Y121014D01*
X-1912164Y120911D01*
X-1912854Y120497D01*
X-1912624Y123184D01*
X-1910554D01*
G01X-1909784Y146984D02*
Y153184D01*
X-1912621Y148741D01*
X-1908787D01*
G01X-1901604Y156205D02*
X-1907804D01*
Y158121D01*
X-1907494Y158735D01*
X-1907081Y159118D01*
X-1906254Y159271D01*
X-1905427Y159118D01*
X-1904911Y158658D01*
X-1904601Y158121D01*
Y156205D01*
G01Y158121D02*
X-1901604Y159271D01*
G01Y163938D02*
X-1907804D01*
X-1906564Y163018D01*
G01X-1901604D02*
Y164858D01*
G01X-1906771Y168681D02*
X-1907391Y169141D01*
X-1907701Y169678D01*
X-1907804Y170291D01*
X-1907597Y171058D01*
X-1907081Y171595D01*
X-1906461Y171748D01*
X-1905841Y171671D01*
X-1905324Y171365D01*
X-1904291Y169831D01*
X-1903567Y169141D01*
X-1902534Y168681D01*
X-1901604Y168528D01*
Y171748D01*
G01X-1907804Y176338D02*
X-1907597Y175725D01*
X-1907081Y175265D01*
X-1906461Y174958D01*
X-1905634Y174728D01*
X-1904704Y174651D01*
X-1903774Y174728D01*
X-1902947Y174958D01*
X-1902327Y175265D01*
X-1901811Y175725D01*
X-1901604Y176338D01*
X-1901811Y176951D01*
X-1902327Y177411D01*
X-1902947Y177718D01*
X-1903774Y177948D01*
X-1904704Y178025D01*
X-1905634Y177948D01*
X-1906461Y177718D01*
X-1907081Y177411D01*
X-1907597Y176951D01*
X-1907804Y176338D01*
G01X-1913036Y156205D02*
X-1919236D01*
Y158121D01*
X-1918926Y158735D01*
X-1918513Y159118D01*
X-1917686Y159271D01*
X-1916859Y159118D01*
X-1916343Y158658D01*
X-1916033Y158121D01*
Y156205D01*
G01Y158121D02*
X-1913036Y159271D01*
G01X-1914276Y162251D02*
X-1913553Y162711D01*
X-1913139Y163325D01*
X-1913036Y164015D01*
X-1913139Y164628D01*
X-1913656Y165241D01*
X-1914276Y165625D01*
X-1914896Y165701D01*
X-1915619Y165548D01*
X-1916136Y165011D01*
X-1916343Y164475D01*
Y163785D01*
G01Y164475D02*
X-1916653Y164935D01*
X-1917169Y165318D01*
X-1917789Y165471D01*
X-1918409Y165318D01*
X-1918926Y164935D01*
X-1919236Y164245D01*
X-1919133Y163555D01*
X-1918719Y162865D01*
G01X-1913036Y169985D02*
X-1914379Y170138D01*
X-1915516Y170368D01*
X-1916549Y170675D01*
X-1917686Y171058D01*
X-1919236Y171671D01*
Y168605D01*
G01X-1913036Y176338D02*
X-1919236D01*
X-1917996Y175418D01*
G01X-1913036D02*
Y177258D01*
G01X-1915859Y187707D02*
X-1916319Y188017D01*
X-1916856Y188224D01*
X-1917469D01*
X-1918159Y187914D01*
X-1918696Y187397D01*
X-1919079Y186777D01*
X-1919386Y185744D01*
X-1919463Y184814D01*
X-1919309Y183884D01*
X-1919079Y183264D01*
X-1918619Y182644D01*
X-1918083Y182231D01*
X-1917546Y182024D01*
X-1917009D01*
X-1916473Y182231D01*
X-1916013Y182541D01*
X-1915629Y182954D01*
G01X-1913033Y183264D02*
X-1912573Y182541D01*
X-1911959Y182127D01*
X-1911269Y182024D01*
X-1910656Y182127D01*
X-1910043Y182644D01*
X-1909659Y183264D01*
X-1909583Y183884D01*
X-1909736Y184607D01*
X-1910273Y185124D01*
X-1910809Y185331D01*
X-1911499D01*
G01X-1910809D02*
X-1910349Y185641D01*
X-1909966Y186157D01*
X-1909813Y186777D01*
X-1909966Y187397D01*
X-1910349Y187914D01*
X-1911039Y188224D01*
X-1911729Y188121D01*
X-1912419Y187707D01*
G01X-1905146Y182024D02*
Y188224D01*
X-1906066Y186984D01*
G01Y182024D02*
X-1904226D01*
G01X-1899099D02*
X-1898946Y183367D01*
X-1898716Y184504D01*
X-1898409Y185537D01*
X-1898026Y186674D01*
X-1897413Y188224D01*
X-1900479D01*
G01X-1894084Y-226672D02*
X-1893547Y-226569D01*
X-1892934Y-226259D01*
X-1892551Y-225742D01*
X-1892397Y-225019D01*
X-1892551Y-224295D01*
X-1893011Y-223675D01*
X-1893701Y-223365D01*
X-1894467D01*
X-1894927Y-223159D01*
X-1895311Y-222642D01*
X-1895464Y-221919D01*
X-1895234Y-221195D01*
X-1894697Y-220679D01*
X-1894084Y-220472D01*
X-1893471Y-220679D01*
X-1892934Y-221195D01*
X-1892704Y-221919D01*
X-1892857Y-222642D01*
X-1893241Y-223159D01*
X-1893701Y-223365D01*
X-1894467D01*
X-1895157Y-223675D01*
X-1895617Y-224295D01*
X-1895771Y-225019D01*
X-1895617Y-225742D01*
X-1895234Y-226259D01*
X-1894621Y-226569D01*
X-1894084Y-226672D01*
G01X-1904356Y-216329D02*
X-1899913D01*
X-1898982Y-216022D01*
X-1898363Y-215409D01*
X-1898156Y-214642D01*
X-1898363Y-213875D01*
X-1898982Y-213262D01*
X-1899913Y-212955D01*
X-1904356D01*
G01X-1898156Y-208442D02*
X-1904356D01*
X-1903116Y-209362D01*
G01X-1898156D02*
Y-207522D01*
G01Y-201322D02*
X-1904356D01*
X-1899913Y-204159D01*
Y-200325D01*
G01X-1890038Y-207780D02*
Y-213980D01*
G01X-1891801Y-207780D02*
X-1888275D01*
G01X-1885371Y-213980D02*
Y-207780D01*
X-1883531D01*
X-1882918Y-208090D01*
X-1882458Y-208813D01*
X-1882305Y-209640D01*
X-1882458Y-210467D01*
X-1882841Y-211087D01*
X-1883531Y-211397D01*
X-1885371D01*
G01X-1879325Y-212740D02*
X-1878865Y-213463D01*
X-1878251Y-213877D01*
X-1877561Y-213980D01*
X-1876948Y-213877D01*
X-1876335Y-213360D01*
X-1875951Y-212740D01*
X-1875875Y-212120D01*
X-1876028Y-211397D01*
X-1876565Y-210880D01*
X-1877101Y-210673D01*
X-1877791D01*
G01X-1877101D02*
X-1876641Y-210363D01*
X-1876258Y-209847D01*
X-1876105Y-209227D01*
X-1876258Y-208607D01*
X-1876641Y-208090D01*
X-1877331Y-207780D01*
X-1878021Y-207883D01*
X-1878711Y-208297D01*
G01X-1871438Y-213980D02*
Y-207780D01*
X-1872358Y-209020D01*
G01Y-213980D02*
X-1870518D01*
G01X-1891604Y-180795D02*
X-1897804D01*
Y-178879D01*
X-1897494Y-178265D01*
X-1897081Y-177882D01*
X-1896254Y-177729D01*
X-1895427Y-177882D01*
X-1894911Y-178342D01*
X-1894601Y-178879D01*
Y-180795D01*
G01Y-178879D02*
X-1891604Y-177729D01*
G01X-1892844Y-174749D02*
X-1892121Y-174289D01*
X-1891707Y-173675D01*
X-1891604Y-172985D01*
X-1891707Y-172372D01*
X-1892224Y-171759D01*
X-1892844Y-171375D01*
X-1893464Y-171299D01*
X-1894187Y-171452D01*
X-1894704Y-171989D01*
X-1894911Y-172525D01*
Y-173215D01*
G01Y-172525D02*
X-1895221Y-172065D01*
X-1895737Y-171682D01*
X-1896357Y-171529D01*
X-1896977Y-171682D01*
X-1897494Y-172065D01*
X-1897804Y-172755D01*
X-1897701Y-173445D01*
X-1897287Y-174135D01*
G01X-1894187Y-168319D02*
X-1894911Y-167782D01*
X-1895324Y-167322D01*
X-1895531Y-166709D01*
X-1895324Y-166172D01*
X-1894911Y-165789D01*
X-1894291Y-165482D01*
X-1893567Y-165405D01*
X-1892947Y-165482D01*
X-1892327Y-165789D01*
X-1891811Y-166249D01*
X-1891604Y-166785D01*
X-1891811Y-167399D01*
X-1892430Y-167935D01*
X-1893361Y-168242D01*
X-1894394Y-168319D01*
X-1895737Y-168165D01*
X-1896461Y-167935D01*
X-1897184Y-167552D01*
X-1897701Y-167015D01*
X-1897804Y-166479D01*
X-1897597Y-165942D01*
X-1897081Y-165559D01*
G01X-1891604Y-160662D02*
X-1891707Y-160125D01*
X-1892017Y-159512D01*
X-1892534Y-159129D01*
X-1893257Y-158975D01*
X-1893981Y-159129D01*
X-1894601Y-159589D01*
X-1894911Y-160279D01*
Y-161045D01*
X-1895117Y-161505D01*
X-1895634Y-161889D01*
X-1896357Y-162042D01*
X-1897081Y-161812D01*
X-1897597Y-161275D01*
X-1897804Y-160662D01*
X-1897597Y-160049D01*
X-1897081Y-159512D01*
X-1896357Y-159282D01*
X-1895634Y-159435D01*
X-1895117Y-159819D01*
X-1894911Y-160279D01*
Y-161045D01*
X-1894601Y-161735D01*
X-1893981Y-162195D01*
X-1893257Y-162349D01*
X-1892534Y-162195D01*
X-1892017Y-161812D01*
X-1891707Y-161199D01*
X-1891604Y-160662D01*
G01X-1900804Y-138262D02*
X-1894604D01*
G01X-1900804Y-140025D02*
Y-136499D01*
G01X-1894604Y-133595D02*
X-1900804D01*
Y-131755D01*
X-1900494Y-131142D01*
X-1899771Y-130682D01*
X-1898944Y-130529D01*
X-1898117Y-130682D01*
X-1897497Y-131065D01*
X-1897187Y-131755D01*
Y-133595D01*
G01X-1895844Y-127549D02*
X-1895121Y-127089D01*
X-1894707Y-126475D01*
X-1894604Y-125785D01*
X-1894707Y-125172D01*
X-1895224Y-124559D01*
X-1895844Y-124175D01*
X-1896464Y-124099D01*
X-1897187Y-124252D01*
X-1897704Y-124789D01*
X-1897911Y-125325D01*
Y-126015D01*
G01Y-125325D02*
X-1898221Y-124865D01*
X-1898737Y-124482D01*
X-1899357Y-124329D01*
X-1899977Y-124482D01*
X-1900494Y-124865D01*
X-1900804Y-125555D01*
X-1900701Y-126245D01*
X-1900287Y-126935D01*
G01X-1900804Y-119662D02*
X-1900597Y-120275D01*
X-1900081Y-120735D01*
X-1899461Y-121042D01*
X-1898634Y-121272D01*
X-1897704Y-121349D01*
X-1896774Y-121272D01*
X-1895947Y-121042D01*
X-1895327Y-120735D01*
X-1894811Y-120275D01*
X-1894604Y-119662D01*
X-1894811Y-119049D01*
X-1895327Y-118589D01*
X-1895947Y-118282D01*
X-1896774Y-118052D01*
X-1897704Y-117975D01*
X-1898634Y-118052D01*
X-1899461Y-118282D01*
X-1900081Y-118589D01*
X-1900597Y-119049D01*
X-1900804Y-119662D01*
G01X-1904356Y-102157D02*
X-1899913D01*
X-1898982Y-101850D01*
X-1898363Y-101237D01*
X-1898156Y-100470D01*
X-1898363Y-99703D01*
X-1898982Y-99090D01*
X-1899913Y-98783D01*
X-1904356D01*
G01X-1898156Y-94270D02*
X-1904356D01*
X-1903116Y-95190D01*
G01X-1898156D02*
Y-93350D01*
G01X-1899396Y-89757D02*
X-1898673Y-89297D01*
X-1898259Y-88683D01*
X-1898156Y-87993D01*
X-1898259Y-87380D01*
X-1898776Y-86767D01*
X-1899396Y-86383D01*
X-1900016Y-86307D01*
X-1900739Y-86460D01*
X-1901256Y-86997D01*
X-1901463Y-87533D01*
Y-88223D01*
G01Y-87533D02*
X-1901773Y-87073D01*
X-1902289Y-86690D01*
X-1902909Y-86537D01*
X-1903529Y-86690D01*
X-1904046Y-87073D01*
X-1904356Y-87763D01*
X-1904253Y-88453D01*
X-1903839Y-89143D01*
G01X-1894084Y-112500D02*
X-1893547Y-112397D01*
X-1892934Y-112087D01*
X-1892551Y-111570D01*
X-1892397Y-110847D01*
X-1892551Y-110123D01*
X-1893011Y-109503D01*
X-1893701Y-109193D01*
X-1894467D01*
X-1894927Y-108987D01*
X-1895311Y-108470D01*
X-1895464Y-107747D01*
X-1895234Y-107023D01*
X-1894697Y-106507D01*
X-1894084Y-106300D01*
X-1893471Y-106507D01*
X-1892934Y-107023D01*
X-1892704Y-107747D01*
X-1892857Y-108470D01*
X-1893241Y-108987D01*
X-1893701Y-109193D01*
X-1894467D01*
X-1895157Y-109503D01*
X-1895617Y-110123D01*
X-1895771Y-110847D01*
X-1895617Y-111570D01*
X-1895234Y-112087D01*
X-1894621Y-112397D01*
X-1894084Y-112500D01*
G01X-1889838Y-88780D02*
Y-94980D01*
G01X-1891601Y-88780D02*
X-1888075D01*
G01X-1885171Y-94980D02*
Y-88780D01*
X-1883331D01*
X-1882718Y-89090D01*
X-1882258Y-89813D01*
X-1882105Y-90640D01*
X-1882258Y-91467D01*
X-1882641Y-92087D01*
X-1883331Y-92397D01*
X-1885171D01*
G01X-1879125Y-93740D02*
X-1878665Y-94463D01*
X-1878051Y-94877D01*
X-1877361Y-94980D01*
X-1876748Y-94877D01*
X-1876135Y-94360D01*
X-1875751Y-93740D01*
X-1875675Y-93120D01*
X-1875828Y-92397D01*
X-1876365Y-91880D01*
X-1876901Y-91673D01*
X-1877591D01*
G01X-1876901D02*
X-1876441Y-91363D01*
X-1876058Y-90847D01*
X-1875905Y-90227D01*
X-1876058Y-89607D01*
X-1876441Y-89090D01*
X-1877131Y-88780D01*
X-1877821Y-88883D01*
X-1878511Y-89297D01*
G01X-1870318Y-94980D02*
Y-88780D01*
X-1873155Y-93223D01*
X-1869321D01*
G01X-1891604Y-68795D02*
X-1897804D01*
Y-66879D01*
X-1897494Y-66265D01*
X-1897081Y-65882D01*
X-1896254Y-65729D01*
X-1895427Y-65882D01*
X-1894911Y-66342D01*
X-1894601Y-66879D01*
Y-68795D01*
G01Y-66879D02*
X-1891604Y-65729D01*
G01X-1892844Y-62749D02*
X-1892121Y-62289D01*
X-1891707Y-61675D01*
X-1891604Y-60985D01*
X-1891707Y-60372D01*
X-1892224Y-59759D01*
X-1892844Y-59375D01*
X-1893464Y-59299D01*
X-1894187Y-59452D01*
X-1894704Y-59989D01*
X-1894911Y-60525D01*
Y-61215D01*
G01Y-60525D02*
X-1895221Y-60065D01*
X-1895737Y-59682D01*
X-1896357Y-59529D01*
X-1896977Y-59682D01*
X-1897494Y-60065D01*
X-1897804Y-60755D01*
X-1897701Y-61445D01*
X-1897287Y-62135D01*
G01X-1894187Y-56319D02*
X-1894911Y-55782D01*
X-1895324Y-55322D01*
X-1895531Y-54709D01*
X-1895324Y-54172D01*
X-1894911Y-53789D01*
X-1894291Y-53482D01*
X-1893567Y-53405D01*
X-1892947Y-53482D01*
X-1892327Y-53789D01*
X-1891811Y-54249D01*
X-1891604Y-54785D01*
X-1891811Y-55399D01*
X-1892430Y-55935D01*
X-1893361Y-56242D01*
X-1894394Y-56319D01*
X-1895737Y-56165D01*
X-1896461Y-55935D01*
X-1897184Y-55552D01*
X-1897701Y-55015D01*
X-1897804Y-54479D01*
X-1897597Y-53942D01*
X-1897081Y-53559D01*
G01X-1892534Y-50349D02*
X-1892017Y-49889D01*
X-1891707Y-49352D01*
X-1891604Y-48662D01*
X-1891811Y-47972D01*
X-1892224Y-47435D01*
X-1892947Y-47052D01*
X-1893774Y-46975D01*
X-1894601Y-47129D01*
X-1895117Y-47512D01*
X-1895531Y-48049D01*
X-1895634Y-48585D01*
X-1895531Y-49122D01*
X-1895117Y-49812D01*
X-1897804Y-49582D01*
Y-47512D01*
G01X-1890287Y-23475D02*
X-1890597Y-23935D01*
X-1890804Y-24472D01*
Y-25085D01*
X-1890494Y-25775D01*
X-1889977Y-26312D01*
X-1889357Y-26695D01*
X-1888324Y-27002D01*
X-1887394Y-27079D01*
X-1886464Y-26925D01*
X-1885844Y-26695D01*
X-1885224Y-26235D01*
X-1884811Y-25699D01*
X-1884604Y-25162D01*
Y-24625D01*
X-1884811Y-24089D01*
X-1885121Y-23629D01*
X-1885534Y-23245D01*
G01X-1884604Y-18962D02*
X-1884707Y-18425D01*
X-1885017Y-17812D01*
X-1885534Y-17429D01*
X-1886257Y-17275D01*
X-1886981Y-17429D01*
X-1887601Y-17889D01*
X-1887911Y-18579D01*
Y-19345D01*
X-1888117Y-19805D01*
X-1888634Y-20189D01*
X-1889357Y-20342D01*
X-1890081Y-20112D01*
X-1890597Y-19575D01*
X-1890804Y-18962D01*
X-1890597Y-18349D01*
X-1890081Y-17812D01*
X-1889357Y-17582D01*
X-1888634Y-17735D01*
X-1888117Y-18119D01*
X-1887911Y-18579D01*
Y-19345D01*
X-1887601Y-20035D01*
X-1886981Y-20495D01*
X-1886257Y-20649D01*
X-1885534Y-20495D01*
X-1885017Y-20112D01*
X-1884707Y-19499D01*
X-1884604Y-18962D01*
G01Y-11842D02*
X-1890804D01*
X-1886361Y-14679D01*
Y-10845D01*
G01X-1888704Y938D02*
X-1888167Y1041D01*
X-1887554Y1351D01*
X-1887171Y1868D01*
X-1887017Y2591D01*
X-1887171Y3315D01*
X-1887631Y3935D01*
X-1888321Y4245D01*
X-1889087D01*
X-1889547Y4451D01*
X-1889931Y4968D01*
X-1890084Y5691D01*
X-1889854Y6415D01*
X-1889317Y6931D01*
X-1888704Y7138D01*
X-1888091Y6931D01*
X-1887554Y6415D01*
X-1887324Y5691D01*
X-1887477Y4968D01*
X-1887861Y4451D01*
X-1888321Y4245D01*
X-1889087D01*
X-1889777Y3935D01*
X-1890237Y3315D01*
X-1890391Y2591D01*
X-1890237Y1868D01*
X-1889854Y1351D01*
X-1889241Y1041D01*
X-1888704Y938D01*
G01X-1904356Y12017D02*
X-1899913D01*
X-1898982Y12324D01*
X-1898363Y12937D01*
X-1898156Y13704D01*
X-1898363Y14471D01*
X-1898982Y15084D01*
X-1899913Y15391D01*
X-1904356D01*
G01X-1898156Y19904D02*
X-1904356D01*
X-1903116Y18984D01*
G01X-1898156D02*
Y20824D01*
G01X-1900739Y24647D02*
X-1901463Y25184D01*
X-1901876Y25644D01*
X-1902083Y26257D01*
X-1901876Y26794D01*
X-1901463Y27177D01*
X-1900843Y27484D01*
X-1900119Y27561D01*
X-1899499Y27484D01*
X-1898879Y27177D01*
X-1898363Y26717D01*
X-1898156Y26181D01*
X-1898363Y25567D01*
X-1898982Y25031D01*
X-1899913Y24724D01*
X-1900946Y24647D01*
X-1902289Y24801D01*
X-1903013Y25031D01*
X-1903736Y25414D01*
X-1904253Y25951D01*
X-1904356Y26487D01*
X-1904149Y27024D01*
X-1903633Y27407D01*
G01X-1893004Y49138D02*
Y42938D01*
G01X-1894767Y49138D02*
X-1891241D01*
G01X-1888337Y42938D02*
Y49138D01*
X-1886497D01*
X-1885884Y48828D01*
X-1885424Y48105D01*
X-1885271Y47278D01*
X-1885424Y46451D01*
X-1885807Y45831D01*
X-1886497Y45521D01*
X-1888337D01*
G01X-1882291Y44178D02*
X-1881831Y43455D01*
X-1881217Y43041D01*
X-1880527Y42938D01*
X-1879914Y43041D01*
X-1879301Y43558D01*
X-1878917Y44178D01*
X-1878841Y44798D01*
X-1878994Y45521D01*
X-1879531Y46038D01*
X-1880067Y46245D01*
X-1880757D01*
G01X-1880067D02*
X-1879607Y46555D01*
X-1879224Y47071D01*
X-1879071Y47691D01*
X-1879224Y48311D01*
X-1879607Y48828D01*
X-1880297Y49138D01*
X-1880987Y49035D01*
X-1881677Y48621D01*
G01X-1876091Y44178D02*
X-1875631Y43455D01*
X-1875017Y43041D01*
X-1874327Y42938D01*
X-1873714Y43041D01*
X-1873101Y43558D01*
X-1872717Y44178D01*
X-1872641Y44798D01*
X-1872794Y45521D01*
X-1873331Y46038D01*
X-1873867Y46245D01*
X-1874557D01*
G01X-1873867D02*
X-1873407Y46555D01*
X-1873024Y47071D01*
X-1872871Y47691D01*
X-1873024Y48311D01*
X-1873407Y48828D01*
X-1874097Y49138D01*
X-1874787Y49035D01*
X-1875477Y48621D01*
G01X-1892604Y52205D02*
X-1898804D01*
Y54121D01*
X-1898494Y54735D01*
X-1898081Y55118D01*
X-1897254Y55271D01*
X-1896427Y55118D01*
X-1895911Y54658D01*
X-1895601Y54121D01*
Y52205D01*
G01Y54121D02*
X-1892604Y55271D01*
G01X-1893844Y58251D02*
X-1893121Y58711D01*
X-1892707Y59325D01*
X-1892604Y60015D01*
X-1892707Y60628D01*
X-1893224Y61241D01*
X-1893844Y61625D01*
X-1894464Y61701D01*
X-1895187Y61548D01*
X-1895704Y61011D01*
X-1895911Y60475D01*
Y59785D01*
G01Y60475D02*
X-1896221Y60935D01*
X-1896737Y61318D01*
X-1897357Y61471D01*
X-1897977Y61318D01*
X-1898494Y60935D01*
X-1898804Y60245D01*
X-1898701Y59555D01*
X-1898287Y58865D01*
G01X-1893844Y64451D02*
X-1893121Y64911D01*
X-1892707Y65525D01*
X-1892604Y66215D01*
X-1892707Y66828D01*
X-1893224Y67441D01*
X-1893844Y67825D01*
X-1894464Y67901D01*
X-1895187Y67748D01*
X-1895704Y67211D01*
X-1895911Y66675D01*
Y65985D01*
G01Y66675D02*
X-1896221Y67135D01*
X-1896737Y67518D01*
X-1897357Y67671D01*
X-1897977Y67518D01*
X-1898494Y67135D01*
X-1898804Y66445D01*
X-1898701Y65755D01*
X-1898287Y65065D01*
G01X-1892604Y72338D02*
X-1898804D01*
X-1897564Y71418D01*
G01X-1892604D02*
Y73258D01*
G01X-1898804Y91738D02*
X-1892604D01*
G01X-1898804Y89975D02*
Y93501D01*
G01X-1892604Y96405D02*
X-1898804D01*
Y98245D01*
X-1898494Y98858D01*
X-1897771Y99318D01*
X-1896944Y99471D01*
X-1896117Y99318D01*
X-1895497Y98935D01*
X-1895187Y98245D01*
Y96405D01*
G01X-1897771Y102681D02*
X-1898391Y103141D01*
X-1898701Y103678D01*
X-1898804Y104291D01*
X-1898597Y105058D01*
X-1898081Y105595D01*
X-1897461Y105748D01*
X-1896841Y105671D01*
X-1896324Y105365D01*
X-1895291Y103831D01*
X-1894567Y103141D01*
X-1893534Y102681D01*
X-1892604Y102528D01*
Y105748D01*
G01Y110338D02*
X-1892707Y110875D01*
X-1893017Y111488D01*
X-1893534Y111871D01*
X-1894257Y112025D01*
X-1894981Y111871D01*
X-1895601Y111411D01*
X-1895911Y110721D01*
Y109955D01*
X-1896117Y109495D01*
X-1896634Y109111D01*
X-1897357Y108958D01*
X-1898081Y109188D01*
X-1898597Y109725D01*
X-1898804Y110338D01*
X-1898597Y110951D01*
X-1898081Y111488D01*
X-1897357Y111718D01*
X-1896634Y111565D01*
X-1896117Y111181D01*
X-1895911Y110721D01*
Y109955D01*
X-1895601Y109265D01*
X-1894981Y108805D01*
X-1894257Y108651D01*
X-1893534Y108805D01*
X-1893017Y109188D01*
X-1892707Y109801D01*
X-1892604Y110338D01*
G01X-1890704Y115938D02*
X-1890167Y116041D01*
X-1889554Y116351D01*
X-1889171Y116868D01*
X-1889017Y117591D01*
X-1889171Y118315D01*
X-1889631Y118935D01*
X-1890321Y119245D01*
X-1891087D01*
X-1891547Y119451D01*
X-1891931Y119968D01*
X-1892084Y120691D01*
X-1891854Y121415D01*
X-1891317Y121931D01*
X-1890704Y122138D01*
X-1890091Y121931D01*
X-1889554Y121415D01*
X-1889324Y120691D01*
X-1889477Y119968D01*
X-1889861Y119451D01*
X-1890321Y119245D01*
X-1891087D01*
X-1891777Y118935D01*
X-1892237Y118315D01*
X-1892391Y117591D01*
X-1892237Y116868D01*
X-1891854Y116351D01*
X-1891241Y116041D01*
X-1890704Y115938D01*
G01X-1904356Y126191D02*
X-1899913D01*
X-1898982Y126498D01*
X-1898363Y127111D01*
X-1898156Y127878D01*
X-1898363Y128645D01*
X-1898982Y129258D01*
X-1899913Y129565D01*
X-1904356D01*
G01X-1898156Y134078D02*
X-1904356D01*
X-1903116Y133158D01*
G01X-1898156D02*
Y134998D01*
G01X-1899086Y138591D02*
X-1898569Y139051D01*
X-1898259Y139588D01*
X-1898156Y140278D01*
X-1898363Y140968D01*
X-1898776Y141505D01*
X-1899499Y141888D01*
X-1900326Y141965D01*
X-1901153Y141811D01*
X-1901669Y141428D01*
X-1902083Y140891D01*
X-1902186Y140355D01*
X-1902083Y139818D01*
X-1901669Y139128D01*
X-1904356Y139358D01*
Y141428D01*
G01X-1892004Y156205D02*
X-1898204D01*
Y158121D01*
X-1897894Y158735D01*
X-1897481Y159118D01*
X-1896654Y159271D01*
X-1895827Y159118D01*
X-1895311Y158658D01*
X-1895001Y158121D01*
Y156205D01*
G01Y158121D02*
X-1892004Y159271D01*
G01X-1893244Y162251D02*
X-1892521Y162711D01*
X-1892107Y163325D01*
X-1892004Y164015D01*
X-1892107Y164628D01*
X-1892624Y165241D01*
X-1893244Y165625D01*
X-1893864Y165701D01*
X-1894587Y165548D01*
X-1895104Y165011D01*
X-1895311Y164475D01*
Y163785D01*
G01Y164475D02*
X-1895621Y164935D01*
X-1896137Y165318D01*
X-1896757Y165471D01*
X-1897377Y165318D01*
X-1897894Y164935D01*
X-1898204Y164245D01*
X-1898101Y163555D01*
X-1897687Y162865D01*
G01X-1894587Y168681D02*
X-1895311Y169218D01*
X-1895724Y169678D01*
X-1895931Y170291D01*
X-1895724Y170828D01*
X-1895311Y171211D01*
X-1894691Y171518D01*
X-1893967Y171595D01*
X-1893347Y171518D01*
X-1892727Y171211D01*
X-1892211Y170751D01*
X-1892004Y170215D01*
X-1892211Y169601D01*
X-1892830Y169065D01*
X-1893761Y168758D01*
X-1894794Y168681D01*
X-1896137Y168835D01*
X-1896861Y169065D01*
X-1897584Y169448D01*
X-1898101Y169985D01*
X-1898204Y170521D01*
X-1897997Y171058D01*
X-1897481Y171441D01*
G01X-1892004Y176338D02*
X-1898204D01*
X-1896964Y175418D01*
G01X-1892004D02*
Y177258D01*
G01X-1896537Y203938D02*
Y210138D01*
X-1894621D01*
X-1894007Y209828D01*
X-1893624Y209415D01*
X-1893471Y208588D01*
X-1893624Y207761D01*
X-1894084Y207245D01*
X-1894621Y206935D01*
X-1896537D01*
G01X-1894621D02*
X-1893471Y203938D01*
G01X-1890491Y205178D02*
X-1890031Y204455D01*
X-1889417Y204041D01*
X-1888727Y203938D01*
X-1888114Y204041D01*
X-1887501Y204558D01*
X-1887117Y205178D01*
X-1887041Y205798D01*
X-1887194Y206521D01*
X-1887731Y207038D01*
X-1888267Y207245D01*
X-1888957D01*
G01X-1888267D02*
X-1887807Y207555D01*
X-1887424Y208071D01*
X-1887271Y208691D01*
X-1887424Y209311D01*
X-1887807Y209828D01*
X-1888497Y210138D01*
X-1889187Y210035D01*
X-1889877Y209621D01*
G01X-1881684Y203938D02*
Y210138D01*
X-1884521Y205695D01*
X-1880687D01*
G01X-1877861Y206521D02*
X-1877324Y207245D01*
X-1876864Y207658D01*
X-1876251Y207865D01*
X-1875714Y207658D01*
X-1875331Y207245D01*
X-1875024Y206625D01*
X-1874947Y205901D01*
X-1875024Y205281D01*
X-1875331Y204661D01*
X-1875791Y204145D01*
X-1876327Y203938D01*
X-1876941Y204145D01*
X-1877477Y204764D01*
X-1877784Y205695D01*
X-1877861Y206728D01*
X-1877707Y208071D01*
X-1877477Y208795D01*
X-1877094Y209518D01*
X-1876557Y210035D01*
X-1876021Y210138D01*
X-1875484Y209931D01*
X-1875101Y209415D01*
G01X-1891638Y235220D02*
Y229020D01*
G01X-1893401Y235220D02*
X-1889875D01*
G01X-1886971Y229020D02*
Y235220D01*
X-1885131D01*
X-1884518Y234910D01*
X-1884058Y234187D01*
X-1883905Y233360D01*
X-1884058Y232533D01*
X-1884441Y231913D01*
X-1885131Y231603D01*
X-1886971D01*
G01X-1880695Y234187D02*
X-1880235Y234807D01*
X-1879698Y235117D01*
X-1879085Y235220D01*
X-1878318Y235013D01*
X-1877781Y234497D01*
X-1877628Y233877D01*
X-1877705Y233257D01*
X-1878011Y232740D01*
X-1879545Y231707D01*
X-1880235Y230983D01*
X-1880695Y229950D01*
X-1880848Y229020D01*
X-1877628D01*
G01X-1872118D02*
Y235220D01*
X-1874955Y230777D01*
X-1871121D01*
G01X-1899537Y304970D02*
Y311170D01*
X-1897621D01*
X-1897007Y310860D01*
X-1896624Y310447D01*
X-1896471Y309620D01*
X-1896624Y308793D01*
X-1897084Y308277D01*
X-1897621Y307967D01*
X-1899537D01*
G01X-1897621D02*
X-1896471Y304970D01*
G01X-1890884D02*
Y311170D01*
X-1893721Y306727D01*
X-1889887D01*
G01X-1884684Y304970D02*
Y311170D01*
X-1887521Y306727D01*
X-1883687D01*
G01X-1881091Y305900D02*
X-1880631Y305383D01*
X-1880094Y305073D01*
X-1879404Y304970D01*
X-1878714Y305177D01*
X-1878177Y305590D01*
X-1877794Y306313D01*
X-1877717Y307140D01*
X-1877871Y307967D01*
X-1878254Y308483D01*
X-1878791Y308897D01*
X-1879327Y309000D01*
X-1879864Y308897D01*
X-1880554Y308483D01*
X-1880324Y311170D01*
X-1878254D01*
G01X-1903291Y320325D02*
X-1903601Y320632D01*
X-1904117Y320862D01*
X-1904841Y321015D01*
X-1905461Y320862D01*
X-1905874Y320555D01*
X-1906184Y320019D01*
Y317949D01*
X-1899984D01*
Y320479D01*
X-1900397Y321015D01*
X-1901017Y321322D01*
X-1901741Y321475D01*
X-1902464Y321322D01*
X-1903084Y320862D01*
X-1903291Y320325D01*
Y317949D01*
G01X-1899984Y325912D02*
X-1906184D01*
X-1904944Y324992D01*
G01X-1899984D02*
Y326832D01*
G01X-1899730Y336475D02*
X-1905930Y338392D01*
X-1899730Y340309D01*
G01X-1901900Y339619D02*
Y337165D01*
G01X-1899730Y344592D02*
X-1905930D01*
X-1904690Y343672D01*
G01X-1899730D02*
Y345512D01*
G01X-1904897Y349335D02*
X-1905517Y349795D01*
X-1905827Y350332D01*
X-1905930Y350945D01*
X-1905723Y351712D01*
X-1905207Y352249D01*
X-1904587Y352402D01*
X-1903967Y352325D01*
X-1903450Y352019D01*
X-1902417Y350485D01*
X-1901693Y349795D01*
X-1900660Y349335D01*
X-1899730Y349182D01*
Y352402D01*
G01X-1889636Y353205D02*
X-1895836D01*
Y355121D01*
X-1895526Y355735D01*
X-1895113Y356118D01*
X-1894286Y356271D01*
X-1893459Y356118D01*
X-1892943Y355658D01*
X-1892633Y355121D01*
Y353205D01*
G01Y355121D02*
X-1889636Y356271D01*
G01Y361858D02*
X-1895836D01*
X-1891393Y359021D01*
Y362855D01*
G01X-1889636Y368058D02*
X-1895836D01*
X-1891393Y365221D01*
Y369055D01*
G01X-1894803Y371881D02*
X-1895423Y372341D01*
X-1895733Y372878D01*
X-1895836Y373491D01*
X-1895629Y374258D01*
X-1895113Y374795D01*
X-1894493Y374948D01*
X-1893873Y374871D01*
X-1893356Y374565D01*
X-1892323Y373031D01*
X-1891599Y372341D01*
X-1890566Y371881D01*
X-1889636Y371728D01*
Y374948D01*
G01X-1899770Y416143D02*
X-1893570D01*
Y419209D01*
G01X-1898737Y422419D02*
X-1899357Y422879D01*
X-1899667Y423416D01*
X-1899770Y424029D01*
X-1899563Y424796D01*
X-1899047Y425333D01*
X-1898427Y425486D01*
X-1897807Y425409D01*
X-1897290Y425103D01*
X-1896257Y423569D01*
X-1895533Y422879D01*
X-1894500Y422419D01*
X-1893570Y422266D01*
Y425486D01*
G01X-1899770Y430076D02*
X-1899563Y429463D01*
X-1899047Y429003D01*
X-1898427Y428696D01*
X-1897600Y428466D01*
X-1896670Y428389D01*
X-1895740Y428466D01*
X-1894913Y428696D01*
X-1894293Y429003D01*
X-1893777Y429463D01*
X-1893570Y430076D01*
X-1893777Y430689D01*
X-1894293Y431149D01*
X-1894913Y431456D01*
X-1895740Y431686D01*
X-1896670Y431763D01*
X-1897600Y431686D01*
X-1898427Y431456D01*
X-1899047Y431149D01*
X-1899563Y430689D01*
X-1899770Y430076D01*
G01X-1886804Y-188262D02*
X-1880604D01*
G01X-1886804Y-190025D02*
Y-186499D01*
G01X-1880604Y-183595D02*
X-1886804D01*
Y-181755D01*
X-1886494Y-181142D01*
X-1885771Y-180682D01*
X-1884944Y-180529D01*
X-1884117Y-180682D01*
X-1883497Y-181065D01*
X-1883187Y-181755D01*
Y-183595D01*
G01X-1881844Y-177549D02*
X-1881121Y-177089D01*
X-1880707Y-176475D01*
X-1880604Y-175785D01*
X-1880707Y-175172D01*
X-1881224Y-174559D01*
X-1881844Y-174175D01*
X-1882464Y-174099D01*
X-1883187Y-174252D01*
X-1883704Y-174789D01*
X-1883911Y-175325D01*
Y-176015D01*
G01Y-175325D02*
X-1884221Y-174865D01*
X-1884737Y-174482D01*
X-1885357Y-174329D01*
X-1885977Y-174482D01*
X-1886494Y-174865D01*
X-1886804Y-175555D01*
X-1886701Y-176245D01*
X-1886287Y-176935D01*
G01X-1881534Y-171349D02*
X-1881017Y-170889D01*
X-1880707Y-170352D01*
X-1880604Y-169662D01*
X-1880811Y-168972D01*
X-1881224Y-168435D01*
X-1881947Y-168052D01*
X-1882774Y-167975D01*
X-1883601Y-168129D01*
X-1884117Y-168512D01*
X-1884531Y-169049D01*
X-1884634Y-169585D01*
X-1884531Y-170122D01*
X-1884117Y-170812D01*
X-1886804Y-170582D01*
Y-168512D01*
G01X-1888287Y-134475D02*
X-1888597Y-134935D01*
X-1888804Y-135472D01*
Y-136085D01*
X-1888494Y-136775D01*
X-1887977Y-137312D01*
X-1887357Y-137695D01*
X-1886324Y-138002D01*
X-1885394Y-138079D01*
X-1884464Y-137925D01*
X-1883844Y-137695D01*
X-1883224Y-137235D01*
X-1882811Y-136699D01*
X-1882604Y-136162D01*
Y-135625D01*
X-1882811Y-135089D01*
X-1883121Y-134629D01*
X-1883534Y-134245D01*
G01X-1882604Y-129962D02*
X-1882707Y-129425D01*
X-1883017Y-128812D01*
X-1883534Y-128429D01*
X-1884257Y-128275D01*
X-1884981Y-128429D01*
X-1885601Y-128889D01*
X-1885911Y-129579D01*
Y-130345D01*
X-1886117Y-130805D01*
X-1886634Y-131189D01*
X-1887357Y-131342D01*
X-1888081Y-131112D01*
X-1888597Y-130575D01*
X-1888804Y-129962D01*
X-1888597Y-129349D01*
X-1888081Y-128812D01*
X-1887357Y-128582D01*
X-1886634Y-128735D01*
X-1886117Y-129119D01*
X-1885911Y-129579D01*
Y-130345D01*
X-1885601Y-131035D01*
X-1884981Y-131495D01*
X-1884257Y-131649D01*
X-1883534Y-131495D01*
X-1883017Y-131112D01*
X-1882707Y-130499D01*
X-1882604Y-129962D01*
G01X-1883844Y-125449D02*
X-1883121Y-124989D01*
X-1882707Y-124375D01*
X-1882604Y-123685D01*
X-1882707Y-123072D01*
X-1883224Y-122459D01*
X-1883844Y-122075D01*
X-1884464Y-121999D01*
X-1885187Y-122152D01*
X-1885704Y-122689D01*
X-1885911Y-123225D01*
Y-123915D01*
G01Y-123225D02*
X-1886221Y-122765D01*
X-1886737Y-122382D01*
X-1887357Y-122229D01*
X-1887977Y-122382D01*
X-1888494Y-122765D01*
X-1888804Y-123455D01*
X-1888701Y-124145D01*
X-1888287Y-124835D01*
G01X-1870428Y-74624D02*
Y-68424D01*
X-1873265Y-72867D01*
X-1869431D01*
G01X-1885287Y94525D02*
X-1885597Y94065D01*
X-1885804Y93528D01*
Y92915D01*
X-1885494Y92225D01*
X-1884977Y91688D01*
X-1884357Y91305D01*
X-1883324Y90998D01*
X-1882394Y90921D01*
X-1881464Y91075D01*
X-1880844Y91305D01*
X-1880224Y91765D01*
X-1879811Y92301D01*
X-1879604Y92838D01*
Y93375D01*
X-1879811Y93911D01*
X-1880121Y94371D01*
X-1880534Y94755D01*
G01X-1879604Y99038D02*
X-1879707Y99575D01*
X-1880017Y100188D01*
X-1880534Y100571D01*
X-1881257Y100725D01*
X-1881981Y100571D01*
X-1882601Y100111D01*
X-1882911Y99421D01*
Y98655D01*
X-1883117Y98195D01*
X-1883634Y97811D01*
X-1884357Y97658D01*
X-1885081Y97888D01*
X-1885597Y98425D01*
X-1885804Y99038D01*
X-1885597Y99651D01*
X-1885081Y100188D01*
X-1884357Y100418D01*
X-1883634Y100265D01*
X-1883117Y99881D01*
X-1882911Y99421D01*
Y98655D01*
X-1882601Y97965D01*
X-1881981Y97505D01*
X-1881257Y97351D01*
X-1880534Y97505D01*
X-1880017Y97888D01*
X-1879707Y98501D01*
X-1879604Y99038D01*
G01X-1880534Y103551D02*
X-1880017Y104011D01*
X-1879707Y104548D01*
X-1879604Y105238D01*
X-1879811Y105928D01*
X-1880224Y106465D01*
X-1880947Y106848D01*
X-1881774Y106925D01*
X-1882601Y106771D01*
X-1883117Y106388D01*
X-1883531Y105851D01*
X-1883634Y105315D01*
X-1883531Y104778D01*
X-1883117Y104088D01*
X-1885804Y104318D01*
Y106388D01*
G01X-1885004Y162138D02*
Y155938D01*
G01X-1886767Y162138D02*
X-1883241D01*
G01X-1880337Y155938D02*
Y162138D01*
X-1878497D01*
X-1877884Y161828D01*
X-1877424Y161105D01*
X-1877271Y160278D01*
X-1877424Y159451D01*
X-1877807Y158831D01*
X-1878497Y158521D01*
X-1880337D01*
G01X-1874291Y157178D02*
X-1873831Y156455D01*
X-1873217Y156041D01*
X-1872527Y155938D01*
X-1871914Y156041D01*
X-1871301Y156558D01*
X-1870917Y157178D01*
X-1870841Y157798D01*
X-1870994Y158521D01*
X-1871531Y159038D01*
X-1872067Y159245D01*
X-1872757D01*
G01X-1872067D02*
X-1871607Y159555D01*
X-1871224Y160071D01*
X-1871071Y160691D01*
X-1871224Y161311D01*
X-1871607Y161828D01*
X-1872297Y162138D01*
X-1872987Y162035D01*
X-1873677Y161621D01*
G01X-1867861Y161105D02*
X-1867401Y161725D01*
X-1866864Y162035D01*
X-1866251Y162138D01*
X-1865484Y161931D01*
X-1864947Y161415D01*
X-1864794Y160795D01*
X-1864871Y160175D01*
X-1865177Y159658D01*
X-1866711Y158625D01*
X-1867401Y157901D01*
X-1867861Y156868D01*
X-1868014Y155938D01*
X-1864794D01*
G01X-1885741Y178738D02*
Y184938D01*
X-1883825D01*
X-1883211Y184628D01*
X-1882828Y184215D01*
X-1882675Y183388D01*
X-1882828Y182561D01*
X-1883288Y182045D01*
X-1883825Y181735D01*
X-1885741D01*
G01X-1883825D02*
X-1882675Y178738D01*
G01X-1878161D02*
X-1878008Y180081D01*
X-1877778Y181218D01*
X-1877471Y182251D01*
X-1877088Y183388D01*
X-1876475Y184938D01*
X-1879541D01*
G01X-1873265Y183905D02*
X-1872805Y184525D01*
X-1872268Y184835D01*
X-1871655Y184938D01*
X-1870888Y184731D01*
X-1870351Y184215D01*
X-1870198Y183595D01*
X-1870275Y182975D01*
X-1870581Y182458D01*
X-1872115Y181425D01*
X-1872805Y180701D01*
X-1873265Y179668D01*
X-1873418Y178738D01*
X-1870198D01*
G01X-1888841Y169770D02*
Y175970D01*
X-1886925D01*
X-1886311Y175660D01*
X-1885928Y175247D01*
X-1885775Y174420D01*
X-1885928Y173593D01*
X-1886388Y173077D01*
X-1886925Y172767D01*
X-1888841D01*
G01X-1886925D02*
X-1885775Y169770D01*
G01X-1882795Y171010D02*
X-1882335Y170287D01*
X-1881721Y169873D01*
X-1881031Y169770D01*
X-1880418Y169873D01*
X-1879805Y170390D01*
X-1879421Y171010D01*
X-1879345Y171630D01*
X-1879498Y172353D01*
X-1880035Y172870D01*
X-1880571Y173077D01*
X-1881261D01*
G01X-1880571D02*
X-1880111Y173387D01*
X-1879728Y173903D01*
X-1879575Y174523D01*
X-1879728Y175143D01*
X-1880111Y175660D01*
X-1880801Y175970D01*
X-1881491Y175867D01*
X-1882181Y175453D01*
G01X-1873988Y169770D02*
Y175970D01*
X-1876825Y171527D01*
X-1872991D01*
G01X-1868861Y169770D02*
X-1868708Y171113D01*
X-1868478Y172250D01*
X-1868171Y173283D01*
X-1867788Y174420D01*
X-1867175Y175970D01*
X-1870241D01*
G01X-1885741Y187738D02*
Y193938D01*
X-1883825D01*
X-1883211Y193628D01*
X-1882828Y193215D01*
X-1882675Y192388D01*
X-1882828Y191561D01*
X-1883288Y191045D01*
X-1883825Y190735D01*
X-1885741D01*
G01X-1883825D02*
X-1882675Y187738D01*
G01X-1878161D02*
X-1878008Y189081D01*
X-1877778Y190218D01*
X-1877471Y191251D01*
X-1877088Y192388D01*
X-1876475Y193938D01*
X-1879541D01*
G01X-1871808D02*
X-1872421Y193731D01*
X-1872881Y193215D01*
X-1873188Y192595D01*
X-1873418Y191768D01*
X-1873495Y190838D01*
X-1873418Y189908D01*
X-1873188Y189081D01*
X-1872881Y188461D01*
X-1872421Y187945D01*
X-1871808Y187738D01*
X-1871195Y187945D01*
X-1870735Y188461D01*
X-1870428Y189081D01*
X-1870198Y189908D01*
X-1870121Y190838D01*
X-1870198Y191768D01*
X-1870428Y192595D01*
X-1870735Y193215D01*
X-1871195Y193731D01*
X-1871808Y193938D01*
G01X-1876537Y286970D02*
Y293170D01*
X-1874621D01*
X-1874007Y292860D01*
X-1873624Y292447D01*
X-1873471Y291620D01*
X-1873624Y290793D01*
X-1874084Y290277D01*
X-1874621Y289967D01*
X-1876537D01*
G01X-1874621D02*
X-1873471Y286970D01*
G01X-1867884D02*
Y293170D01*
X-1870721Y288727D01*
X-1866887D01*
G01X-1862757Y286970D02*
X-1862604Y288313D01*
X-1862374Y289450D01*
X-1862067Y290483D01*
X-1861684Y291620D01*
X-1861071Y293170D01*
X-1864137D01*
G01X-1857861Y292137D02*
X-1857401Y292757D01*
X-1856864Y293067D01*
X-1856251Y293170D01*
X-1855484Y292963D01*
X-1854947Y292447D01*
X-1854794Y291827D01*
X-1854871Y291207D01*
X-1855177Y290690D01*
X-1856711Y289657D01*
X-1857401Y288933D01*
X-1857861Y287900D01*
X-1858014Y286970D01*
X-1854794D01*
G01X-1876537Y295970D02*
Y302170D01*
X-1874621D01*
X-1874007Y301860D01*
X-1873624Y301447D01*
X-1873471Y300620D01*
X-1873624Y299793D01*
X-1874084Y299277D01*
X-1874621Y298967D01*
X-1876537D01*
G01X-1874621D02*
X-1873471Y295970D01*
G01X-1867884D02*
Y302170D01*
X-1870721Y297727D01*
X-1866887D01*
G01X-1862757Y295970D02*
X-1862604Y297313D01*
X-1862374Y298450D01*
X-1862067Y299483D01*
X-1861684Y300620D01*
X-1861071Y302170D01*
X-1864137D01*
G01X-1856404Y295970D02*
Y302170D01*
X-1857324Y300930D01*
G01Y295970D02*
X-1855484D01*
G01X-1876561Y359085D02*
X-1876024Y359809D01*
X-1875564Y360222D01*
X-1874951Y360429D01*
X-1874414Y360222D01*
X-1874031Y359809D01*
X-1873724Y359189D01*
X-1873647Y358465D01*
X-1873724Y357845D01*
X-1874031Y357225D01*
X-1874491Y356709D01*
X-1875027Y356502D01*
X-1875641Y356709D01*
X-1876177Y357328D01*
X-1876484Y358259D01*
X-1876561Y359292D01*
X-1876407Y360635D01*
X-1876177Y361359D01*
X-1875794Y362082D01*
X-1875257Y362599D01*
X-1874721Y362702D01*
X-1874184Y362495D01*
X-1873801Y361979D01*
G01X-1872304Y374138D02*
Y380338D01*
X-1873224Y379098D01*
G01Y374138D02*
X-1871384D01*
G01X-1867838Y-223780D02*
Y-229980D01*
G01X-1869601Y-223780D02*
X-1866075D01*
G01X-1863171Y-229980D02*
Y-223780D01*
X-1861331D01*
X-1860718Y-224090D01*
X-1860258Y-224813D01*
X-1860105Y-225640D01*
X-1860258Y-226467D01*
X-1860641Y-227087D01*
X-1861331Y-227397D01*
X-1863171D01*
G01X-1856895Y-224813D02*
X-1856435Y-224193D01*
X-1855898Y-223883D01*
X-1855285Y-223780D01*
X-1854518Y-223987D01*
X-1853981Y-224503D01*
X-1853828Y-225123D01*
X-1853905Y-225743D01*
X-1854211Y-226260D01*
X-1855745Y-227293D01*
X-1856435Y-228017D01*
X-1856895Y-229050D01*
X-1857048Y-229980D01*
X-1853828D01*
G01X-1849238Y-223780D02*
X-1849851Y-223987D01*
X-1850311Y-224503D01*
X-1850618Y-225123D01*
X-1850848Y-225950D01*
X-1850925Y-226880D01*
X-1850848Y-227810D01*
X-1850618Y-228637D01*
X-1850311Y-229257D01*
X-1849851Y-229773D01*
X-1849238Y-229980D01*
X-1848625Y-229773D01*
X-1848165Y-229257D01*
X-1847858Y-228637D01*
X-1847628Y-227810D01*
X-1847551Y-226880D01*
X-1847628Y-225950D01*
X-1847858Y-225123D01*
X-1848165Y-224503D01*
X-1848625Y-223987D01*
X-1849238Y-223780D01*
G01X-1864036Y-222749D02*
X-1863519Y-222289D01*
X-1863209Y-221752D01*
X-1863106Y-221062D01*
X-1863313Y-220372D01*
X-1863726Y-219835D01*
X-1864449Y-219452D01*
X-1865276Y-219375D01*
X-1866103Y-219529D01*
X-1866619Y-219912D01*
X-1867033Y-220449D01*
X-1867136Y-220985D01*
X-1867033Y-221522D01*
X-1866619Y-222212D01*
X-1869306Y-221982D01*
Y-219912D01*
G01X-1857768Y-193249D02*
X-1853325D01*
X-1852394Y-192942D01*
X-1851775Y-192329D01*
X-1851568Y-191562D01*
X-1851775Y-190795D01*
X-1852394Y-190182D01*
X-1853325Y-189875D01*
X-1857768D01*
G01X-1851568Y-185362D02*
X-1857768D01*
X-1856528Y-186282D01*
G01X-1851568D02*
Y-184442D01*
G01X-1852291Y-180465D02*
X-1851775Y-179929D01*
X-1851568Y-179315D01*
X-1851775Y-178702D01*
X-1852394Y-178165D01*
X-1853325Y-177782D01*
X-1854255Y-177629D01*
X-1855391D01*
X-1856321Y-177782D01*
X-1857148Y-178165D01*
X-1857561Y-178625D01*
X-1857768Y-179162D01*
X-1857561Y-179775D01*
X-1857148Y-180235D01*
X-1856528Y-180542D01*
X-1855701Y-180695D01*
X-1854978Y-180542D01*
X-1854255Y-180159D01*
X-1853841Y-179699D01*
X-1853738Y-179162D01*
X-1853945Y-178549D01*
X-1854461Y-178089D01*
X-1855391Y-177629D01*
G01X-1862506Y-145342D02*
X-1868706D01*
X-1864263Y-148179D01*
Y-144345D01*
G01X-1861537Y-131998D02*
Y-125798D01*
X-1859621D01*
X-1859007Y-126108D01*
X-1858624Y-126521D01*
X-1858471Y-127348D01*
X-1858624Y-128175D01*
X-1859084Y-128691D01*
X-1859621Y-129001D01*
X-1861537D01*
G01X-1859621D02*
X-1858471Y-131998D01*
G01X-1855261Y-126831D02*
X-1854801Y-126211D01*
X-1854264Y-125901D01*
X-1853651Y-125798D01*
X-1852884Y-126005D01*
X-1852347Y-126521D01*
X-1852194Y-127141D01*
X-1852271Y-127761D01*
X-1852577Y-128278D01*
X-1854111Y-129311D01*
X-1854801Y-130035D01*
X-1855261Y-131068D01*
X-1855414Y-131998D01*
X-1852194D01*
G01X-1847757D02*
X-1847604Y-130655D01*
X-1847374Y-129518D01*
X-1847067Y-128485D01*
X-1846684Y-127348D01*
X-1846071Y-125798D01*
X-1849137D01*
G01X-1843091Y-130758D02*
X-1842631Y-131481D01*
X-1842017Y-131895D01*
X-1841327Y-131998D01*
X-1840714Y-131895D01*
X-1840101Y-131378D01*
X-1839717Y-130758D01*
X-1839641Y-130138D01*
X-1839794Y-129415D01*
X-1840331Y-128898D01*
X-1840867Y-128691D01*
X-1841557D01*
G01X-1840867D02*
X-1840407Y-128381D01*
X-1840024Y-127865D01*
X-1839871Y-127245D01*
X-1840024Y-126625D01*
X-1840407Y-126108D01*
X-1841097Y-125798D01*
X-1841787Y-125901D01*
X-1842477Y-126315D01*
G01X-1861537Y-141998D02*
Y-135798D01*
X-1859621D01*
X-1859007Y-136108D01*
X-1858624Y-136521D01*
X-1858471Y-137348D01*
X-1858624Y-138175D01*
X-1859084Y-138691D01*
X-1859621Y-139001D01*
X-1861537D01*
G01X-1859621D02*
X-1858471Y-141998D01*
G01X-1855491Y-140758D02*
X-1855031Y-141481D01*
X-1854417Y-141895D01*
X-1853727Y-141998D01*
X-1853114Y-141895D01*
X-1852501Y-141378D01*
X-1852117Y-140758D01*
X-1852041Y-140138D01*
X-1852194Y-139415D01*
X-1852731Y-138898D01*
X-1853267Y-138691D01*
X-1853957D01*
G01X-1853267D02*
X-1852807Y-138381D01*
X-1852424Y-137865D01*
X-1852271Y-137245D01*
X-1852424Y-136625D01*
X-1852807Y-136108D01*
X-1853497Y-135798D01*
X-1854187Y-135901D01*
X-1854877Y-136315D01*
G01X-1847604Y-141998D02*
X-1847067Y-141895D01*
X-1846454Y-141585D01*
X-1846071Y-141068D01*
X-1845917Y-140345D01*
X-1846071Y-139621D01*
X-1846531Y-139001D01*
X-1847221Y-138691D01*
X-1847987D01*
X-1848447Y-138485D01*
X-1848831Y-137968D01*
X-1848984Y-137245D01*
X-1848754Y-136521D01*
X-1848217Y-136005D01*
X-1847604Y-135798D01*
X-1846991Y-136005D01*
X-1846454Y-136521D01*
X-1846224Y-137245D01*
X-1846377Y-137968D01*
X-1846761Y-138485D01*
X-1847221Y-138691D01*
X-1847987D01*
X-1848677Y-139001D01*
X-1849137Y-139621D01*
X-1849291Y-140345D01*
X-1849137Y-141068D01*
X-1848754Y-141585D01*
X-1848141Y-141895D01*
X-1847604Y-141998D01*
G01X-1841404D02*
X-1840867Y-141895D01*
X-1840254Y-141585D01*
X-1839871Y-141068D01*
X-1839717Y-140345D01*
X-1839871Y-139621D01*
X-1840331Y-139001D01*
X-1841021Y-138691D01*
X-1841787D01*
X-1842247Y-138485D01*
X-1842631Y-137968D01*
X-1842784Y-137245D01*
X-1842554Y-136521D01*
X-1842017Y-136005D01*
X-1841404Y-135798D01*
X-1840791Y-136005D01*
X-1840254Y-136521D01*
X-1840024Y-137245D01*
X-1840177Y-137968D01*
X-1840561Y-138485D01*
X-1841021Y-138691D01*
X-1841787D01*
X-1842477Y-139001D01*
X-1842937Y-139621D01*
X-1843091Y-140345D01*
X-1842937Y-141068D01*
X-1842554Y-141585D01*
X-1841941Y-141895D01*
X-1841404Y-141998D01*
G01X-1861537Y-121998D02*
Y-115798D01*
X-1859621D01*
X-1859007Y-116108D01*
X-1858624Y-116521D01*
X-1858471Y-117348D01*
X-1858624Y-118175D01*
X-1859084Y-118691D01*
X-1859621Y-119001D01*
X-1861537D01*
G01X-1859621D02*
X-1858471Y-121998D01*
G01X-1855491Y-120758D02*
X-1855031Y-121481D01*
X-1854417Y-121895D01*
X-1853727Y-121998D01*
X-1853114Y-121895D01*
X-1852501Y-121378D01*
X-1852117Y-120758D01*
X-1852041Y-120138D01*
X-1852194Y-119415D01*
X-1852731Y-118898D01*
X-1853267Y-118691D01*
X-1853957D01*
G01X-1853267D02*
X-1852807Y-118381D01*
X-1852424Y-117865D01*
X-1852271Y-117245D01*
X-1852424Y-116625D01*
X-1852807Y-116108D01*
X-1853497Y-115798D01*
X-1854187Y-115901D01*
X-1854877Y-116315D01*
G01X-1847757Y-121998D02*
X-1847604Y-120655D01*
X-1847374Y-119518D01*
X-1847067Y-118485D01*
X-1846684Y-117348D01*
X-1846071Y-115798D01*
X-1849137D01*
G01X-1843091Y-120758D02*
X-1842631Y-121481D01*
X-1842017Y-121895D01*
X-1841327Y-121998D01*
X-1840714Y-121895D01*
X-1840101Y-121378D01*
X-1839717Y-120758D01*
X-1839641Y-120138D01*
X-1839794Y-119415D01*
X-1840331Y-118898D01*
X-1840867Y-118691D01*
X-1841557D01*
G01X-1840867D02*
X-1840407Y-118381D01*
X-1840024Y-117865D01*
X-1839871Y-117245D01*
X-1840024Y-116625D01*
X-1840407Y-116108D01*
X-1841097Y-115798D01*
X-1841787Y-115901D01*
X-1842477Y-116315D01*
G01X-1861537Y-111998D02*
Y-105798D01*
X-1859621D01*
X-1859007Y-106108D01*
X-1858624Y-106521D01*
X-1858471Y-107348D01*
X-1858624Y-108175D01*
X-1859084Y-108691D01*
X-1859621Y-109001D01*
X-1861537D01*
G01X-1859621D02*
X-1858471Y-111998D01*
G01X-1855491Y-110758D02*
X-1855031Y-111481D01*
X-1854417Y-111895D01*
X-1853727Y-111998D01*
X-1853114Y-111895D01*
X-1852501Y-111378D01*
X-1852117Y-110758D01*
X-1852041Y-110138D01*
X-1852194Y-109415D01*
X-1852731Y-108898D01*
X-1853267Y-108691D01*
X-1853957D01*
G01X-1853267D02*
X-1852807Y-108381D01*
X-1852424Y-107865D01*
X-1852271Y-107245D01*
X-1852424Y-106625D01*
X-1852807Y-106108D01*
X-1853497Y-105798D01*
X-1854187Y-105901D01*
X-1854877Y-106315D01*
G01X-1848907Y-111275D02*
X-1848371Y-111791D01*
X-1847757Y-111998D01*
X-1847144Y-111791D01*
X-1846607Y-111172D01*
X-1846224Y-110241D01*
X-1846071Y-109311D01*
Y-108175D01*
X-1846224Y-107245D01*
X-1846607Y-106418D01*
X-1847067Y-106005D01*
X-1847604Y-105798D01*
X-1848217Y-106005D01*
X-1848677Y-106418D01*
X-1848984Y-107038D01*
X-1849137Y-107865D01*
X-1848984Y-108588D01*
X-1848601Y-109311D01*
X-1848141Y-109725D01*
X-1847604Y-109828D01*
X-1846991Y-109621D01*
X-1846531Y-109105D01*
X-1846071Y-108175D01*
G01X-1841404Y-105798D02*
X-1842017Y-106005D01*
X-1842477Y-106521D01*
X-1842784Y-107141D01*
X-1843014Y-107968D01*
X-1843091Y-108898D01*
X-1843014Y-109828D01*
X-1842784Y-110655D01*
X-1842477Y-111275D01*
X-1842017Y-111791D01*
X-1841404Y-111998D01*
X-1840791Y-111791D01*
X-1840331Y-111275D01*
X-1840024Y-110655D01*
X-1839794Y-109828D01*
X-1839717Y-108898D01*
X-1839794Y-107968D01*
X-1840024Y-107141D01*
X-1840331Y-106521D01*
X-1840791Y-106005D01*
X-1841404Y-105798D01*
G01X-1861537Y-101998D02*
Y-95798D01*
X-1859621D01*
X-1859007Y-96108D01*
X-1858624Y-96521D01*
X-1858471Y-97348D01*
X-1858624Y-98175D01*
X-1859084Y-98691D01*
X-1859621Y-99001D01*
X-1861537D01*
G01X-1859621D02*
X-1858471Y-101998D01*
G01X-1855261Y-96831D02*
X-1854801Y-96211D01*
X-1854264Y-95901D01*
X-1853651Y-95798D01*
X-1852884Y-96005D01*
X-1852347Y-96521D01*
X-1852194Y-97141D01*
X-1852271Y-97761D01*
X-1852577Y-98278D01*
X-1854111Y-99311D01*
X-1854801Y-100035D01*
X-1855261Y-101068D01*
X-1855414Y-101998D01*
X-1852194D01*
G01X-1847757D02*
X-1847604Y-100655D01*
X-1847374Y-99518D01*
X-1847067Y-98485D01*
X-1846684Y-97348D01*
X-1846071Y-95798D01*
X-1849137D01*
G01X-1840484Y-101998D02*
Y-95798D01*
X-1843321Y-100241D01*
X-1839487D01*
G01X-1861537Y-91998D02*
Y-85798D01*
X-1859621D01*
X-1859007Y-86108D01*
X-1858624Y-86521D01*
X-1858471Y-87348D01*
X-1858624Y-88175D01*
X-1859084Y-88691D01*
X-1859621Y-89001D01*
X-1861537D01*
G01X-1859621D02*
X-1858471Y-91998D01*
G01X-1855491Y-90758D02*
X-1855031Y-91481D01*
X-1854417Y-91895D01*
X-1853727Y-91998D01*
X-1853114Y-91895D01*
X-1852501Y-91378D01*
X-1852117Y-90758D01*
X-1852041Y-90138D01*
X-1852194Y-89415D01*
X-1852731Y-88898D01*
X-1853267Y-88691D01*
X-1853957D01*
G01X-1853267D02*
X-1852807Y-88381D01*
X-1852424Y-87865D01*
X-1852271Y-87245D01*
X-1852424Y-86625D01*
X-1852807Y-86108D01*
X-1853497Y-85798D01*
X-1854187Y-85901D01*
X-1854877Y-86315D01*
G01X-1847604Y-91998D02*
X-1847067Y-91895D01*
X-1846454Y-91585D01*
X-1846071Y-91068D01*
X-1845917Y-90345D01*
X-1846071Y-89621D01*
X-1846531Y-89001D01*
X-1847221Y-88691D01*
X-1847987D01*
X-1848447Y-88485D01*
X-1848831Y-87968D01*
X-1848984Y-87245D01*
X-1848754Y-86521D01*
X-1848217Y-86005D01*
X-1847604Y-85798D01*
X-1846991Y-86005D01*
X-1846454Y-86521D01*
X-1846224Y-87245D01*
X-1846377Y-87968D01*
X-1846761Y-88485D01*
X-1847221Y-88691D01*
X-1847987D01*
X-1848677Y-89001D01*
X-1849137Y-89621D01*
X-1849291Y-90345D01*
X-1849137Y-91068D01*
X-1848754Y-91585D01*
X-1848141Y-91895D01*
X-1847604Y-91998D01*
G01X-1842707Y-91275D02*
X-1842171Y-91791D01*
X-1841557Y-91998D01*
X-1840944Y-91791D01*
X-1840407Y-91172D01*
X-1840024Y-90241D01*
X-1839871Y-89311D01*
Y-88175D01*
X-1840024Y-87245D01*
X-1840407Y-86418D01*
X-1840867Y-86005D01*
X-1841404Y-85798D01*
X-1842017Y-86005D01*
X-1842477Y-86418D01*
X-1842784Y-87038D01*
X-1842937Y-87865D01*
X-1842784Y-88588D01*
X-1842401Y-89311D01*
X-1841941Y-89725D01*
X-1841404Y-89828D01*
X-1840791Y-89621D01*
X-1840331Y-89105D01*
X-1839871Y-88175D01*
G01X-1864337Y-47822D02*
X-1863954Y-48442D01*
X-1863494Y-48855D01*
X-1862957Y-49062D01*
X-1862344Y-48855D01*
X-1861884Y-48442D01*
X-1861424Y-47822D01*
X-1861271Y-46995D01*
Y-42862D01*
G01X-1857907Y-48339D02*
X-1857371Y-48855D01*
X-1856757Y-49062D01*
X-1856144Y-48855D01*
X-1855607Y-48236D01*
X-1855224Y-47305D01*
X-1855071Y-46375D01*
Y-45239D01*
X-1855224Y-44309D01*
X-1855607Y-43482D01*
X-1856067Y-43069D01*
X-1856604Y-42862D01*
X-1857217Y-43069D01*
X-1857677Y-43482D01*
X-1857984Y-44102D01*
X-1858137Y-44929D01*
X-1857984Y-45652D01*
X-1857601Y-46375D01*
X-1857141Y-46789D01*
X-1856604Y-46892D01*
X-1855991Y-46685D01*
X-1855531Y-46169D01*
X-1855071Y-45239D01*
G01X-1870231Y-18576D02*
X-1869771Y-19299D01*
X-1869157Y-19713D01*
X-1868467Y-19816D01*
X-1867854Y-19713D01*
X-1867241Y-19196D01*
X-1866857Y-18576D01*
X-1866781Y-17956D01*
X-1866934Y-17233D01*
X-1867471Y-16716D01*
X-1868007Y-16509D01*
X-1868697D01*
G01X-1868007D02*
X-1867547Y-16199D01*
X-1867164Y-15683D01*
X-1867011Y-15063D01*
X-1867164Y-14443D01*
X-1867547Y-13926D01*
X-1868237Y-13616D01*
X-1868927Y-13719D01*
X-1869617Y-14133D01*
G01X-1868243Y7002D02*
Y13202D01*
X-1866327D01*
X-1865713Y12892D01*
X-1865330Y12479D01*
X-1865177Y11652D01*
X-1865330Y10825D01*
X-1865790Y10309D01*
X-1866327Y9999D01*
X-1868243D01*
G01X-1866327D02*
X-1865177Y7002D01*
G01X-1859590D02*
Y13202D01*
X-1862427Y8759D01*
X-1858593D01*
G01X-1854310Y13202D02*
X-1854923Y12995D01*
X-1855383Y12479D01*
X-1855690Y11859D01*
X-1855920Y11032D01*
X-1855997Y10102D01*
X-1855920Y9172D01*
X-1855690Y8345D01*
X-1855383Y7725D01*
X-1854923Y7209D01*
X-1854310Y7002D01*
X-1853697Y7209D01*
X-1853237Y7725D01*
X-1852930Y8345D01*
X-1852700Y9172D01*
X-1852623Y10102D01*
X-1852700Y11032D01*
X-1852930Y11859D01*
X-1853237Y12479D01*
X-1853697Y12995D01*
X-1854310Y13202D01*
G01X-1848110D02*
X-1848723Y12995D01*
X-1849183Y12479D01*
X-1849490Y11859D01*
X-1849720Y11032D01*
X-1849797Y10102D01*
X-1849720Y9172D01*
X-1849490Y8345D01*
X-1849183Y7725D01*
X-1848723Y7209D01*
X-1848110Y7002D01*
X-1847497Y7209D01*
X-1847037Y7725D01*
X-1846730Y8345D01*
X-1846500Y9172D01*
X-1846423Y10102D01*
X-1846500Y11032D01*
X-1846730Y11859D01*
X-1847037Y12479D01*
X-1847497Y12995D01*
X-1848110Y13202D01*
G01X-1868243Y-1998D02*
Y4202D01*
X-1866327D01*
X-1865713Y3892D01*
X-1865330Y3479D01*
X-1865177Y2652D01*
X-1865330Y1825D01*
X-1865790Y1309D01*
X-1866327Y999D01*
X-1868243D01*
G01X-1866327D02*
X-1865177Y-1998D01*
G01X-1862197Y-758D02*
X-1861737Y-1481D01*
X-1861123Y-1895D01*
X-1860433Y-1998D01*
X-1859820Y-1895D01*
X-1859207Y-1378D01*
X-1858823Y-758D01*
X-1858747Y-138D01*
X-1858900Y585D01*
X-1859437Y1102D01*
X-1859973Y1309D01*
X-1860663D01*
G01X-1859973D02*
X-1859513Y1619D01*
X-1859130Y2135D01*
X-1858977Y2755D01*
X-1859130Y3375D01*
X-1859513Y3892D01*
X-1860203Y4202D01*
X-1860893Y4099D01*
X-1861583Y3685D01*
G01X-1855613Y-1275D02*
X-1855077Y-1791D01*
X-1854463Y-1998D01*
X-1853850Y-1791D01*
X-1853313Y-1172D01*
X-1852930Y-241D01*
X-1852777Y689D01*
Y1825D01*
X-1852930Y2755D01*
X-1853313Y3582D01*
X-1853773Y3995D01*
X-1854310Y4202D01*
X-1854923Y3995D01*
X-1855383Y3582D01*
X-1855690Y2962D01*
X-1855843Y2135D01*
X-1855690Y1412D01*
X-1855307Y689D01*
X-1854847Y275D01*
X-1854310Y172D01*
X-1853697Y379D01*
X-1853237Y895D01*
X-1852777Y1825D01*
G01X-1847190Y-1998D02*
Y4202D01*
X-1850027Y-241D01*
X-1846193D01*
G01X-1868243Y25002D02*
Y31202D01*
X-1866327D01*
X-1865713Y30892D01*
X-1865330Y30479D01*
X-1865177Y29652D01*
X-1865330Y28825D01*
X-1865790Y28309D01*
X-1866327Y27999D01*
X-1868243D01*
G01X-1866327D02*
X-1865177Y25002D01*
G01X-1862197Y26242D02*
X-1861737Y25519D01*
X-1861123Y25105D01*
X-1860433Y25002D01*
X-1859820Y25105D01*
X-1859207Y25622D01*
X-1858823Y26242D01*
X-1858747Y26862D01*
X-1858900Y27585D01*
X-1859437Y28102D01*
X-1859973Y28309D01*
X-1860663D01*
G01X-1859973D02*
X-1859513Y28619D01*
X-1859130Y29135D01*
X-1858977Y29755D01*
X-1859130Y30375D01*
X-1859513Y30892D01*
X-1860203Y31202D01*
X-1860893Y31099D01*
X-1861583Y30685D01*
G01X-1855613Y25725D02*
X-1855077Y25209D01*
X-1854463Y25002D01*
X-1853850Y25209D01*
X-1853313Y25828D01*
X-1852930Y26759D01*
X-1852777Y27689D01*
Y28825D01*
X-1852930Y29755D01*
X-1853313Y30582D01*
X-1853773Y30995D01*
X-1854310Y31202D01*
X-1854923Y30995D01*
X-1855383Y30582D01*
X-1855690Y29962D01*
X-1855843Y29135D01*
X-1855690Y28412D01*
X-1855307Y27689D01*
X-1854847Y27275D01*
X-1854310Y27172D01*
X-1853697Y27379D01*
X-1853237Y27895D01*
X-1852777Y28825D01*
G01X-1849567Y27585D02*
X-1849030Y28309D01*
X-1848570Y28722D01*
X-1847957Y28929D01*
X-1847420Y28722D01*
X-1847037Y28309D01*
X-1846730Y27689D01*
X-1846653Y26965D01*
X-1846730Y26345D01*
X-1847037Y25725D01*
X-1847497Y25209D01*
X-1848033Y25002D01*
X-1848647Y25209D01*
X-1849183Y25828D01*
X-1849490Y26759D01*
X-1849567Y27792D01*
X-1849413Y29135D01*
X-1849183Y29859D01*
X-1848800Y30582D01*
X-1848263Y31099D01*
X-1847727Y31202D01*
X-1847190Y30995D01*
X-1846807Y30479D01*
G01X-1868243Y16002D02*
Y22202D01*
X-1866327D01*
X-1865713Y21892D01*
X-1865330Y21479D01*
X-1865177Y20652D01*
X-1865330Y19825D01*
X-1865790Y19309D01*
X-1866327Y18999D01*
X-1868243D01*
G01X-1866327D02*
X-1865177Y16002D01*
G01X-1859590D02*
Y22202D01*
X-1862427Y17759D01*
X-1858593D01*
G01X-1855767Y21169D02*
X-1855307Y21789D01*
X-1854770Y22099D01*
X-1854157Y22202D01*
X-1853390Y21995D01*
X-1852853Y21479D01*
X-1852700Y20859D01*
X-1852777Y20239D01*
X-1853083Y19722D01*
X-1854617Y18689D01*
X-1855307Y17965D01*
X-1855767Y16932D01*
X-1855920Y16002D01*
X-1852700D01*
G01X-1847190D02*
Y22202D01*
X-1850027Y17759D01*
X-1846193D01*
G01X-1868243Y34002D02*
Y40202D01*
X-1866327D01*
X-1865713Y39892D01*
X-1865330Y39479D01*
X-1865177Y38652D01*
X-1865330Y37825D01*
X-1865790Y37309D01*
X-1866327Y36999D01*
X-1868243D01*
G01X-1866327D02*
X-1865177Y34002D01*
G01X-1862197Y35242D02*
X-1861737Y34519D01*
X-1861123Y34105D01*
X-1860433Y34002D01*
X-1859820Y34105D01*
X-1859207Y34622D01*
X-1858823Y35242D01*
X-1858747Y35862D01*
X-1858900Y36585D01*
X-1859437Y37102D01*
X-1859973Y37309D01*
X-1860663D01*
G01X-1859973D02*
X-1859513Y37619D01*
X-1859130Y38135D01*
X-1858977Y38755D01*
X-1859130Y39375D01*
X-1859513Y39892D01*
X-1860203Y40202D01*
X-1860893Y40099D01*
X-1861583Y39685D01*
G01X-1855613Y34725D02*
X-1855077Y34209D01*
X-1854463Y34002D01*
X-1853850Y34209D01*
X-1853313Y34828D01*
X-1852930Y35759D01*
X-1852777Y36689D01*
Y37825D01*
X-1852930Y38755D01*
X-1853313Y39582D01*
X-1853773Y39995D01*
X-1854310Y40202D01*
X-1854923Y39995D01*
X-1855383Y39582D01*
X-1855690Y38962D01*
X-1855843Y38135D01*
X-1855690Y37412D01*
X-1855307Y36689D01*
X-1854847Y36275D01*
X-1854310Y36172D01*
X-1853697Y36379D01*
X-1853237Y36895D01*
X-1852777Y37825D01*
G01X-1849797Y34932D02*
X-1849337Y34415D01*
X-1848800Y34105D01*
X-1848110Y34002D01*
X-1847420Y34209D01*
X-1846883Y34622D01*
X-1846500Y35345D01*
X-1846423Y36172D01*
X-1846577Y36999D01*
X-1846960Y37515D01*
X-1847497Y37929D01*
X-1848033Y38032D01*
X-1848570Y37929D01*
X-1849260Y37515D01*
X-1849030Y40202D01*
X-1846960D01*
G01X-1868243Y43002D02*
Y49202D01*
X-1866327D01*
X-1865713Y48892D01*
X-1865330Y48479D01*
X-1865177Y47652D01*
X-1865330Y46825D01*
X-1865790Y46309D01*
X-1866327Y45999D01*
X-1868243D01*
G01X-1866327D02*
X-1865177Y43002D01*
G01X-1859590D02*
Y49202D01*
X-1862427Y44759D01*
X-1858593D01*
G01X-1854310Y49202D02*
X-1854923Y48995D01*
X-1855383Y48479D01*
X-1855690Y47859D01*
X-1855920Y47032D01*
X-1855997Y46102D01*
X-1855920Y45172D01*
X-1855690Y44345D01*
X-1855383Y43725D01*
X-1854923Y43209D01*
X-1854310Y43002D01*
X-1853697Y43209D01*
X-1853237Y43725D01*
X-1852930Y44345D01*
X-1852700Y45172D01*
X-1852623Y46102D01*
X-1852700Y47032D01*
X-1852930Y47859D01*
X-1853237Y48479D01*
X-1853697Y48995D01*
X-1854310Y49202D01*
G01X-1848110Y43002D02*
Y49202D01*
X-1849030Y47962D01*
G01Y43002D02*
X-1847190D01*
G01X-1857437Y65178D02*
X-1857054Y64558D01*
X-1856594Y64145D01*
X-1856057Y63938D01*
X-1855444Y64145D01*
X-1854984Y64558D01*
X-1854524Y65178D01*
X-1854371Y66005D01*
Y70138D01*
G01X-1849704Y63938D02*
Y70138D01*
X-1850624Y68898D01*
G01Y63938D02*
X-1848784D01*
G01X-1843504D02*
X-1842967Y64041D01*
X-1842354Y64351D01*
X-1841971Y64868D01*
X-1841817Y65591D01*
X-1841971Y66315D01*
X-1842431Y66935D01*
X-1843121Y67245D01*
X-1843887D01*
X-1844347Y67451D01*
X-1844731Y67968D01*
X-1844884Y68691D01*
X-1844654Y69415D01*
X-1844117Y69931D01*
X-1843504Y70138D01*
X-1842891Y69931D01*
X-1842354Y69415D01*
X-1842124Y68691D01*
X-1842277Y67968D01*
X-1842661Y67451D01*
X-1843121Y67245D01*
X-1843887D01*
X-1844577Y66935D01*
X-1845037Y66315D01*
X-1845191Y65591D01*
X-1845037Y64868D01*
X-1844654Y64351D01*
X-1844041Y64041D01*
X-1843504Y63938D01*
G01X-1869391Y73278D02*
X-1868931Y72555D01*
X-1868317Y72141D01*
X-1867627Y72038D01*
X-1867014Y72141D01*
X-1866401Y72658D01*
X-1866017Y73278D01*
X-1865941Y73898D01*
X-1866094Y74621D01*
X-1866631Y75138D01*
X-1867167Y75345D01*
X-1867857D01*
G01X-1867167D02*
X-1866707Y75655D01*
X-1866324Y76171D01*
X-1866171Y76791D01*
X-1866324Y77411D01*
X-1866707Y77928D01*
X-1867397Y78238D01*
X-1868087Y78135D01*
X-1868777Y77721D01*
G01X-1870487Y96025D02*
X-1870797Y95565D01*
X-1871004Y95028D01*
Y94415D01*
X-1870694Y93725D01*
X-1870177Y93188D01*
X-1869557Y92805D01*
X-1868524Y92498D01*
X-1867594Y92421D01*
X-1866664Y92575D01*
X-1866044Y92805D01*
X-1865424Y93265D01*
X-1865011Y93801D01*
X-1864804Y94338D01*
Y94875D01*
X-1865011Y95411D01*
X-1865321Y95871D01*
X-1865734Y96255D01*
G01X-1866044Y98851D02*
X-1865321Y99311D01*
X-1864907Y99925D01*
X-1864804Y100615D01*
X-1864907Y101228D01*
X-1865424Y101841D01*
X-1866044Y102225D01*
X-1866664Y102301D01*
X-1867387Y102148D01*
X-1867904Y101611D01*
X-1868111Y101075D01*
Y100385D01*
G01Y101075D02*
X-1868421Y101535D01*
X-1868937Y101918D01*
X-1869557Y102071D01*
X-1870177Y101918D01*
X-1870694Y101535D01*
X-1871004Y100845D01*
X-1870901Y100155D01*
X-1870487Y99465D01*
G01X-1864804Y106738D02*
X-1871004D01*
X-1869764Y105818D01*
G01X-1864804D02*
Y107658D01*
G01X-1866044Y111251D02*
X-1865321Y111711D01*
X-1864907Y112325D01*
X-1864804Y113015D01*
X-1864907Y113628D01*
X-1865424Y114241D01*
X-1866044Y114625D01*
X-1866664Y114701D01*
X-1867387Y114548D01*
X-1867904Y114011D01*
X-1868111Y113475D01*
Y112785D01*
G01Y113475D02*
X-1868421Y113935D01*
X-1868937Y114318D01*
X-1869557Y114471D01*
X-1870177Y114318D01*
X-1870694Y113935D01*
X-1871004Y113245D01*
X-1870901Y112555D01*
X-1870487Y111865D01*
G01X-1870287Y126025D02*
X-1870597Y125565D01*
X-1870804Y125028D01*
Y124415D01*
X-1870494Y123725D01*
X-1869977Y123188D01*
X-1869357Y122805D01*
X-1868324Y122498D01*
X-1867394Y122421D01*
X-1866464Y122575D01*
X-1865844Y122805D01*
X-1865224Y123265D01*
X-1864811Y123801D01*
X-1864604Y124338D01*
Y124875D01*
X-1864811Y125411D01*
X-1865121Y125871D01*
X-1865534Y126255D01*
G01X-1865844Y128851D02*
X-1865121Y129311D01*
X-1864707Y129925D01*
X-1864604Y130615D01*
X-1864707Y131228D01*
X-1865224Y131841D01*
X-1865844Y132225D01*
X-1866464Y132301D01*
X-1867187Y132148D01*
X-1867704Y131611D01*
X-1867911Y131075D01*
Y130385D01*
G01Y131075D02*
X-1868221Y131535D01*
X-1868737Y131918D01*
X-1869357Y132071D01*
X-1869977Y131918D01*
X-1870494Y131535D01*
X-1870804Y130845D01*
X-1870701Y130155D01*
X-1870287Y129465D01*
G01X-1864604Y136738D02*
X-1870804D01*
X-1869564Y135818D01*
G01X-1864604D02*
Y137658D01*
G01X-1869771Y141481D02*
X-1870391Y141941D01*
X-1870701Y142478D01*
X-1870804Y143091D01*
X-1870597Y143858D01*
X-1870081Y144395D01*
X-1869461Y144548D01*
X-1868841Y144471D01*
X-1868324Y144165D01*
X-1867291Y142631D01*
X-1866567Y141941D01*
X-1865534Y141481D01*
X-1864604Y141328D01*
Y144548D01*
G01X-1858704Y131938D02*
X-1858167Y132041D01*
X-1857554Y132351D01*
X-1857171Y132868D01*
X-1857017Y133591D01*
X-1857171Y134315D01*
X-1857631Y134935D01*
X-1858321Y135245D01*
X-1859087D01*
X-1859547Y135451D01*
X-1859931Y135968D01*
X-1860084Y136691D01*
X-1859854Y137415D01*
X-1859317Y137931D01*
X-1858704Y138138D01*
X-1858091Y137931D01*
X-1857554Y137415D01*
X-1857324Y136691D01*
X-1857477Y135968D01*
X-1857861Y135451D01*
X-1858321Y135245D01*
X-1859087D01*
X-1859777Y134935D01*
X-1860237Y134315D01*
X-1860391Y133591D01*
X-1860237Y132868D01*
X-1859854Y132351D01*
X-1859241Y132041D01*
X-1858704Y131938D01*
G01X-1853604Y144205D02*
X-1859804D01*
Y146121D01*
X-1859494Y146735D01*
X-1859081Y147118D01*
X-1858254Y147271D01*
X-1857427Y147118D01*
X-1856911Y146658D01*
X-1856601Y146121D01*
Y144205D01*
G01Y146121D02*
X-1853604Y147271D01*
G01X-1854844Y150251D02*
X-1854121Y150711D01*
X-1853707Y151325D01*
X-1853604Y152015D01*
X-1853707Y152628D01*
X-1854224Y153241D01*
X-1854844Y153625D01*
X-1855464Y153701D01*
X-1856187Y153548D01*
X-1856704Y153011D01*
X-1856911Y152475D01*
Y151785D01*
G01Y152475D02*
X-1857221Y152935D01*
X-1857737Y153318D01*
X-1858357Y153471D01*
X-1858977Y153318D01*
X-1859494Y152935D01*
X-1859804Y152245D01*
X-1859701Y151555D01*
X-1859287Y150865D01*
G01X-1854534Y156451D02*
X-1854017Y156911D01*
X-1853707Y157448D01*
X-1853604Y158138D01*
X-1853811Y158828D01*
X-1854224Y159365D01*
X-1854947Y159748D01*
X-1855774Y159825D01*
X-1856601Y159671D01*
X-1857117Y159288D01*
X-1857531Y158751D01*
X-1857634Y158215D01*
X-1857531Y157678D01*
X-1857117Y156988D01*
X-1859804Y157218D01*
Y159288D01*
G01Y164338D02*
X-1859597Y163725D01*
X-1859081Y163265D01*
X-1858461Y162958D01*
X-1857634Y162728D01*
X-1856704Y162651D01*
X-1855774Y162728D01*
X-1854947Y162958D01*
X-1854327Y163265D01*
X-1853811Y163725D01*
X-1853604Y164338D01*
X-1853811Y164951D01*
X-1854327Y165411D01*
X-1854947Y165718D01*
X-1855774Y165948D01*
X-1856704Y166025D01*
X-1857634Y165948D01*
X-1858461Y165718D01*
X-1859081Y165411D01*
X-1859597Y164951D01*
X-1859804Y164338D01*
G01X-1865161Y167621D02*
X-1864624Y168345D01*
X-1864164Y168758D01*
X-1863551Y168965D01*
X-1863014Y168758D01*
X-1862631Y168345D01*
X-1862324Y167725D01*
X-1862247Y167001D01*
X-1862324Y166381D01*
X-1862631Y165761D01*
X-1863091Y165245D01*
X-1863627Y165038D01*
X-1864241Y165245D01*
X-1864777Y165864D01*
X-1865084Y166795D01*
X-1865161Y167828D01*
X-1865007Y169171D01*
X-1864777Y169895D01*
X-1864394Y170618D01*
X-1863857Y171135D01*
X-1863321Y171238D01*
X-1862784Y171031D01*
X-1862401Y170515D01*
G01X-1860695Y184338D02*
Y179895D01*
X-1860388Y178964D01*
X-1859775Y178345D01*
X-1859008Y178138D01*
X-1858241Y178345D01*
X-1857628Y178964D01*
X-1857321Y179895D01*
Y184338D01*
G01X-1854265Y183305D02*
X-1853805Y183925D01*
X-1853268Y184235D01*
X-1852655Y184338D01*
X-1851888Y184131D01*
X-1851351Y183615D01*
X-1851198Y182995D01*
X-1851275Y182375D01*
X-1851581Y181858D01*
X-1853115Y180825D01*
X-1853805Y180101D01*
X-1854265Y179068D01*
X-1854418Y178138D01*
X-1851198D01*
G01X-1846608D02*
X-1846071Y178241D01*
X-1845458Y178551D01*
X-1845075Y179068D01*
X-1844921Y179791D01*
X-1845075Y180515D01*
X-1845535Y181135D01*
X-1846225Y181445D01*
X-1846991D01*
X-1847451Y181651D01*
X-1847835Y182168D01*
X-1847988Y182891D01*
X-1847758Y183615D01*
X-1847221Y184131D01*
X-1846608Y184338D01*
X-1845995Y184131D01*
X-1845458Y183615D01*
X-1845228Y182891D01*
X-1845381Y182168D01*
X-1845765Y181651D01*
X-1846225Y181445D01*
X-1846991D01*
X-1847681Y181135D01*
X-1848141Y180515D01*
X-1848295Y179791D01*
X-1848141Y179068D01*
X-1847758Y178551D01*
X-1847145Y178241D01*
X-1846608Y178138D01*
G01X-1865391Y174968D02*
X-1864931Y174451D01*
X-1864394Y174141D01*
X-1863704Y174038D01*
X-1863014Y174245D01*
X-1862477Y174658D01*
X-1862094Y175381D01*
X-1862017Y176208D01*
X-1862171Y177035D01*
X-1862554Y177551D01*
X-1863091Y177965D01*
X-1863627Y178068D01*
X-1864164Y177965D01*
X-1864854Y177551D01*
X-1864624Y180238D01*
X-1862554D01*
G01X-1867391Y188278D02*
X-1866931Y187555D01*
X-1866317Y187141D01*
X-1865627Y187038D01*
X-1865014Y187141D01*
X-1864401Y187658D01*
X-1864017Y188278D01*
X-1863941Y188898D01*
X-1864094Y189621D01*
X-1864631Y190138D01*
X-1865167Y190345D01*
X-1865857D01*
G01X-1865167D02*
X-1864707Y190655D01*
X-1864324Y191171D01*
X-1864171Y191791D01*
X-1864324Y192411D01*
X-1864707Y192928D01*
X-1865397Y193238D01*
X-1866087Y193135D01*
X-1866777Y192721D01*
G01X-1859161Y197205D02*
X-1858701Y197825D01*
X-1858164Y198135D01*
X-1857551Y198238D01*
X-1856784Y198031D01*
X-1856247Y197515D01*
X-1856094Y196895D01*
X-1856171Y196275D01*
X-1856477Y195758D01*
X-1858011Y194725D01*
X-1858701Y194001D01*
X-1859161Y192968D01*
X-1859314Y192038D01*
X-1856094D01*
G01X-1871437Y203938D02*
Y210138D01*
X-1869521D01*
X-1868907Y209828D01*
X-1868524Y209415D01*
X-1868371Y208588D01*
X-1868524Y207761D01*
X-1868984Y207245D01*
X-1869521Y206935D01*
X-1871437D01*
G01X-1869521D02*
X-1868371Y203938D01*
G01X-1863857D02*
X-1863704Y205281D01*
X-1863474Y206418D01*
X-1863167Y207451D01*
X-1862784Y208588D01*
X-1862171Y210138D01*
X-1865237D01*
G01X-1859191Y205178D02*
X-1858731Y204455D01*
X-1858117Y204041D01*
X-1857427Y203938D01*
X-1856814Y204041D01*
X-1856201Y204558D01*
X-1855817Y205178D01*
X-1855741Y205798D01*
X-1855894Y206521D01*
X-1856431Y207038D01*
X-1856967Y207245D01*
X-1857657D01*
G01X-1856967D02*
X-1856507Y207555D01*
X-1856124Y208071D01*
X-1855971Y208691D01*
X-1856124Y209311D01*
X-1856507Y209828D01*
X-1857197Y210138D01*
X-1857887Y210035D01*
X-1858577Y209621D01*
G01X-1859289Y318360D02*
X-1858829Y317637D01*
X-1858215Y317223D01*
X-1857525Y317120D01*
X-1856912Y317223D01*
X-1856299Y317740D01*
X-1855915Y318360D01*
X-1855839Y318980D01*
X-1855992Y319703D01*
X-1856529Y320220D01*
X-1857065Y320427D01*
X-1857755D01*
G01X-1857065D02*
X-1856605Y320737D01*
X-1856222Y321253D01*
X-1856069Y321873D01*
X-1856222Y322493D01*
X-1856605Y323010D01*
X-1857295Y323320D01*
X-1857985Y323217D01*
X-1858675Y322803D01*
G01X-1871868Y331151D02*
X-1867425D01*
X-1866494Y331458D01*
X-1865875Y332071D01*
X-1865668Y332838D01*
X-1865875Y333605D01*
X-1866494Y334218D01*
X-1867425Y334525D01*
X-1871868D01*
G01X-1865668Y339038D02*
X-1871868D01*
X-1870628Y338118D01*
G01X-1865668D02*
Y339958D01*
G01Y345085D02*
X-1867011Y345238D01*
X-1868148Y345468D01*
X-1869181Y345775D01*
X-1870318Y346158D01*
X-1871868Y346771D01*
Y343705D01*
G01X-1858984Y356902D02*
Y363102D01*
X-1861821Y358659D01*
X-1857987D01*
G01X-1861717Y427021D02*
X-1862177Y427331D01*
X-1862714Y427538D01*
X-1863327D01*
X-1864017Y427228D01*
X-1864554Y426711D01*
X-1864937Y426091D01*
X-1865244Y425058D01*
X-1865321Y424128D01*
X-1865167Y423198D01*
X-1864937Y422578D01*
X-1864477Y421958D01*
X-1863941Y421545D01*
X-1863404Y421338D01*
X-1862867D01*
X-1862331Y421545D01*
X-1861871Y421855D01*
X-1861487Y422268D01*
G01X-1858737Y421338D02*
Y427538D01*
X-1856821D01*
X-1856207Y427228D01*
X-1855824Y426815D01*
X-1855671Y425988D01*
X-1855824Y425161D01*
X-1856284Y424645D01*
X-1856821Y424335D01*
X-1858737D01*
G01X-1856821D02*
X-1855671Y421338D01*
G01X-1851004D02*
Y427538D01*
X-1851924Y426298D01*
G01Y421338D02*
X-1850084D01*
G01X-1846261Y426505D02*
X-1845801Y427125D01*
X-1845264Y427435D01*
X-1844651Y427538D01*
X-1843884Y427331D01*
X-1843347Y426815D01*
X-1843194Y426195D01*
X-1843271Y425575D01*
X-1843577Y425058D01*
X-1845111Y424025D01*
X-1845801Y423301D01*
X-1846261Y422268D01*
X-1846414Y421338D01*
X-1843194D01*
G01X-1857191Y482578D02*
X-1856731Y481855D01*
X-1856117Y481441D01*
X-1855427Y481338D01*
X-1854814Y481441D01*
X-1854201Y481958D01*
X-1853817Y482578D01*
X-1853741Y483198D01*
X-1853894Y483921D01*
X-1854431Y484438D01*
X-1854967Y484645D01*
X-1855657D01*
G01X-1854967D02*
X-1854507Y484955D01*
X-1854124Y485471D01*
X-1853971Y486091D01*
X-1854124Y486711D01*
X-1854507Y487228D01*
X-1855197Y487538D01*
X-1855887Y487435D01*
X-1856577Y487021D01*
G01X-1846506Y-221062D02*
X-1846609Y-220525D01*
X-1846919Y-219912D01*
X-1847436Y-219529D01*
X-1848159Y-219375D01*
X-1848883Y-219529D01*
X-1849503Y-219989D01*
X-1849813Y-220679D01*
Y-221445D01*
X-1850019Y-221905D01*
X-1850536Y-222289D01*
X-1851259Y-222442D01*
X-1851983Y-222212D01*
X-1852499Y-221675D01*
X-1852706Y-221062D01*
X-1852499Y-220449D01*
X-1851983Y-219912D01*
X-1851259Y-219682D01*
X-1850536Y-219835D01*
X-1850019Y-220219D01*
X-1849813Y-220679D01*
Y-221445D01*
X-1849503Y-222135D01*
X-1848883Y-222595D01*
X-1848159Y-222749D01*
X-1847436Y-222595D01*
X-1846919Y-222212D01*
X-1846609Y-221599D01*
X-1846506Y-221062D01*
G01X-1850945Y-69195D02*
X-1850485Y-68575D01*
X-1849948Y-68265D01*
X-1849335Y-68162D01*
X-1848568Y-68369D01*
X-1848031Y-68885D01*
X-1847878Y-69505D01*
X-1847955Y-70125D01*
X-1848261Y-70642D01*
X-1849795Y-71675D01*
X-1850485Y-72399D01*
X-1850945Y-73432D01*
X-1851098Y-74362D01*
X-1847878D01*
G01X-1847744Y-19816D02*
Y-13616D01*
X-1848664Y-14856D01*
G01Y-19816D02*
X-1846824D01*
G01X-1843161Y87105D02*
X-1842701Y87725D01*
X-1842164Y88035D01*
X-1841551Y88138D01*
X-1840784Y87931D01*
X-1840247Y87415D01*
X-1840094Y86795D01*
X-1840171Y86175D01*
X-1840477Y85658D01*
X-1842011Y84625D01*
X-1842701Y83901D01*
X-1843161Y82868D01*
X-1843314Y81938D01*
X-1840094D01*
G01X-1849604Y108551D02*
X-1845161D01*
X-1844230Y108858D01*
X-1843611Y109471D01*
X-1843404Y110238D01*
X-1843611Y111005D01*
X-1844230Y111618D01*
X-1845161Y111925D01*
X-1849604D01*
G01X-1844644Y114751D02*
X-1843921Y115211D01*
X-1843507Y115825D01*
X-1843404Y116515D01*
X-1843507Y117128D01*
X-1844024Y117741D01*
X-1844644Y118125D01*
X-1845264Y118201D01*
X-1845987Y118048D01*
X-1846504Y117511D01*
X-1846711Y116975D01*
Y116285D01*
G01Y116975D02*
X-1847021Y117435D01*
X-1847537Y117818D01*
X-1848157Y117971D01*
X-1848777Y117818D01*
X-1849294Y117435D01*
X-1849604Y116745D01*
X-1849501Y116055D01*
X-1849087Y115365D01*
G01X-1848571Y121181D02*
X-1849191Y121641D01*
X-1849501Y122178D01*
X-1849604Y122791D01*
X-1849397Y123558D01*
X-1848881Y124095D01*
X-1848261Y124248D01*
X-1847641Y124171D01*
X-1847124Y123865D01*
X-1846091Y122331D01*
X-1845367Y121641D01*
X-1844334Y121181D01*
X-1843404Y121028D01*
Y124248D01*
G01X-1840604Y144205D02*
X-1846804D01*
Y146121D01*
X-1846494Y146735D01*
X-1846081Y147118D01*
X-1845254Y147271D01*
X-1844427Y147118D01*
X-1843911Y146658D01*
X-1843601Y146121D01*
Y144205D01*
G01Y146121D02*
X-1840604Y147271D01*
G01X-1841844Y150251D02*
X-1841121Y150711D01*
X-1840707Y151325D01*
X-1840604Y152015D01*
X-1840707Y152628D01*
X-1841224Y153241D01*
X-1841844Y153625D01*
X-1842464Y153701D01*
X-1843187Y153548D01*
X-1843704Y153011D01*
X-1843911Y152475D01*
Y151785D01*
G01Y152475D02*
X-1844221Y152935D01*
X-1844737Y153318D01*
X-1845357Y153471D01*
X-1845977Y153318D01*
X-1846494Y152935D01*
X-1846804Y152245D01*
X-1846701Y151555D01*
X-1846287Y150865D01*
G01X-1841534Y156451D02*
X-1841017Y156911D01*
X-1840707Y157448D01*
X-1840604Y158138D01*
X-1840811Y158828D01*
X-1841224Y159365D01*
X-1841947Y159748D01*
X-1842774Y159825D01*
X-1843601Y159671D01*
X-1844117Y159288D01*
X-1844531Y158751D01*
X-1844634Y158215D01*
X-1844531Y157678D01*
X-1844117Y156988D01*
X-1846804Y157218D01*
Y159288D01*
G01X-1840604Y164338D02*
X-1846804D01*
X-1845564Y163418D01*
G01X-1840604D02*
Y165258D01*
G01X-1848857Y165038D02*
X-1848704Y166381D01*
X-1848474Y167518D01*
X-1848167Y168551D01*
X-1847784Y169688D01*
X-1847171Y171238D01*
X-1850237D01*
G01X-1839704Y173038D02*
X-1839167Y173141D01*
X-1838554Y173451D01*
X-1838171Y173968D01*
X-1838017Y174691D01*
X-1838171Y175415D01*
X-1838631Y176035D01*
X-1839321Y176345D01*
X-1840087D01*
X-1840547Y176551D01*
X-1840931Y177068D01*
X-1841084Y177791D01*
X-1840854Y178515D01*
X-1840317Y179031D01*
X-1839704Y179238D01*
X-1839091Y179031D01*
X-1838554Y178515D01*
X-1838324Y177791D01*
X-1838477Y177068D01*
X-1838861Y176551D01*
X-1839321Y176345D01*
X-1840087D01*
X-1840777Y176035D01*
X-1841237Y175415D01*
X-1841391Y174691D01*
X-1841237Y173968D01*
X-1840854Y173451D01*
X-1840241Y173141D01*
X-1839704Y173038D01*
G01X-1841804Y190038D02*
Y196238D01*
X-1842724Y194998D01*
G01Y190038D02*
X-1840884D01*
G01X-1835604Y196238D02*
X-1836217Y196031D01*
X-1836677Y195515D01*
X-1836984Y194895D01*
X-1837214Y194068D01*
X-1837291Y193138D01*
X-1837214Y192208D01*
X-1836984Y191381D01*
X-1836677Y190761D01*
X-1836217Y190245D01*
X-1835604Y190038D01*
X-1834991Y190245D01*
X-1834531Y190761D01*
X-1834224Y191381D01*
X-1833994Y192208D01*
X-1833917Y193138D01*
X-1833994Y194068D01*
X-1834224Y194895D01*
X-1834531Y195515D01*
X-1834991Y196031D01*
X-1835604Y196238D01*
G01X-1845604Y203305D02*
X-1851804D01*
Y205221D01*
X-1851494Y205835D01*
X-1851081Y206218D01*
X-1850254Y206371D01*
X-1849427Y206218D01*
X-1848911Y205758D01*
X-1848601Y205221D01*
Y203305D01*
G01Y205221D02*
X-1845604Y206371D01*
G01Y210885D02*
X-1846947Y211038D01*
X-1848084Y211268D01*
X-1849117Y211575D01*
X-1850254Y211958D01*
X-1851804Y212571D01*
Y209505D01*
G01X-1845604Y217238D02*
X-1851804D01*
X-1850564Y216318D01*
G01X-1845604D02*
Y218158D01*
G01X-1842598Y283609D02*
X-1841875Y284069D01*
X-1841461Y284683D01*
X-1841358Y285373D01*
X-1841461Y285986D01*
X-1841978Y286599D01*
X-1842598Y286983D01*
X-1843218Y287059D01*
X-1843941Y286906D01*
X-1844458Y286369D01*
X-1844665Y285833D01*
Y285143D01*
G01Y285833D02*
X-1844975Y286293D01*
X-1845491Y286676D01*
X-1846111Y286829D01*
X-1846731Y286676D01*
X-1847248Y286293D01*
X-1847558Y285603D01*
X-1847455Y284913D01*
X-1847041Y284223D01*
G01X-1846525Y290039D02*
X-1847145Y290499D01*
X-1847455Y291036D01*
X-1847558Y291649D01*
X-1847351Y292416D01*
X-1846835Y292953D01*
X-1846215Y293106D01*
X-1845595Y293029D01*
X-1845078Y292723D01*
X-1844045Y291189D01*
X-1843321Y290499D01*
X-1842288Y290039D01*
X-1841358Y289886D01*
Y293106D01*
G01X-1841404Y347040D02*
X-1847604D01*
X-1846364Y346120D01*
G01X-1841404D02*
Y347960D01*
G01Y353087D02*
X-1842747Y353240D01*
X-1843884Y353470D01*
X-1844917Y353777D01*
X-1846054Y354160D01*
X-1847604Y354773D01*
Y351707D01*
G01X-1831591Y-221522D02*
X-1831131Y-222245D01*
X-1830517Y-222659D01*
X-1829827Y-222762D01*
X-1829214Y-222659D01*
X-1828601Y-222142D01*
X-1828217Y-221522D01*
X-1828141Y-220902D01*
X-1828294Y-220179D01*
X-1828831Y-219662D01*
X-1829367Y-219455D01*
X-1830057D01*
G01X-1829367D02*
X-1828907Y-219145D01*
X-1828524Y-218629D01*
X-1828371Y-218009D01*
X-1828524Y-217389D01*
X-1828907Y-216872D01*
X-1829597Y-216562D01*
X-1830287Y-216665D01*
X-1830977Y-217079D01*
G01X-1832704Y65038D02*
Y71238D01*
X-1833624Y69998D01*
G01Y65038D02*
X-1831784D01*
G01X-1833784Y91938D02*
Y98138D01*
X-1836621Y93695D01*
X-1832787D01*
G01X-1835391Y132868D02*
X-1834931Y132351D01*
X-1834394Y132041D01*
X-1833704Y131938D01*
X-1833014Y132145D01*
X-1832477Y132558D01*
X-1832094Y133281D01*
X-1832017Y134108D01*
X-1832171Y134935D01*
X-1832554Y135451D01*
X-1833091Y135865D01*
X-1833627Y135968D01*
X-1834164Y135865D01*
X-1834854Y135451D01*
X-1834624Y138138D01*
X-1832554D01*
G01X-1832717Y167717D02*
X-1833177Y168027D01*
X-1833714Y168234D01*
X-1834327D01*
X-1835017Y167924D01*
X-1835554Y167407D01*
X-1835937Y166787D01*
X-1836244Y165754D01*
X-1836321Y164824D01*
X-1836167Y163894D01*
X-1835937Y163274D01*
X-1835477Y162654D01*
X-1834941Y162241D01*
X-1834404Y162034D01*
X-1833867D01*
X-1833331Y162241D01*
X-1832871Y162551D01*
X-1832487Y162964D01*
G01X-1829661Y167201D02*
X-1829201Y167821D01*
X-1828664Y168131D01*
X-1828051Y168234D01*
X-1827284Y168027D01*
X-1826747Y167511D01*
X-1826594Y166891D01*
X-1826671Y166271D01*
X-1826977Y165754D01*
X-1828511Y164721D01*
X-1829201Y163997D01*
X-1829661Y162964D01*
X-1829814Y162034D01*
X-1826594D01*
G01X-1822157D02*
X-1822004Y163377D01*
X-1821774Y164514D01*
X-1821467Y165547D01*
X-1821084Y166684D01*
X-1820471Y168234D01*
X-1823537D01*
G01X-1817261Y164617D02*
X-1816724Y165341D01*
X-1816264Y165754D01*
X-1815651Y165961D01*
X-1815114Y165754D01*
X-1814731Y165341D01*
X-1814424Y164721D01*
X-1814347Y163997D01*
X-1814424Y163377D01*
X-1814731Y162757D01*
X-1815191Y162241D01*
X-1815727Y162034D01*
X-1816341Y162241D01*
X-1816877Y162860D01*
X-1817184Y163791D01*
X-1817261Y164824D01*
X-1817107Y166167D01*
X-1816877Y166891D01*
X-1816494Y167614D01*
X-1815957Y168131D01*
X-1815421Y168234D01*
X-1814884Y168027D01*
X-1814501Y167511D01*
G01X-1833341Y179570D02*
Y173370D01*
X-1830275D01*
G01X-1825608D02*
Y179570D01*
X-1826528Y178330D01*
G01Y173370D02*
X-1824688D01*
G01X-1819408D02*
X-1818871Y173473D01*
X-1818258Y173783D01*
X-1817875Y174300D01*
X-1817721Y175023D01*
X-1817875Y175747D01*
X-1818335Y176367D01*
X-1819025Y176677D01*
X-1819791D01*
X-1820251Y176883D01*
X-1820635Y177400D01*
X-1820788Y178123D01*
X-1820558Y178847D01*
X-1820021Y179363D01*
X-1819408Y179570D01*
X-1818795Y179363D01*
X-1818258Y178847D01*
X-1818028Y178123D01*
X-1818181Y177400D01*
X-1818565Y176883D01*
X-1819025Y176677D01*
X-1819791D01*
X-1820481Y176367D01*
X-1820941Y175747D01*
X-1821095Y175023D01*
X-1820941Y174300D01*
X-1820558Y173783D01*
X-1819945Y173473D01*
X-1819408Y173370D01*
G01X-1825317Y188721D02*
X-1825777Y189031D01*
X-1826314Y189238D01*
X-1826927D01*
X-1827617Y188928D01*
X-1828154Y188411D01*
X-1828537Y187791D01*
X-1828844Y186758D01*
X-1828921Y185828D01*
X-1828767Y184898D01*
X-1828537Y184278D01*
X-1828077Y183658D01*
X-1827541Y183245D01*
X-1827004Y183038D01*
X-1826467D01*
X-1825931Y183245D01*
X-1825471Y183555D01*
X-1825087Y183968D01*
G01X-1822261Y188205D02*
X-1821801Y188825D01*
X-1821264Y189135D01*
X-1820651Y189238D01*
X-1819884Y189031D01*
X-1819347Y188515D01*
X-1819194Y187895D01*
X-1819271Y187275D01*
X-1819577Y186758D01*
X-1821111Y185725D01*
X-1821801Y185001D01*
X-1822261Y183968D01*
X-1822414Y183038D01*
X-1819194D01*
G01X-1814757D02*
X-1814604Y184381D01*
X-1814374Y185518D01*
X-1814067Y186551D01*
X-1813684Y187688D01*
X-1813071Y189238D01*
X-1816137D01*
G01X-1808404Y183038D02*
X-1807867Y183141D01*
X-1807254Y183451D01*
X-1806871Y183968D01*
X-1806717Y184691D01*
X-1806871Y185415D01*
X-1807331Y186035D01*
X-1808021Y186345D01*
X-1808787D01*
X-1809247Y186551D01*
X-1809631Y187068D01*
X-1809784Y187791D01*
X-1809554Y188515D01*
X-1809017Y189031D01*
X-1808404Y189238D01*
X-1807791Y189031D01*
X-1807254Y188515D01*
X-1807024Y187791D01*
X-1807177Y187068D01*
X-1807561Y186551D01*
X-1808021Y186345D01*
X-1808787D01*
X-1809477Y186035D01*
X-1809937Y185415D01*
X-1810091Y184691D01*
X-1809937Y183968D01*
X-1809554Y183451D01*
X-1808941Y183141D01*
X-1808404Y183038D01*
G01X-1825317Y197721D02*
X-1825777Y198031D01*
X-1826314Y198238D01*
X-1826927D01*
X-1827617Y197928D01*
X-1828154Y197411D01*
X-1828537Y196791D01*
X-1828844Y195758D01*
X-1828921Y194828D01*
X-1828767Y193898D01*
X-1828537Y193278D01*
X-1828077Y192658D01*
X-1827541Y192245D01*
X-1827004Y192038D01*
X-1826467D01*
X-1825931Y192245D01*
X-1825471Y192555D01*
X-1825087Y192968D01*
G01X-1822261Y197205D02*
X-1821801Y197825D01*
X-1821264Y198135D01*
X-1820651Y198238D01*
X-1819884Y198031D01*
X-1819347Y197515D01*
X-1819194Y196895D01*
X-1819271Y196275D01*
X-1819577Y195758D01*
X-1821111Y194725D01*
X-1821801Y194001D01*
X-1822261Y192968D01*
X-1822414Y192038D01*
X-1819194D01*
G01X-1814757D02*
X-1814604Y193381D01*
X-1814374Y194518D01*
X-1814067Y195551D01*
X-1813684Y196688D01*
X-1813071Y198238D01*
X-1816137D01*
G01X-1808557Y192038D02*
X-1808404Y193381D01*
X-1808174Y194518D01*
X-1807867Y195551D01*
X-1807484Y196688D01*
X-1806871Y198238D01*
X-1809937D01*
G01X-1817604Y372938D02*
X-1823804D01*
X-1822564Y372018D01*
G01X-1817604D02*
Y373858D01*
G01X-1820187Y377681D02*
X-1820911Y378218D01*
X-1821324Y378678D01*
X-1821531Y379291D01*
X-1821324Y379828D01*
X-1820911Y380211D01*
X-1820291Y380518D01*
X-1819567Y380595D01*
X-1818947Y380518D01*
X-1818327Y380211D01*
X-1817811Y379751D01*
X-1817604Y379215D01*
X-1817811Y378601D01*
X-1818430Y378065D01*
X-1819361Y377758D01*
X-1820394Y377681D01*
X-1821737Y377835D01*
X-1822461Y378065D01*
X-1823184Y378448D01*
X-1823701Y378985D01*
X-1823804Y379521D01*
X-1823597Y380058D01*
X-1823081Y380441D01*
G01X-1837061Y379205D02*
X-1836601Y379825D01*
X-1836064Y380135D01*
X-1835451Y380238D01*
X-1834684Y380031D01*
X-1834147Y379515D01*
X-1833994Y378895D01*
X-1834071Y378275D01*
X-1834377Y377758D01*
X-1835911Y376725D01*
X-1836601Y376001D01*
X-1837061Y374968D01*
X-1837214Y374038D01*
X-1833994D01*
G01X-1823238Y435820D02*
Y429620D01*
G01X-1825001Y435820D02*
X-1821475D01*
G01X-1818571Y429620D02*
Y435820D01*
X-1816731D01*
X-1816118Y435510D01*
X-1815658Y434787D01*
X-1815505Y433960D01*
X-1815658Y433133D01*
X-1816041Y432513D01*
X-1816731Y432203D01*
X-1818571D01*
G01X-1809918Y429620D02*
Y435820D01*
X-1812755Y431377D01*
X-1808921D01*
G01X-1806095Y434787D02*
X-1805635Y435407D01*
X-1805098Y435717D01*
X-1804485Y435820D01*
X-1803718Y435613D01*
X-1803181Y435097D01*
X-1803028Y434477D01*
X-1803105Y433857D01*
X-1803411Y433340D01*
X-1804945Y432307D01*
X-1805635Y431583D01*
X-1806095Y430550D01*
X-1806248Y429620D01*
X-1803028D01*
G01X-1811231Y-210362D02*
Y-214805D01*
X-1810924Y-215736D01*
X-1810311Y-216355D01*
X-1809544Y-216562D01*
X-1808777Y-216355D01*
X-1808164Y-215736D01*
X-1807857Y-214805D01*
Y-210362D01*
G01X-1803497Y-216562D02*
X-1803344Y-215219D01*
X-1803114Y-214082D01*
X-1802807Y-213049D01*
X-1802424Y-211912D01*
X-1801811Y-210362D01*
X-1804877D01*
G01X-1803636Y230205D02*
X-1809836D01*
Y232121D01*
X-1809526Y232735D01*
X-1809113Y233118D01*
X-1808286Y233271D01*
X-1807459Y233118D01*
X-1806943Y232658D01*
X-1806633Y232121D01*
Y230205D01*
G01Y232121D02*
X-1803636Y233271D01*
G01Y238858D02*
X-1809836D01*
X-1805393Y236021D01*
Y239855D01*
G01X-1803636Y244138D02*
X-1803739Y244675D01*
X-1804049Y245288D01*
X-1804566Y245671D01*
X-1805289Y245825D01*
X-1806013Y245671D01*
X-1806633Y245211D01*
X-1806943Y244521D01*
Y243755D01*
X-1807149Y243295D01*
X-1807666Y242911D01*
X-1808389Y242758D01*
X-1809113Y242988D01*
X-1809629Y243525D01*
X-1809836Y244138D01*
X-1809629Y244751D01*
X-1809113Y245288D01*
X-1808389Y245518D01*
X-1807666Y245365D01*
X-1807149Y244981D01*
X-1806943Y244521D01*
Y243755D01*
X-1806633Y243065D01*
X-1806013Y242605D01*
X-1805289Y242451D01*
X-1804566Y242605D01*
X-1804049Y242988D01*
X-1803739Y243601D01*
X-1803636Y244138D01*
G01X-1809836Y250338D02*
X-1809629Y249725D01*
X-1809113Y249265D01*
X-1808493Y248958D01*
X-1807666Y248728D01*
X-1806736Y248651D01*
X-1805806Y248728D01*
X-1804979Y248958D01*
X-1804359Y249265D01*
X-1803843Y249725D01*
X-1803636Y250338D01*
X-1803843Y250951D01*
X-1804359Y251411D01*
X-1804979Y251718D01*
X-1805806Y251948D01*
X-1806736Y252025D01*
X-1807666Y251948D01*
X-1808493Y251718D01*
X-1809113Y251411D01*
X-1809629Y250951D01*
X-1809836Y250338D01*
G01X-1814890Y255167D02*
X-1814167Y255627D01*
X-1813753Y256241D01*
X-1813650Y256931D01*
X-1813753Y257544D01*
X-1814270Y258157D01*
X-1814890Y258541D01*
X-1815510Y258617D01*
X-1816233Y258464D01*
X-1816750Y257927D01*
X-1816957Y257391D01*
Y256701D01*
G01Y257391D02*
X-1817267Y257851D01*
X-1817783Y258234D01*
X-1818403Y258387D01*
X-1819023Y258234D01*
X-1819540Y257851D01*
X-1819850Y257161D01*
X-1819747Y256471D01*
X-1819333Y255781D01*
G01X-1814890Y261367D02*
X-1814167Y261827D01*
X-1813753Y262441D01*
X-1813650Y263131D01*
X-1813753Y263744D01*
X-1814270Y264357D01*
X-1814890Y264741D01*
X-1815510Y264817D01*
X-1816233Y264664D01*
X-1816750Y264127D01*
X-1816957Y263591D01*
Y262901D01*
G01Y263591D02*
X-1817267Y264051D01*
X-1817783Y264434D01*
X-1818403Y264587D01*
X-1819023Y264434D01*
X-1819540Y264051D01*
X-1819850Y263361D01*
X-1819747Y262671D01*
X-1819333Y261981D01*
G01X-1814804Y384738D02*
X-1808604D01*
G01X-1814804Y382975D02*
Y386501D01*
G01X-1808604Y389405D02*
X-1814804D01*
Y391245D01*
X-1814494Y391858D01*
X-1813771Y392318D01*
X-1812944Y392471D01*
X-1812117Y392318D01*
X-1811497Y391935D01*
X-1811187Y391245D01*
Y389405D01*
G01X-1808604Y397138D02*
X-1814804D01*
X-1813564Y396218D01*
G01X-1808604D02*
Y398058D01*
G01Y403338D02*
X-1814804D01*
X-1813564Y402418D01*
G01X-1808604D02*
Y404258D01*
G01X-1797640Y380205D02*
X-1803840D01*
Y382121D01*
X-1803530Y382735D01*
X-1803117Y383118D01*
X-1802290Y383271D01*
X-1801463Y383118D01*
X-1800947Y382658D01*
X-1800637Y382121D01*
Y380205D01*
G01Y382121D02*
X-1797640Y383271D01*
G01Y388858D02*
X-1803840D01*
X-1799397Y386021D01*
Y389855D01*
G01X-1798570Y392451D02*
X-1798053Y392911D01*
X-1797743Y393448D01*
X-1797640Y394138D01*
X-1797847Y394828D01*
X-1798260Y395365D01*
X-1798983Y395748D01*
X-1799810Y395825D01*
X-1800637Y395671D01*
X-1801153Y395288D01*
X-1801567Y394751D01*
X-1801670Y394215D01*
X-1801567Y393678D01*
X-1801153Y392988D01*
X-1803840Y393218D01*
Y395288D01*
G01X-1800223Y398881D02*
X-1800947Y399418D01*
X-1801360Y399878D01*
X-1801567Y400491D01*
X-1801360Y401028D01*
X-1800947Y401411D01*
X-1800327Y401718D01*
X-1799603Y401795D01*
X-1798983Y401718D01*
X-1798363Y401411D01*
X-1797847Y400951D01*
X-1797640Y400415D01*
X-1797847Y399801D01*
X-1798466Y399265D01*
X-1799397Y398958D01*
X-1800430Y398881D01*
X-1801773Y399035D01*
X-1802497Y399265D01*
X-1803220Y399648D01*
X-1803737Y400185D01*
X-1803840Y400721D01*
X-1803633Y401258D01*
X-1803117Y401641D01*
G01X-1790984Y-224162D02*
Y-217962D01*
X-1793821Y-222405D01*
X-1789987D01*
G01X-1793591Y-208032D02*
X-1793131Y-208549D01*
X-1792594Y-208859D01*
X-1791904Y-208962D01*
X-1791214Y-208755D01*
X-1790677Y-208342D01*
X-1790294Y-207619D01*
X-1790217Y-206792D01*
X-1790371Y-205965D01*
X-1790754Y-205449D01*
X-1791291Y-205035D01*
X-1791827Y-204932D01*
X-1792364Y-205035D01*
X-1793054Y-205449D01*
X-1792824Y-202762D01*
X-1790754D01*
G01X-1785697Y-203342D02*
Y-197142D01*
X-1783781D01*
X-1783167Y-197452D01*
X-1782784Y-197865D01*
X-1782631Y-198692D01*
X-1782784Y-199519D01*
X-1783244Y-200035D01*
X-1783781Y-200345D01*
X-1785697D01*
G01X-1783781D02*
X-1782631Y-203342D01*
G01X-1777964D02*
Y-197142D01*
X-1778884Y-198382D01*
G01Y-203342D02*
X-1777044D01*
G01X-1773067Y-202619D02*
X-1772531Y-203135D01*
X-1771917Y-203342D01*
X-1771304Y-203135D01*
X-1770767Y-202516D01*
X-1770384Y-201585D01*
X-1770231Y-200655D01*
Y-199519D01*
X-1770384Y-198589D01*
X-1770767Y-197762D01*
X-1771227Y-197349D01*
X-1771764Y-197142D01*
X-1772377Y-197349D01*
X-1772837Y-197762D01*
X-1773144Y-198382D01*
X-1773297Y-199209D01*
X-1773144Y-199932D01*
X-1772761Y-200655D01*
X-1772301Y-201069D01*
X-1771764Y-201172D01*
X-1771151Y-200965D01*
X-1770691Y-200449D01*
X-1770231Y-199519D01*
G01X-1766867Y-202619D02*
X-1766331Y-203135D01*
X-1765717Y-203342D01*
X-1765104Y-203135D01*
X-1764567Y-202516D01*
X-1764184Y-201585D01*
X-1764031Y-200655D01*
Y-199519D01*
X-1764184Y-198589D01*
X-1764567Y-197762D01*
X-1765027Y-197349D01*
X-1765564Y-197142D01*
X-1766177Y-197349D01*
X-1766637Y-197762D01*
X-1766944Y-198382D01*
X-1767097Y-199209D01*
X-1766944Y-199932D01*
X-1766561Y-200655D01*
X-1766101Y-201069D01*
X-1765564Y-201172D01*
X-1764951Y-200965D01*
X-1764491Y-200449D01*
X-1764031Y-199519D01*
G01X-1760821Y-198175D02*
X-1760361Y-197555D01*
X-1759824Y-197245D01*
X-1759211Y-197142D01*
X-1758444Y-197349D01*
X-1757907Y-197865D01*
X-1757754Y-198485D01*
X-1757831Y-199105D01*
X-1758137Y-199622D01*
X-1759671Y-200655D01*
X-1760361Y-201379D01*
X-1760821Y-202412D01*
X-1760974Y-203342D01*
X-1757754D01*
G01X-1798397Y-144962D02*
Y-138762D01*
X-1796404Y-143929D01*
X-1794411Y-138762D01*
Y-144962D01*
G01X-1792121D02*
X-1790204Y-138762D01*
X-1788287Y-144962D01*
G01X-1788977Y-142792D02*
X-1791431D01*
G01X-1782317Y-139279D02*
X-1782777Y-138969D01*
X-1783314Y-138762D01*
X-1783927D01*
X-1784617Y-139072D01*
X-1785154Y-139589D01*
X-1785537Y-140209D01*
X-1785844Y-141242D01*
X-1785921Y-142172D01*
X-1785767Y-143102D01*
X-1785537Y-143722D01*
X-1785077Y-144342D01*
X-1784541Y-144755D01*
X-1784004Y-144962D01*
X-1783467D01*
X-1782931Y-144755D01*
X-1782471Y-144445D01*
X-1782087Y-144032D01*
G01X-1780104Y-147029D02*
X-1775504D01*
G01X-1773137Y-144962D02*
Y-138762D01*
X-1771297D01*
X-1770684Y-139072D01*
X-1770224Y-139795D01*
X-1770071Y-140622D01*
X-1770224Y-141449D01*
X-1770607Y-142069D01*
X-1771297Y-142379D01*
X-1773137D01*
G01X-1766324Y-138762D02*
X-1764484D01*
G01X-1765404D02*
Y-144962D01*
G01X-1766324D02*
X-1764484D01*
G01X-1760967D02*
Y-138762D01*
X-1757441Y-144962D01*
Y-138762D01*
G01X-1754691Y-143722D02*
X-1754231Y-144445D01*
X-1753617Y-144859D01*
X-1752927Y-144962D01*
X-1752314Y-144859D01*
X-1751701Y-144342D01*
X-1751317Y-143722D01*
X-1751241Y-143102D01*
X-1751394Y-142379D01*
X-1751931Y-141862D01*
X-1752467Y-141655D01*
X-1753157D01*
G01X-1752467D02*
X-1752007Y-141345D01*
X-1751624Y-140829D01*
X-1751471Y-140209D01*
X-1751624Y-139589D01*
X-1752007Y-139072D01*
X-1752697Y-138762D01*
X-1753387Y-138865D01*
X-1754077Y-139279D01*
G01X-1790397Y169038D02*
Y175238D01*
X-1788404Y170071D01*
X-1786411Y175238D01*
Y169038D01*
G01X-1784121D02*
X-1782204Y175238D01*
X-1780287Y169038D01*
G01X-1780977Y171208D02*
X-1783431D01*
G01X-1774317Y174721D02*
X-1774777Y175031D01*
X-1775314Y175238D01*
X-1775927D01*
X-1776617Y174928D01*
X-1777154Y174411D01*
X-1777537Y173791D01*
X-1777844Y172758D01*
X-1777921Y171828D01*
X-1777767Y170898D01*
X-1777537Y170278D01*
X-1777077Y169658D01*
X-1776541Y169245D01*
X-1776004Y169038D01*
X-1775467D01*
X-1774931Y169245D01*
X-1774471Y169555D01*
X-1774087Y169968D01*
G01X-1772104Y166971D02*
X-1767504D01*
G01X-1765137Y169038D02*
Y175238D01*
X-1763297D01*
X-1762684Y174928D01*
X-1762224Y174205D01*
X-1762071Y173378D01*
X-1762224Y172551D01*
X-1762607Y171931D01*
X-1763297Y171621D01*
X-1765137D01*
G01X-1758324Y175238D02*
X-1756484D01*
G01X-1757404D02*
Y169038D01*
G01X-1758324D02*
X-1756484D01*
G01X-1752967D02*
Y175238D01*
X-1749441Y169038D01*
Y175238D01*
G01X-1745004Y169038D02*
Y175238D01*
X-1745924Y173998D01*
G01Y169038D02*
X-1744084D01*
G01X-1793640Y230205D02*
X-1799840D01*
Y232121D01*
X-1799530Y232735D01*
X-1799117Y233118D01*
X-1798290Y233271D01*
X-1797463Y233118D01*
X-1796947Y232658D01*
X-1796637Y232121D01*
Y230205D01*
G01Y232121D02*
X-1793640Y233271D01*
G01X-1794880Y236251D02*
X-1794157Y236711D01*
X-1793743Y237325D01*
X-1793640Y238015D01*
X-1793743Y238628D01*
X-1794260Y239241D01*
X-1794880Y239625D01*
X-1795500Y239701D01*
X-1796223Y239548D01*
X-1796740Y239011D01*
X-1796947Y238475D01*
Y237785D01*
G01Y238475D02*
X-1797257Y238935D01*
X-1797773Y239318D01*
X-1798393Y239471D01*
X-1799013Y239318D01*
X-1799530Y238935D01*
X-1799840Y238245D01*
X-1799737Y237555D01*
X-1799323Y236865D01*
G01X-1794570Y242451D02*
X-1794053Y242911D01*
X-1793743Y243448D01*
X-1793640Y244138D01*
X-1793847Y244828D01*
X-1794260Y245365D01*
X-1794983Y245748D01*
X-1795810Y245825D01*
X-1796637Y245671D01*
X-1797153Y245288D01*
X-1797567Y244751D01*
X-1797670Y244215D01*
X-1797567Y243678D01*
X-1797153Y242988D01*
X-1799840Y243218D01*
Y245288D01*
G01X-1794880Y248651D02*
X-1794157Y249111D01*
X-1793743Y249725D01*
X-1793640Y250415D01*
X-1793743Y251028D01*
X-1794260Y251641D01*
X-1794880Y252025D01*
X-1795500Y252101D01*
X-1796223Y251948D01*
X-1796740Y251411D01*
X-1796947Y250875D01*
Y250185D01*
G01Y250875D02*
X-1797257Y251335D01*
X-1797773Y251718D01*
X-1798393Y251871D01*
X-1799013Y251718D01*
X-1799530Y251335D01*
X-1799840Y250645D01*
X-1799737Y249955D01*
X-1799323Y249265D01*
G01X-1783640Y230205D02*
X-1789840D01*
Y232121D01*
X-1789530Y232735D01*
X-1789117Y233118D01*
X-1788290Y233271D01*
X-1787463Y233118D01*
X-1786947Y232658D01*
X-1786637Y232121D01*
Y230205D01*
G01Y232121D02*
X-1783640Y233271D01*
G01X-1784880Y236251D02*
X-1784157Y236711D01*
X-1783743Y237325D01*
X-1783640Y238015D01*
X-1783743Y238628D01*
X-1784260Y239241D01*
X-1784880Y239625D01*
X-1785500Y239701D01*
X-1786223Y239548D01*
X-1786740Y239011D01*
X-1786947Y238475D01*
Y237785D01*
G01Y238475D02*
X-1787257Y238935D01*
X-1787773Y239318D01*
X-1788393Y239471D01*
X-1789013Y239318D01*
X-1789530Y238935D01*
X-1789840Y238245D01*
X-1789737Y237555D01*
X-1789323Y236865D01*
G01X-1784570Y242451D02*
X-1784053Y242911D01*
X-1783743Y243448D01*
X-1783640Y244138D01*
X-1783847Y244828D01*
X-1784260Y245365D01*
X-1784983Y245748D01*
X-1785810Y245825D01*
X-1786637Y245671D01*
X-1787153Y245288D01*
X-1787567Y244751D01*
X-1787670Y244215D01*
X-1787567Y243678D01*
X-1787153Y242988D01*
X-1789840Y243218D01*
Y245288D01*
G01X-1788807Y248881D02*
X-1789427Y249341D01*
X-1789737Y249878D01*
X-1789840Y250491D01*
X-1789633Y251258D01*
X-1789117Y251795D01*
X-1788497Y251948D01*
X-1787877Y251871D01*
X-1787360Y251565D01*
X-1786327Y250031D01*
X-1785603Y249341D01*
X-1784570Y248881D01*
X-1783640Y248728D01*
Y251948D01*
G01X-1789932Y310531D02*
X-1785489D01*
X-1784558Y310838D01*
X-1783939Y311451D01*
X-1783732Y312218D01*
X-1783939Y312985D01*
X-1784558Y313598D01*
X-1785489Y313905D01*
X-1789932D01*
G01X-1783732Y318418D02*
X-1789932D01*
X-1788692Y317498D01*
G01X-1783732D02*
Y319338D01*
G01Y324618D02*
X-1783835Y325155D01*
X-1784145Y325768D01*
X-1784662Y326151D01*
X-1785385Y326305D01*
X-1786109Y326151D01*
X-1786729Y325691D01*
X-1787039Y325001D01*
Y324235D01*
X-1787245Y323775D01*
X-1787762Y323391D01*
X-1788485Y323238D01*
X-1789209Y323468D01*
X-1789725Y324005D01*
X-1789932Y324618D01*
X-1789725Y325231D01*
X-1789209Y325768D01*
X-1788485Y325998D01*
X-1787762Y325845D01*
X-1787245Y325461D01*
X-1787039Y325001D01*
Y324235D01*
X-1786729Y323545D01*
X-1786109Y323085D01*
X-1785385Y322931D01*
X-1784662Y323085D01*
X-1784145Y323468D01*
X-1783835Y324081D01*
X-1783732Y324618D01*
G01X-1787640Y380205D02*
X-1793840D01*
Y382121D01*
X-1793530Y382735D01*
X-1793117Y383118D01*
X-1792290Y383271D01*
X-1791463Y383118D01*
X-1790947Y382658D01*
X-1790637Y382121D01*
Y380205D01*
G01Y382121D02*
X-1787640Y383271D01*
G01Y387938D02*
X-1793840D01*
X-1792600Y387018D01*
G01X-1787640D02*
Y388858D01*
G01X-1792807Y392681D02*
X-1793427Y393141D01*
X-1793737Y393678D01*
X-1793840Y394291D01*
X-1793633Y395058D01*
X-1793117Y395595D01*
X-1792497Y395748D01*
X-1791877Y395671D01*
X-1791360Y395365D01*
X-1790327Y393831D01*
X-1789603Y393141D01*
X-1788570Y392681D01*
X-1787640Y392528D01*
Y395748D01*
G01X-1788363Y399035D02*
X-1787847Y399571D01*
X-1787640Y400185D01*
X-1787847Y400798D01*
X-1788466Y401335D01*
X-1789397Y401718D01*
X-1790327Y401871D01*
X-1791463D01*
X-1792393Y401718D01*
X-1793220Y401335D01*
X-1793633Y400875D01*
X-1793840Y400338D01*
X-1793633Y399725D01*
X-1793220Y399265D01*
X-1792600Y398958D01*
X-1791773Y398805D01*
X-1791050Y398958D01*
X-1790327Y399341D01*
X-1789913Y399801D01*
X-1789810Y400338D01*
X-1790017Y400951D01*
X-1790533Y401411D01*
X-1791463Y401871D01*
G01X-1779377Y-225659D02*
X-1779837Y-225349D01*
X-1780374Y-225142D01*
X-1780987D01*
X-1781677Y-225452D01*
X-1782214Y-225969D01*
X-1782597Y-226589D01*
X-1782904Y-227622D01*
X-1782981Y-228552D01*
X-1782827Y-229482D01*
X-1782597Y-230102D01*
X-1782137Y-230722D01*
X-1781601Y-231135D01*
X-1781064Y-231342D01*
X-1780527D01*
X-1779991Y-231135D01*
X-1779531Y-230825D01*
X-1779147Y-230412D01*
G01X-1776321Y-226175D02*
X-1775861Y-225555D01*
X-1775324Y-225245D01*
X-1774711Y-225142D01*
X-1773944Y-225349D01*
X-1773407Y-225865D01*
X-1773254Y-226485D01*
X-1773331Y-227105D01*
X-1773637Y-227622D01*
X-1775171Y-228655D01*
X-1775861Y-229379D01*
X-1776321Y-230412D01*
X-1776474Y-231342D01*
X-1773254D01*
G01X-1770121Y-226175D02*
X-1769661Y-225555D01*
X-1769124Y-225245D01*
X-1768511Y-225142D01*
X-1767744Y-225349D01*
X-1767207Y-225865D01*
X-1767054Y-226485D01*
X-1767131Y-227105D01*
X-1767437Y-227622D01*
X-1768971Y-228655D01*
X-1769661Y-229379D01*
X-1770121Y-230412D01*
X-1770274Y-231342D01*
X-1767054D01*
G01X-1764151Y-230412D02*
X-1763691Y-230929D01*
X-1763154Y-231239D01*
X-1762464Y-231342D01*
X-1761774Y-231135D01*
X-1761237Y-230722D01*
X-1760854Y-229999D01*
X-1760777Y-229172D01*
X-1760931Y-228345D01*
X-1761314Y-227829D01*
X-1761851Y-227415D01*
X-1762387Y-227312D01*
X-1762924Y-227415D01*
X-1763614Y-227829D01*
X-1763384Y-225142D01*
X-1761314D01*
G01X-1782597Y-222342D02*
Y-216142D01*
X-1780681D01*
X-1780067Y-216452D01*
X-1779684Y-216865D01*
X-1779531Y-217692D01*
X-1779684Y-218519D01*
X-1780144Y-219035D01*
X-1780681Y-219345D01*
X-1782597D01*
G01X-1780681D02*
X-1779531Y-222342D01*
G01X-1776551Y-221102D02*
X-1776091Y-221825D01*
X-1775477Y-222239D01*
X-1774787Y-222342D01*
X-1774174Y-222239D01*
X-1773561Y-221722D01*
X-1773177Y-221102D01*
X-1773101Y-220482D01*
X-1773254Y-219759D01*
X-1773791Y-219242D01*
X-1774327Y-219035D01*
X-1775017D01*
G01X-1774327D02*
X-1773867Y-218725D01*
X-1773484Y-218209D01*
X-1773331Y-217589D01*
X-1773484Y-216969D01*
X-1773867Y-216452D01*
X-1774557Y-216142D01*
X-1775247Y-216245D01*
X-1775937Y-216659D01*
G01X-1767744Y-222342D02*
Y-216142D01*
X-1770581Y-220585D01*
X-1766747D01*
G01X-1764151Y-221412D02*
X-1763691Y-221929D01*
X-1763154Y-222239D01*
X-1762464Y-222342D01*
X-1761774Y-222135D01*
X-1761237Y-221722D01*
X-1760854Y-220999D01*
X-1760777Y-220172D01*
X-1760931Y-219345D01*
X-1761314Y-218829D01*
X-1761851Y-218415D01*
X-1762387Y-218312D01*
X-1762924Y-218415D01*
X-1763614Y-218829D01*
X-1763384Y-216142D01*
X-1761314D01*
G01X-1779497Y-212342D02*
Y-206142D01*
X-1777581D01*
X-1776967Y-206452D01*
X-1776584Y-206865D01*
X-1776431Y-207692D01*
X-1776584Y-208519D01*
X-1777044Y-209035D01*
X-1777581Y-209345D01*
X-1779497D01*
G01X-1777581D02*
X-1776431Y-212342D01*
G01X-1771764D02*
Y-206142D01*
X-1772684Y-207382D01*
G01Y-212342D02*
X-1770844D01*
G01X-1766867Y-211619D02*
X-1766331Y-212135D01*
X-1765717Y-212342D01*
X-1765104Y-212135D01*
X-1764567Y-211516D01*
X-1764184Y-210585D01*
X-1764031Y-209655D01*
Y-208519D01*
X-1764184Y-207589D01*
X-1764567Y-206762D01*
X-1765027Y-206349D01*
X-1765564Y-206142D01*
X-1766177Y-206349D01*
X-1766637Y-206762D01*
X-1766944Y-207382D01*
X-1767097Y-208209D01*
X-1766944Y-208932D01*
X-1766561Y-209655D01*
X-1766101Y-210069D01*
X-1765564Y-210172D01*
X-1764951Y-209965D01*
X-1764491Y-209449D01*
X-1764031Y-208519D01*
G01X-1782263Y14024D02*
Y20224D01*
X-1780270Y15057D01*
X-1778277Y20224D01*
Y14024D01*
G01X-1775987D02*
X-1774070Y20224D01*
X-1772153Y14024D01*
G01X-1772843Y16194D02*
X-1775297D01*
G01X-1766183Y19707D02*
X-1766643Y20017D01*
X-1767180Y20224D01*
X-1767793D01*
X-1768483Y19914D01*
X-1769020Y19397D01*
X-1769403Y18777D01*
X-1769710Y17744D01*
X-1769787Y16814D01*
X-1769633Y15884D01*
X-1769403Y15264D01*
X-1768943Y14644D01*
X-1768407Y14231D01*
X-1767870Y14024D01*
X-1767333D01*
X-1766797Y14231D01*
X-1766337Y14541D01*
X-1765953Y14954D01*
G01X-1763970Y11957D02*
X-1759370D01*
G01X-1757003Y14024D02*
Y20224D01*
X-1755163D01*
X-1754550Y19914D01*
X-1754090Y19191D01*
X-1753937Y18364D01*
X-1754090Y17537D01*
X-1754473Y16917D01*
X-1755163Y16607D01*
X-1757003D01*
G01X-1750190Y20224D02*
X-1748350D01*
G01X-1749270D02*
Y14024D01*
G01X-1750190D02*
X-1748350D01*
G01X-1744833D02*
Y20224D01*
X-1741307Y14024D01*
Y20224D01*
G01X-1738327Y19191D02*
X-1737867Y19811D01*
X-1737330Y20121D01*
X-1736717Y20224D01*
X-1735950Y20017D01*
X-1735413Y19501D01*
X-1735260Y18881D01*
X-1735337Y18261D01*
X-1735643Y17744D01*
X-1737177Y16711D01*
X-1737867Y15987D01*
X-1738327Y14954D01*
X-1738480Y14024D01*
X-1735260D01*
G01X-1773640Y230205D02*
X-1779840D01*
Y232121D01*
X-1779530Y232735D01*
X-1779117Y233118D01*
X-1778290Y233271D01*
X-1777463Y233118D01*
X-1776947Y232658D01*
X-1776637Y232121D01*
Y230205D01*
G01Y232121D02*
X-1773640Y233271D01*
G01Y238858D02*
X-1779840D01*
X-1775397Y236021D01*
Y239855D01*
G01X-1773640Y244138D02*
X-1773743Y244675D01*
X-1774053Y245288D01*
X-1774570Y245671D01*
X-1775293Y245825D01*
X-1776017Y245671D01*
X-1776637Y245211D01*
X-1776947Y244521D01*
Y243755D01*
X-1777153Y243295D01*
X-1777670Y242911D01*
X-1778393Y242758D01*
X-1779117Y242988D01*
X-1779633Y243525D01*
X-1779840Y244138D01*
X-1779633Y244751D01*
X-1779117Y245288D01*
X-1778393Y245518D01*
X-1777670Y245365D01*
X-1777153Y244981D01*
X-1776947Y244521D01*
Y243755D01*
X-1776637Y243065D01*
X-1776017Y242605D01*
X-1775293Y242451D01*
X-1774570Y242605D01*
X-1774053Y242988D01*
X-1773743Y243601D01*
X-1773640Y244138D01*
G01Y250338D02*
X-1779840D01*
X-1778600Y249418D01*
G01X-1773640D02*
Y251258D01*
G01X-1777640Y380205D02*
X-1783840D01*
Y382121D01*
X-1783530Y382735D01*
X-1783117Y383118D01*
X-1782290Y383271D01*
X-1781463Y383118D01*
X-1780947Y382658D01*
X-1780637Y382121D01*
Y380205D01*
G01Y382121D02*
X-1777640Y383271D01*
G01Y387938D02*
X-1783840D01*
X-1782600Y387018D01*
G01X-1777640D02*
Y388858D01*
G01X-1782807Y392681D02*
X-1783427Y393141D01*
X-1783737Y393678D01*
X-1783840Y394291D01*
X-1783633Y395058D01*
X-1783117Y395595D01*
X-1782497Y395748D01*
X-1781877Y395671D01*
X-1781360Y395365D01*
X-1780327Y393831D01*
X-1779603Y393141D01*
X-1778570Y392681D01*
X-1777640Y392528D01*
Y395748D01*
G01Y400338D02*
X-1777743Y400875D01*
X-1778053Y401488D01*
X-1778570Y401871D01*
X-1779293Y402025D01*
X-1780017Y401871D01*
X-1780637Y401411D01*
X-1780947Y400721D01*
Y399955D01*
X-1781153Y399495D01*
X-1781670Y399111D01*
X-1782393Y398958D01*
X-1783117Y399188D01*
X-1783633Y399725D01*
X-1783840Y400338D01*
X-1783633Y400951D01*
X-1783117Y401488D01*
X-1782393Y401718D01*
X-1781670Y401565D01*
X-1781153Y401181D01*
X-1780947Y400721D01*
Y399955D01*
X-1780637Y399265D01*
X-1780017Y398805D01*
X-1779293Y398651D01*
X-1778570Y398805D01*
X-1778053Y399188D01*
X-1777743Y399801D01*
X-1777640Y400338D01*
G01X-1771537Y396970D02*
Y403170D01*
X-1769621D01*
X-1769007Y402860D01*
X-1768624Y402447D01*
X-1768471Y401620D01*
X-1768624Y400793D01*
X-1769084Y400277D01*
X-1769621Y399967D01*
X-1771537D01*
G01X-1769621D02*
X-1768471Y396970D01*
G01X-1762884D02*
Y403170D01*
X-1765721Y398727D01*
X-1761887D01*
G01X-1759291Y397900D02*
X-1758831Y397383D01*
X-1758294Y397073D01*
X-1757604Y396970D01*
X-1756914Y397177D01*
X-1756377Y397590D01*
X-1755994Y398313D01*
X-1755917Y399140D01*
X-1756071Y399967D01*
X-1756454Y400483D01*
X-1756991Y400897D01*
X-1757527Y401000D01*
X-1758064Y400897D01*
X-1758754Y400483D01*
X-1758524Y403170D01*
X-1756454D01*
G01X-1753091Y397900D02*
X-1752631Y397383D01*
X-1752094Y397073D01*
X-1751404Y396970D01*
X-1750714Y397177D01*
X-1750177Y397590D01*
X-1749794Y398313D01*
X-1749717Y399140D01*
X-1749871Y399967D01*
X-1750254Y400483D01*
X-1750791Y400897D01*
X-1751327Y401000D01*
X-1751864Y400897D01*
X-1752554Y400483D01*
X-1752324Y403170D01*
X-1750254D01*
G01X-1770217Y409621D02*
X-1770677Y409931D01*
X-1771214Y410138D01*
X-1771827D01*
X-1772517Y409828D01*
X-1773054Y409311D01*
X-1773437Y408691D01*
X-1773744Y407658D01*
X-1773821Y406728D01*
X-1773667Y405798D01*
X-1773437Y405178D01*
X-1772977Y404558D01*
X-1772441Y404145D01*
X-1771904Y403938D01*
X-1771367D01*
X-1770831Y404145D01*
X-1770371Y404455D01*
X-1769987Y404868D01*
G01X-1765704Y403938D02*
X-1765167Y404041D01*
X-1764554Y404351D01*
X-1764171Y404868D01*
X-1764017Y405591D01*
X-1764171Y406315D01*
X-1764631Y406935D01*
X-1765321Y407245D01*
X-1766087D01*
X-1766547Y407451D01*
X-1766931Y407968D01*
X-1767084Y408691D01*
X-1766854Y409415D01*
X-1766317Y409931D01*
X-1765704Y410138D01*
X-1765091Y409931D01*
X-1764554Y409415D01*
X-1764324Y408691D01*
X-1764477Y407968D01*
X-1764861Y407451D01*
X-1765321Y407245D01*
X-1766087D01*
X-1766777Y406935D01*
X-1767237Y406315D01*
X-1767391Y405591D01*
X-1767237Y404868D01*
X-1766854Y404351D01*
X-1766241Y404041D01*
X-1765704Y403938D01*
G01X-1759657D02*
X-1759504Y405281D01*
X-1759274Y406418D01*
X-1758967Y407451D01*
X-1758584Y408588D01*
X-1757971Y410138D01*
X-1761037D01*
G01X-1779391Y413178D02*
X-1778931Y412455D01*
X-1778317Y412041D01*
X-1777627Y411938D01*
X-1777014Y412041D01*
X-1776401Y412558D01*
X-1776017Y413178D01*
X-1775941Y413798D01*
X-1776094Y414521D01*
X-1776631Y415038D01*
X-1777167Y415245D01*
X-1777857D01*
G01X-1777167D02*
X-1776707Y415555D01*
X-1776324Y416071D01*
X-1776171Y416691D01*
X-1776324Y417311D01*
X-1776707Y417828D01*
X-1777397Y418138D01*
X-1778087Y418035D01*
X-1778777Y417621D01*
G01X-1778161Y444105D02*
X-1777701Y444725D01*
X-1777164Y445035D01*
X-1776551Y445138D01*
X-1775784Y444931D01*
X-1775247Y444415D01*
X-1775094Y443795D01*
X-1775171Y443175D01*
X-1775477Y442658D01*
X-1777011Y441625D01*
X-1777701Y440901D01*
X-1778161Y439868D01*
X-1778314Y438938D01*
X-1775094D01*
G01X-1755637Y-231462D02*
Y-225262D01*
X-1753721D01*
X-1753107Y-225572D01*
X-1752724Y-225985D01*
X-1752571Y-226812D01*
X-1752724Y-227639D01*
X-1753184Y-228155D01*
X-1753721Y-228465D01*
X-1755637D01*
G01X-1753721D02*
X-1752571Y-231462D01*
G01X-1747904D02*
Y-225262D01*
X-1748824Y-226502D01*
G01Y-231462D02*
X-1746984D01*
G01X-1741704D02*
X-1741167Y-231359D01*
X-1740554Y-231049D01*
X-1740171Y-230532D01*
X-1740017Y-229809D01*
X-1740171Y-229085D01*
X-1740631Y-228465D01*
X-1741321Y-228155D01*
X-1742087D01*
X-1742547Y-227949D01*
X-1742931Y-227432D01*
X-1743084Y-226709D01*
X-1742854Y-225985D01*
X-1742317Y-225469D01*
X-1741704Y-225262D01*
X-1741091Y-225469D01*
X-1740554Y-225985D01*
X-1740324Y-226709D01*
X-1740477Y-227432D01*
X-1740861Y-227949D01*
X-1741321Y-228155D01*
X-1742087D01*
X-1742777Y-228465D01*
X-1743237Y-229085D01*
X-1743391Y-229809D01*
X-1743237Y-230532D01*
X-1742854Y-231049D01*
X-1742241Y-231359D01*
X-1741704Y-231462D01*
G01X-1737191Y-230222D02*
X-1736731Y-230945D01*
X-1736117Y-231359D01*
X-1735427Y-231462D01*
X-1734814Y-231359D01*
X-1734201Y-230842D01*
X-1733817Y-230222D01*
X-1733741Y-229602D01*
X-1733894Y-228879D01*
X-1734431Y-228362D01*
X-1734967Y-228155D01*
X-1735657D01*
G01X-1734967D02*
X-1734507Y-227845D01*
X-1734124Y-227329D01*
X-1733971Y-226709D01*
X-1734124Y-226089D01*
X-1734507Y-225572D01*
X-1735197Y-225262D01*
X-1735887Y-225365D01*
X-1736577Y-225779D01*
G01X-1755637Y-222462D02*
Y-216262D01*
X-1753721D01*
X-1753107Y-216572D01*
X-1752724Y-216985D01*
X-1752571Y-217812D01*
X-1752724Y-218639D01*
X-1753184Y-219155D01*
X-1753721Y-219465D01*
X-1755637D01*
G01X-1753721D02*
X-1752571Y-222462D01*
G01X-1749591Y-221222D02*
X-1749131Y-221945D01*
X-1748517Y-222359D01*
X-1747827Y-222462D01*
X-1747214Y-222359D01*
X-1746601Y-221842D01*
X-1746217Y-221222D01*
X-1746141Y-220602D01*
X-1746294Y-219879D01*
X-1746831Y-219362D01*
X-1747367Y-219155D01*
X-1748057D01*
G01X-1747367D02*
X-1746907Y-218845D01*
X-1746524Y-218329D01*
X-1746371Y-217709D01*
X-1746524Y-217089D01*
X-1746907Y-216572D01*
X-1747597Y-216262D01*
X-1748287Y-216365D01*
X-1748977Y-216779D01*
G01X-1741704Y-222462D02*
Y-216262D01*
X-1742624Y-217502D01*
G01Y-222462D02*
X-1740784D01*
G01X-1736961Y-217295D02*
X-1736501Y-216675D01*
X-1735964Y-216365D01*
X-1735351Y-216262D01*
X-1734584Y-216469D01*
X-1734047Y-216985D01*
X-1733894Y-217605D01*
X-1733971Y-218225D01*
X-1734277Y-218742D01*
X-1735811Y-219775D01*
X-1736501Y-220499D01*
X-1736961Y-221532D01*
X-1737114Y-222462D01*
X-1733894D01*
G01X-1755597Y-203462D02*
Y-197262D01*
X-1753681D01*
X-1753067Y-197572D01*
X-1752684Y-197985D01*
X-1752531Y-198812D01*
X-1752684Y-199639D01*
X-1753144Y-200155D01*
X-1753681Y-200465D01*
X-1755597D01*
G01X-1753681D02*
X-1752531Y-203462D01*
G01X-1749551Y-202222D02*
X-1749091Y-202945D01*
X-1748477Y-203359D01*
X-1747787Y-203462D01*
X-1747174Y-203359D01*
X-1746561Y-202842D01*
X-1746177Y-202222D01*
X-1746101Y-201602D01*
X-1746254Y-200879D01*
X-1746791Y-200362D01*
X-1747327Y-200155D01*
X-1748017D01*
G01X-1747327D02*
X-1746867Y-199845D01*
X-1746484Y-199329D01*
X-1746331Y-198709D01*
X-1746484Y-198089D01*
X-1746867Y-197572D01*
X-1747557Y-197262D01*
X-1748247Y-197365D01*
X-1748937Y-197779D01*
G01X-1741664Y-203462D02*
Y-197262D01*
X-1742584Y-198502D01*
G01Y-203462D02*
X-1740744D01*
G01X-1737151Y-202222D02*
X-1736691Y-202945D01*
X-1736077Y-203359D01*
X-1735387Y-203462D01*
X-1734774Y-203359D01*
X-1734161Y-202842D01*
X-1733777Y-202222D01*
X-1733701Y-201602D01*
X-1733854Y-200879D01*
X-1734391Y-200362D01*
X-1734927Y-200155D01*
X-1735617D01*
G01X-1734927D02*
X-1734467Y-199845D01*
X-1734084Y-199329D01*
X-1733931Y-198709D01*
X-1734084Y-198089D01*
X-1734467Y-197572D01*
X-1735157Y-197262D01*
X-1735847Y-197365D01*
X-1736537Y-197779D01*
G01X-1755597Y-212462D02*
Y-206262D01*
X-1753681D01*
X-1753067Y-206572D01*
X-1752684Y-206985D01*
X-1752531Y-207812D01*
X-1752684Y-208639D01*
X-1753144Y-209155D01*
X-1753681Y-209465D01*
X-1755597D01*
G01X-1753681D02*
X-1752531Y-212462D01*
G01X-1747864D02*
Y-206262D01*
X-1748784Y-207502D01*
G01Y-212462D02*
X-1746944D01*
G01X-1741664D02*
X-1741127Y-212359D01*
X-1740514Y-212049D01*
X-1740131Y-211532D01*
X-1739977Y-210809D01*
X-1740131Y-210085D01*
X-1740591Y-209465D01*
X-1741281Y-209155D01*
X-1742047D01*
X-1742507Y-208949D01*
X-1742891Y-208432D01*
X-1743044Y-207709D01*
X-1742814Y-206985D01*
X-1742277Y-206469D01*
X-1741664Y-206262D01*
X-1741051Y-206469D01*
X-1740514Y-206985D01*
X-1740284Y-207709D01*
X-1740437Y-208432D01*
X-1740821Y-208949D01*
X-1741281Y-209155D01*
X-1742047D01*
X-1742737Y-209465D01*
X-1743197Y-210085D01*
X-1743351Y-210809D01*
X-1743197Y-211532D01*
X-1742814Y-212049D01*
X-1742201Y-212359D01*
X-1741664Y-212462D01*
G01X-1734544D02*
Y-206262D01*
X-1737381Y-210705D01*
X-1733547D01*
G01X-1753426Y257728D02*
X-1759626D01*
X-1755183Y254891D01*
Y258725D01*
G01X-1753426Y263008D02*
X-1753529Y263545D01*
X-1753839Y264158D01*
X-1754356Y264541D01*
X-1755079Y264695D01*
X-1755803Y264541D01*
X-1756423Y264081D01*
X-1756733Y263391D01*
Y262625D01*
X-1756939Y262165D01*
X-1757456Y261781D01*
X-1758179Y261628D01*
X-1758903Y261858D01*
X-1759419Y262395D01*
X-1759626Y263008D01*
X-1759419Y263621D01*
X-1758903Y264158D01*
X-1758179Y264388D01*
X-1757456Y264235D01*
X-1756939Y263851D01*
X-1756733Y263391D01*
Y262625D01*
X-1756423Y261935D01*
X-1755803Y261475D01*
X-1755079Y261321D01*
X-1754356Y261475D01*
X-1753839Y261858D01*
X-1753529Y262471D01*
X-1753426Y263008D01*
G01X-1753303Y409921D02*
X-1753763Y410231D01*
X-1754300Y410438D01*
X-1754913D01*
X-1755603Y410128D01*
X-1756140Y409611D01*
X-1756523Y408991D01*
X-1756830Y407958D01*
X-1756907Y407028D01*
X-1756753Y406098D01*
X-1756523Y405478D01*
X-1756063Y404858D01*
X-1755527Y404445D01*
X-1754990Y404238D01*
X-1754453D01*
X-1753917Y404445D01*
X-1753457Y404755D01*
X-1753073Y405168D01*
G01X-1748790Y404238D02*
X-1748253Y404341D01*
X-1747640Y404651D01*
X-1747257Y405168D01*
X-1747103Y405891D01*
X-1747257Y406615D01*
X-1747717Y407235D01*
X-1748407Y407545D01*
X-1749173D01*
X-1749633Y407751D01*
X-1750017Y408268D01*
X-1750170Y408991D01*
X-1749940Y409715D01*
X-1749403Y410231D01*
X-1748790Y410438D01*
X-1748177Y410231D01*
X-1747640Y409715D01*
X-1747410Y408991D01*
X-1747563Y408268D01*
X-1747947Y407751D01*
X-1748407Y407545D01*
X-1749173D01*
X-1749863Y407235D01*
X-1750323Y406615D01*
X-1750477Y405891D01*
X-1750323Y405168D01*
X-1749940Y404651D01*
X-1749327Y404341D01*
X-1748790Y404238D01*
G01X-1744047Y406821D02*
X-1743510Y407545D01*
X-1743050Y407958D01*
X-1742437Y408165D01*
X-1741900Y407958D01*
X-1741517Y407545D01*
X-1741210Y406925D01*
X-1741133Y406201D01*
X-1741210Y405581D01*
X-1741517Y404961D01*
X-1741977Y404445D01*
X-1742513Y404238D01*
X-1743127Y404445D01*
X-1743663Y405064D01*
X-1743970Y405995D01*
X-1744047Y407028D01*
X-1743893Y408371D01*
X-1743663Y409095D01*
X-1743280Y409818D01*
X-1742743Y410335D01*
X-1742207Y410438D01*
X-1741670Y410231D01*
X-1741287Y409715D01*
G01X-1762804Y422938D02*
Y425728D01*
X-1764337Y429138D01*
G01X-1761271D02*
X-1762804Y425728D01*
G01X-1758061Y428105D02*
X-1757601Y428725D01*
X-1757064Y429035D01*
X-1756451Y429138D01*
X-1755684Y428931D01*
X-1755147Y428415D01*
X-1754994Y427795D01*
X-1755071Y427175D01*
X-1755377Y426658D01*
X-1756911Y425625D01*
X-1757601Y424901D01*
X-1758061Y423868D01*
X-1758214Y422938D01*
X-1754994D01*
G01X-1739784Y412938D02*
Y419138D01*
X-1742621Y414695D01*
X-1738787D01*
G01X-1730604Y465405D02*
X-1736804D01*
Y467321D01*
X-1736494Y467935D01*
X-1736081Y468318D01*
X-1735254Y468471D01*
X-1734427Y468318D01*
X-1733911Y467858D01*
X-1733601Y467321D01*
Y465405D01*
G01Y467321D02*
X-1730604Y468471D01*
G01X-1733187Y471681D02*
X-1733911Y472218D01*
X-1734324Y472678D01*
X-1734531Y473291D01*
X-1734324Y473828D01*
X-1733911Y474211D01*
X-1733291Y474518D01*
X-1732567Y474595D01*
X-1731947Y474518D01*
X-1731327Y474211D01*
X-1730811Y473751D01*
X-1730604Y473215D01*
X-1730811Y472601D01*
X-1731430Y472065D01*
X-1732361Y471758D01*
X-1733394Y471681D01*
X-1734737Y471835D01*
X-1735461Y472065D01*
X-1736184Y472448D01*
X-1736701Y472985D01*
X-1736804Y473521D01*
X-1736597Y474058D01*
X-1736081Y474441D01*
G01X-1731763Y-141976D02*
Y-135776D01*
X-1729770Y-140943D01*
X-1727777Y-135776D01*
Y-141976D01*
G01X-1722037D02*
X-1725103D01*
Y-135776D01*
X-1722037D01*
G01X-1723263Y-138773D02*
X-1725103D01*
G01X-1717523Y-141976D02*
X-1717370Y-140633D01*
X-1717140Y-139496D01*
X-1716833Y-138463D01*
X-1716450Y-137326D01*
X-1715837Y-135776D01*
X-1718903D01*
G01X-1726763Y182024D02*
Y188224D01*
X-1724770Y183057D01*
X-1722777Y188224D01*
Y182024D01*
G01X-1717037D02*
X-1720103D01*
Y188224D01*
X-1717037D01*
G01X-1718263Y185227D02*
X-1720103D01*
G01X-1714057Y182954D02*
X-1713597Y182437D01*
X-1713060Y182127D01*
X-1712370Y182024D01*
X-1711680Y182231D01*
X-1711143Y182644D01*
X-1710760Y183367D01*
X-1710683Y184194D01*
X-1710837Y185021D01*
X-1711220Y185537D01*
X-1711757Y185951D01*
X-1712293Y186054D01*
X-1712830Y185951D01*
X-1713520Y185537D01*
X-1713290Y188224D01*
X-1711220D01*
G01X-1722319Y249425D02*
X-1722629Y248965D01*
X-1722836Y248428D01*
Y247815D01*
X-1722526Y247125D01*
X-1722009Y246588D01*
X-1721389Y246205D01*
X-1720356Y245898D01*
X-1719426Y245821D01*
X-1718496Y245975D01*
X-1717876Y246205D01*
X-1717256Y246665D01*
X-1716843Y247201D01*
X-1716636Y247738D01*
Y248275D01*
X-1716843Y248811D01*
X-1717153Y249271D01*
X-1717566Y249655D01*
G01X-1717876Y252251D02*
X-1717153Y252711D01*
X-1716739Y253325D01*
X-1716636Y254015D01*
X-1716739Y254628D01*
X-1717256Y255241D01*
X-1717876Y255625D01*
X-1718496Y255701D01*
X-1719219Y255548D01*
X-1719736Y255011D01*
X-1719943Y254475D01*
Y253785D01*
G01Y254475D02*
X-1720253Y254935D01*
X-1720769Y255318D01*
X-1721389Y255471D01*
X-1722009Y255318D01*
X-1722526Y254935D01*
X-1722836Y254245D01*
X-1722733Y253555D01*
X-1722319Y252865D01*
G01X-1722836Y260138D02*
X-1722629Y259525D01*
X-1722113Y259065D01*
X-1721493Y258758D01*
X-1720666Y258528D01*
X-1719736Y258451D01*
X-1718806Y258528D01*
X-1717979Y258758D01*
X-1717359Y259065D01*
X-1716843Y259525D01*
X-1716636Y260138D01*
X-1716843Y260751D01*
X-1717359Y261211D01*
X-1717979Y261518D01*
X-1718806Y261748D01*
X-1719736Y261825D01*
X-1720666Y261748D01*
X-1721493Y261518D01*
X-1722113Y261211D01*
X-1722629Y260751D01*
X-1722836Y260138D01*
G01X-1716636Y266338D02*
X-1716739Y266875D01*
X-1717049Y267488D01*
X-1717566Y267871D01*
X-1718289Y268025D01*
X-1719013Y267871D01*
X-1719633Y267411D01*
X-1719943Y266721D01*
Y265955D01*
X-1720149Y265495D01*
X-1720666Y265111D01*
X-1721389Y264958D01*
X-1722113Y265188D01*
X-1722629Y265725D01*
X-1722836Y266338D01*
X-1722629Y266951D01*
X-1722113Y267488D01*
X-1721389Y267718D01*
X-1720666Y267565D01*
X-1720149Y267181D01*
X-1719943Y266721D01*
Y265955D01*
X-1719633Y265265D01*
X-1719013Y264805D01*
X-1718289Y264651D01*
X-1717566Y264805D01*
X-1717049Y265188D01*
X-1716739Y265801D01*
X-1716636Y266338D01*
G01X-1720537Y236970D02*
Y243170D01*
X-1718621D01*
X-1718007Y242860D01*
X-1717624Y242447D01*
X-1717471Y241620D01*
X-1717624Y240793D01*
X-1718084Y240277D01*
X-1718621Y239967D01*
X-1720537D01*
G01X-1718621D02*
X-1717471Y236970D01*
G01X-1711884D02*
Y243170D01*
X-1714721Y238727D01*
X-1710887D01*
G01X-1706604Y236970D02*
X-1706067Y237073D01*
X-1705454Y237383D01*
X-1705071Y237900D01*
X-1704917Y238623D01*
X-1705071Y239347D01*
X-1705531Y239967D01*
X-1706221Y240277D01*
X-1706987D01*
X-1707447Y240483D01*
X-1707831Y241000D01*
X-1707984Y241723D01*
X-1707754Y242447D01*
X-1707217Y242963D01*
X-1706604Y243170D01*
X-1705991Y242963D01*
X-1705454Y242447D01*
X-1705224Y241723D01*
X-1705377Y241000D01*
X-1705761Y240483D01*
X-1706221Y240277D01*
X-1706987D01*
X-1707677Y239967D01*
X-1708137Y239347D01*
X-1708291Y238623D01*
X-1708137Y237900D01*
X-1707754Y237383D01*
X-1707141Y237073D01*
X-1706604Y236970D01*
G01X-1701707Y237693D02*
X-1701171Y237177D01*
X-1700557Y236970D01*
X-1699944Y237177D01*
X-1699407Y237796D01*
X-1699024Y238727D01*
X-1698871Y239657D01*
Y240793D01*
X-1699024Y241723D01*
X-1699407Y242550D01*
X-1699867Y242963D01*
X-1700404Y243170D01*
X-1701017Y242963D01*
X-1701477Y242550D01*
X-1701784Y241930D01*
X-1701937Y241103D01*
X-1701784Y240380D01*
X-1701401Y239657D01*
X-1700941Y239243D01*
X-1700404Y239140D01*
X-1699791Y239347D01*
X-1699331Y239863D01*
X-1698871Y240793D01*
G01X-1725604Y285700D02*
X-1731804D01*
X-1727361Y282863D01*
Y286697D01*
G01X-1726327Y289677D02*
X-1725811Y290213D01*
X-1725604Y290827D01*
X-1725811Y291440D01*
X-1726430Y291977D01*
X-1727361Y292360D01*
X-1728291Y292513D01*
X-1729427D01*
X-1730357Y292360D01*
X-1731184Y291977D01*
X-1731597Y291517D01*
X-1731804Y290980D01*
X-1731597Y290367D01*
X-1731184Y289907D01*
X-1730564Y289600D01*
X-1729737Y289447D01*
X-1729014Y289600D01*
X-1728291Y289983D01*
X-1727877Y290443D01*
X-1727774Y290980D01*
X-1727981Y291593D01*
X-1728497Y292053D01*
X-1729427Y292513D01*
G01X-1724706Y273867D02*
X-1718506D01*
Y276933D01*
G01X-1723673Y280143D02*
X-1724293Y280603D01*
X-1724603Y281140D01*
X-1724706Y281753D01*
X-1724499Y282520D01*
X-1723983Y283057D01*
X-1723363Y283210D01*
X-1722743Y283133D01*
X-1722226Y282827D01*
X-1721193Y281293D01*
X-1720469Y280603D01*
X-1719436Y280143D01*
X-1718506Y279990D01*
Y283210D01*
G01Y288720D02*
X-1724706D01*
X-1720263Y285883D01*
Y289717D01*
G01X-1728107Y345359D02*
X-1728831Y345896D01*
X-1729244Y346356D01*
X-1729451Y346969D01*
X-1729244Y347506D01*
X-1728831Y347889D01*
X-1728211Y348196D01*
X-1727487Y348273D01*
X-1726867Y348196D01*
X-1726247Y347889D01*
X-1725731Y347429D01*
X-1725524Y346893D01*
X-1725731Y346279D01*
X-1726350Y345743D01*
X-1727281Y345436D01*
X-1728314Y345359D01*
X-1729657Y345513D01*
X-1730381Y345743D01*
X-1731104Y346126D01*
X-1731621Y346663D01*
X-1731724Y347199D01*
X-1731517Y347736D01*
X-1731001Y348119D01*
G01X-1725524Y353936D02*
X-1731724D01*
X-1727281Y351099D01*
Y354933D01*
G01X-1724287Y389525D02*
X-1724597Y389065D01*
X-1724804Y388528D01*
Y387915D01*
X-1724494Y387225D01*
X-1723977Y386688D01*
X-1723357Y386305D01*
X-1722324Y385998D01*
X-1721394Y385921D01*
X-1720464Y386075D01*
X-1719844Y386305D01*
X-1719224Y386765D01*
X-1718811Y387301D01*
X-1718604Y387838D01*
Y388375D01*
X-1718811Y388911D01*
X-1719121Y389371D01*
X-1719534Y389755D01*
G01X-1718604Y393885D02*
X-1719947Y394038D01*
X-1721084Y394268D01*
X-1722117Y394575D01*
X-1723254Y394958D01*
X-1724804Y395571D01*
Y392505D01*
G01X-1718604Y401158D02*
X-1724804D01*
X-1720361Y398321D01*
Y402155D01*
G01X-1732337Y416138D02*
Y422338D01*
X-1730421D01*
X-1729807Y422028D01*
X-1729424Y421615D01*
X-1729271Y420788D01*
X-1729424Y419961D01*
X-1729884Y419445D01*
X-1730421Y419135D01*
X-1732337D01*
G01X-1730421D02*
X-1729271Y416138D01*
G01X-1726061Y421305D02*
X-1725601Y421925D01*
X-1725064Y422235D01*
X-1724451Y422338D01*
X-1723684Y422131D01*
X-1723147Y421615D01*
X-1722994Y420995D01*
X-1723071Y420375D01*
X-1723377Y419858D01*
X-1724911Y418825D01*
X-1725601Y418101D01*
X-1726061Y417068D01*
X-1726214Y416138D01*
X-1722994D01*
G01X-1719707Y416861D02*
X-1719171Y416345D01*
X-1718557Y416138D01*
X-1717944Y416345D01*
X-1717407Y416964D01*
X-1717024Y417895D01*
X-1716871Y418825D01*
Y419961D01*
X-1717024Y420891D01*
X-1717407Y421718D01*
X-1717867Y422131D01*
X-1718404Y422338D01*
X-1719017Y422131D01*
X-1719477Y421718D01*
X-1719784Y421098D01*
X-1719937Y420271D01*
X-1719784Y419548D01*
X-1719401Y418825D01*
X-1718941Y418411D01*
X-1718404Y418308D01*
X-1717791Y418515D01*
X-1717331Y419031D01*
X-1716871Y419961D01*
G01X-1711284Y416138D02*
Y422338D01*
X-1714121Y417895D01*
X-1710287D01*
G01X-1723017Y431821D02*
X-1723477Y432131D01*
X-1724014Y432338D01*
X-1724627D01*
X-1725317Y432028D01*
X-1725854Y431511D01*
X-1726237Y430891D01*
X-1726544Y429858D01*
X-1726621Y428928D01*
X-1726467Y427998D01*
X-1726237Y427378D01*
X-1725777Y426758D01*
X-1725241Y426345D01*
X-1724704Y426138D01*
X-1724167D01*
X-1723631Y426345D01*
X-1723171Y426655D01*
X-1722787Y427068D01*
G01X-1718657Y426138D02*
X-1718504Y427481D01*
X-1718274Y428618D01*
X-1717967Y429651D01*
X-1717584Y430788D01*
X-1716971Y432338D01*
X-1720037D01*
G01X-1713991Y427068D02*
X-1713531Y426551D01*
X-1712994Y426241D01*
X-1712304Y426138D01*
X-1711614Y426345D01*
X-1711077Y426758D01*
X-1710694Y427481D01*
X-1710617Y428308D01*
X-1710771Y429135D01*
X-1711154Y429651D01*
X-1711691Y430065D01*
X-1712227Y430168D01*
X-1712764Y430065D01*
X-1713454Y429651D01*
X-1713224Y432338D01*
X-1711154D01*
G01X-1724017Y440821D02*
X-1724477Y441131D01*
X-1725014Y441338D01*
X-1725627D01*
X-1726317Y441028D01*
X-1726854Y440511D01*
X-1727237Y439891D01*
X-1727544Y438858D01*
X-1727621Y437928D01*
X-1727467Y436998D01*
X-1727237Y436378D01*
X-1726777Y435758D01*
X-1726241Y435345D01*
X-1725704Y435138D01*
X-1725167D01*
X-1724631Y435345D01*
X-1724171Y435655D01*
X-1723787Y436068D01*
G01X-1720961Y440305D02*
X-1720501Y440925D01*
X-1719964Y441235D01*
X-1719351Y441338D01*
X-1718584Y441131D01*
X-1718047Y440615D01*
X-1717894Y439995D01*
X-1717971Y439375D01*
X-1718277Y438858D01*
X-1719811Y437825D01*
X-1720501Y437101D01*
X-1720961Y436068D01*
X-1721114Y435138D01*
X-1717894D01*
G01X-1714607Y435861D02*
X-1714071Y435345D01*
X-1713457Y435138D01*
X-1712844Y435345D01*
X-1712307Y435964D01*
X-1711924Y436895D01*
X-1711771Y437825D01*
Y438961D01*
X-1711924Y439891D01*
X-1712307Y440718D01*
X-1712767Y441131D01*
X-1713304Y441338D01*
X-1713917Y441131D01*
X-1714377Y440718D01*
X-1714684Y440098D01*
X-1714837Y439271D01*
X-1714684Y438548D01*
X-1714301Y437825D01*
X-1713841Y437411D01*
X-1713304Y437308D01*
X-1712691Y437515D01*
X-1712231Y438031D01*
X-1711771Y438961D01*
G01X-1724017Y449821D02*
X-1724477Y450131D01*
X-1725014Y450338D01*
X-1725627D01*
X-1726317Y450028D01*
X-1726854Y449511D01*
X-1727237Y448891D01*
X-1727544Y447858D01*
X-1727621Y446928D01*
X-1727467Y445998D01*
X-1727237Y445378D01*
X-1726777Y444758D01*
X-1726241Y444345D01*
X-1725704Y444138D01*
X-1725167D01*
X-1724631Y444345D01*
X-1724171Y444655D01*
X-1723787Y445068D01*
G01X-1721191Y445378D02*
X-1720731Y444655D01*
X-1720117Y444241D01*
X-1719427Y444138D01*
X-1718814Y444241D01*
X-1718201Y444758D01*
X-1717817Y445378D01*
X-1717741Y445998D01*
X-1717894Y446721D01*
X-1718431Y447238D01*
X-1718967Y447445D01*
X-1719657D01*
G01X-1718967D02*
X-1718507Y447755D01*
X-1718124Y448271D01*
X-1717971Y448891D01*
X-1718124Y449511D01*
X-1718507Y450028D01*
X-1719197Y450338D01*
X-1719887Y450235D01*
X-1720577Y449821D01*
G01X-1713304Y444138D02*
Y450338D01*
X-1714224Y449098D01*
G01Y444138D02*
X-1712384D01*
G01X-1723017Y457821D02*
X-1723477Y458131D01*
X-1724014Y458338D01*
X-1724627D01*
X-1725317Y458028D01*
X-1725854Y457511D01*
X-1726237Y456891D01*
X-1726544Y455858D01*
X-1726621Y454928D01*
X-1726467Y453998D01*
X-1726237Y453378D01*
X-1725777Y452758D01*
X-1725241Y452345D01*
X-1724704Y452138D01*
X-1724167D01*
X-1723631Y452345D01*
X-1723171Y452655D01*
X-1722787Y453068D01*
G01X-1717584Y452138D02*
Y458338D01*
X-1720421Y453895D01*
X-1716587D01*
G01X-1713991Y453378D02*
X-1713531Y452655D01*
X-1712917Y452241D01*
X-1712227Y452138D01*
X-1711614Y452241D01*
X-1711001Y452758D01*
X-1710617Y453378D01*
X-1710541Y453998D01*
X-1710694Y454721D01*
X-1711231Y455238D01*
X-1711767Y455445D01*
X-1712457D01*
G01X-1711767D02*
X-1711307Y455755D01*
X-1710924Y456271D01*
X-1710771Y456891D01*
X-1710924Y457511D01*
X-1711307Y458028D01*
X-1711997Y458338D01*
X-1712687Y458235D01*
X-1713377Y457821D01*
G01X-1724017Y468821D02*
X-1724477Y469131D01*
X-1725014Y469338D01*
X-1725627D01*
X-1726317Y469028D01*
X-1726854Y468511D01*
X-1727237Y467891D01*
X-1727544Y466858D01*
X-1727621Y465928D01*
X-1727467Y464998D01*
X-1727237Y464378D01*
X-1726777Y463758D01*
X-1726241Y463345D01*
X-1725704Y463138D01*
X-1725167D01*
X-1724631Y463345D01*
X-1724171Y463655D01*
X-1723787Y464068D01*
G01X-1719504Y463138D02*
Y469338D01*
X-1720424Y468098D01*
G01Y463138D02*
X-1718584D01*
G01X-1713304D02*
Y469338D01*
X-1714224Y468098D01*
G01Y463138D02*
X-1712384D01*
G01X-1727237Y474338D02*
Y480538D01*
X-1725321D01*
X-1724707Y480228D01*
X-1724324Y479815D01*
X-1724171Y478988D01*
X-1724324Y478161D01*
X-1724784Y477645D01*
X-1725321Y477335D01*
X-1727237D01*
G01X-1725321D02*
X-1724171Y474338D01*
G01X-1721191Y475578D02*
X-1720731Y474855D01*
X-1720117Y474441D01*
X-1719427Y474338D01*
X-1718814Y474441D01*
X-1718201Y474958D01*
X-1717817Y475578D01*
X-1717741Y476198D01*
X-1717894Y476921D01*
X-1718431Y477438D01*
X-1718967Y477645D01*
X-1719657D01*
G01X-1718967D02*
X-1718507Y477955D01*
X-1718124Y478471D01*
X-1717971Y479091D01*
X-1718124Y479711D01*
X-1718507Y480228D01*
X-1719197Y480538D01*
X-1719887Y480435D01*
X-1720577Y480021D01*
G01X-1712384Y474338D02*
Y480538D01*
X-1715221Y476095D01*
X-1711387D01*
G01X-1703687Y-227035D02*
X-1703997Y-227495D01*
X-1704204Y-228032D01*
Y-228645D01*
X-1703894Y-229335D01*
X-1703377Y-229872D01*
X-1702757Y-230255D01*
X-1701724Y-230562D01*
X-1700794Y-230639D01*
X-1699864Y-230485D01*
X-1699244Y-230255D01*
X-1698624Y-229795D01*
X-1698211Y-229259D01*
X-1698004Y-228722D01*
Y-228185D01*
X-1698211Y-227649D01*
X-1698521Y-227189D01*
X-1698934Y-226805D01*
G01X-1698004Y-222522D02*
X-1704204D01*
X-1702964Y-223442D01*
G01X-1698004D02*
Y-221602D01*
G01Y-216475D02*
X-1699347Y-216322D01*
X-1700484Y-216092D01*
X-1701517Y-215785D01*
X-1702654Y-215402D01*
X-1704204Y-214789D01*
Y-217855D01*
G01X-1701604Y247205D02*
X-1707804D01*
Y249121D01*
X-1707494Y249735D01*
X-1707081Y250118D01*
X-1706254Y250271D01*
X-1705427Y250118D01*
X-1704911Y249658D01*
X-1704601Y249121D01*
Y247205D01*
G01Y249121D02*
X-1701604Y250271D01*
G01Y255858D02*
X-1707804D01*
X-1703361Y253021D01*
Y256855D01*
G01X-1702327Y259835D02*
X-1701811Y260371D01*
X-1701604Y260985D01*
X-1701811Y261598D01*
X-1702430Y262135D01*
X-1703361Y262518D01*
X-1704291Y262671D01*
X-1705427D01*
X-1706357Y262518D01*
X-1707184Y262135D01*
X-1707597Y261675D01*
X-1707804Y261138D01*
X-1707597Y260525D01*
X-1707184Y260065D01*
X-1706564Y259758D01*
X-1705737Y259605D01*
X-1705014Y259758D01*
X-1704291Y260141D01*
X-1703877Y260601D01*
X-1703774Y261138D01*
X-1703981Y261751D01*
X-1704497Y262211D01*
X-1705427Y262671D01*
G01X-1707804Y267338D02*
X-1707597Y266725D01*
X-1707081Y266265D01*
X-1706461Y265958D01*
X-1705634Y265728D01*
X-1704704Y265651D01*
X-1703774Y265728D01*
X-1702947Y265958D01*
X-1702327Y266265D01*
X-1701811Y266725D01*
X-1701604Y267338D01*
X-1701811Y267951D01*
X-1702327Y268411D01*
X-1702947Y268718D01*
X-1703774Y268948D01*
X-1704704Y269025D01*
X-1705634Y268948D01*
X-1706461Y268718D01*
X-1707081Y268411D01*
X-1707597Y267951D01*
X-1707804Y267338D01*
G01X-1712319Y278425D02*
X-1712629Y277965D01*
X-1712836Y277428D01*
Y276815D01*
X-1712526Y276125D01*
X-1712009Y275588D01*
X-1711389Y275205D01*
X-1710356Y274898D01*
X-1709426Y274821D01*
X-1708496Y274975D01*
X-1707876Y275205D01*
X-1707256Y275665D01*
X-1706843Y276201D01*
X-1706636Y276738D01*
Y277275D01*
X-1706843Y277811D01*
X-1707153Y278271D01*
X-1707566Y278655D01*
G01X-1707876Y281251D02*
X-1707153Y281711D01*
X-1706739Y282325D01*
X-1706636Y283015D01*
X-1706739Y283628D01*
X-1707256Y284241D01*
X-1707876Y284625D01*
X-1708496Y284701D01*
X-1709219Y284548D01*
X-1709736Y284011D01*
X-1709943Y283475D01*
Y282785D01*
G01Y283475D02*
X-1710253Y283935D01*
X-1710769Y284318D01*
X-1711389Y284471D01*
X-1712009Y284318D01*
X-1712526Y283935D01*
X-1712836Y283245D01*
X-1712733Y282555D01*
X-1712319Y281865D01*
G01X-1712836Y289138D02*
X-1712629Y288525D01*
X-1712113Y288065D01*
X-1711493Y287758D01*
X-1710666Y287528D01*
X-1709736Y287451D01*
X-1708806Y287528D01*
X-1707979Y287758D01*
X-1707359Y288065D01*
X-1706843Y288525D01*
X-1706636Y289138D01*
X-1706843Y289751D01*
X-1707359Y290211D01*
X-1707979Y290518D01*
X-1708806Y290748D01*
X-1709736Y290825D01*
X-1710666Y290748D01*
X-1711493Y290518D01*
X-1712113Y290211D01*
X-1712629Y289751D01*
X-1712836Y289138D01*
G01X-1707359Y294035D02*
X-1706843Y294571D01*
X-1706636Y295185D01*
X-1706843Y295798D01*
X-1707462Y296335D01*
X-1708393Y296718D01*
X-1709323Y296871D01*
X-1710459D01*
X-1711389Y296718D01*
X-1712216Y296335D01*
X-1712629Y295875D01*
X-1712836Y295338D01*
X-1712629Y294725D01*
X-1712216Y294265D01*
X-1711596Y293958D01*
X-1710769Y293805D01*
X-1710046Y293958D01*
X-1709323Y294341D01*
X-1708909Y294801D01*
X-1708806Y295338D01*
X-1709013Y295951D01*
X-1709529Y296411D01*
X-1710459Y296871D01*
G01X-1702433Y281482D02*
X-1700516Y287682D01*
X-1698599Y281482D01*
G01X-1699289Y283652D02*
X-1701743D01*
G01X-1702433Y301482D02*
X-1700516Y307682D01*
X-1698599Y301482D01*
G01X-1699289Y303652D02*
X-1701743D01*
G01X-1705799Y407504D02*
Y401304D01*
X-1702733D01*
G01X-1698219D02*
X-1698066Y402647D01*
X-1697836Y403784D01*
X-1697529Y404817D01*
X-1697146Y405954D01*
X-1696533Y407504D01*
X-1699599D01*
G01X-1706804Y428038D02*
Y434238D01*
X-1707724Y432998D01*
G01Y428038D02*
X-1705884D01*
G01X-1700604D02*
X-1700067Y428141D01*
X-1699454Y428451D01*
X-1699071Y428968D01*
X-1698917Y429691D01*
X-1699071Y430415D01*
X-1699531Y431035D01*
X-1700221Y431345D01*
X-1700987D01*
X-1701447Y431551D01*
X-1701831Y432068D01*
X-1701984Y432791D01*
X-1701754Y433515D01*
X-1701217Y434031D01*
X-1700604Y434238D01*
X-1699991Y434031D01*
X-1699454Y433515D01*
X-1699224Y432791D01*
X-1699377Y432068D01*
X-1699761Y431551D01*
X-1700221Y431345D01*
X-1700987D01*
X-1701677Y431035D01*
X-1702137Y430415D01*
X-1702291Y429691D01*
X-1702137Y428968D01*
X-1701754Y428451D01*
X-1701141Y428141D01*
X-1700604Y428038D01*
G01X-1705804Y452038D02*
Y458238D01*
X-1706724Y456998D01*
G01Y452038D02*
X-1704884D01*
G01X-1701291Y453278D02*
X-1700831Y452555D01*
X-1700217Y452141D01*
X-1699527Y452038D01*
X-1698914Y452141D01*
X-1698301Y452658D01*
X-1697917Y453278D01*
X-1697841Y453898D01*
X-1697994Y454621D01*
X-1698531Y455138D01*
X-1699067Y455345D01*
X-1699757D01*
G01X-1699067D02*
X-1698607Y455655D01*
X-1698224Y456171D01*
X-1698071Y456791D01*
X-1698224Y457411D01*
X-1698607Y457928D01*
X-1699297Y458238D01*
X-1699987Y458135D01*
X-1700677Y457721D01*
G01X-1697804Y460038D02*
Y466238D01*
X-1698724Y464998D01*
G01Y460038D02*
X-1696884D01*
G01X-1693061Y465205D02*
X-1692601Y465825D01*
X-1692064Y466135D01*
X-1691451Y466238D01*
X-1690684Y466031D01*
X-1690147Y465515D01*
X-1689994Y464895D01*
X-1690071Y464275D01*
X-1690377Y463758D01*
X-1691911Y462725D01*
X-1692601Y462001D01*
X-1693061Y460968D01*
X-1693214Y460038D01*
X-1689994D01*
G01X-1696404Y469505D02*
X-1702604D01*
Y471421D01*
X-1702294Y472035D01*
X-1701881Y472418D01*
X-1701054Y472571D01*
X-1700227Y472418D01*
X-1699711Y471958D01*
X-1699401Y471421D01*
Y469505D01*
G01Y471421D02*
X-1696404Y472571D01*
G01X-1701571Y475781D02*
X-1702191Y476241D01*
X-1702501Y476778D01*
X-1702604Y477391D01*
X-1702397Y478158D01*
X-1701881Y478695D01*
X-1701261Y478848D01*
X-1700641Y478771D01*
X-1700124Y478465D01*
X-1699091Y476931D01*
X-1698367Y476241D01*
X-1697334Y475781D01*
X-1696404Y475628D01*
Y478848D01*
G01X-1697127Y482135D02*
X-1696611Y482671D01*
X-1696404Y483285D01*
X-1696611Y483898D01*
X-1697230Y484435D01*
X-1698161Y484818D01*
X-1699091Y484971D01*
X-1700227D01*
X-1701157Y484818D01*
X-1701984Y484435D01*
X-1702397Y483975D01*
X-1702604Y483438D01*
X-1702397Y482825D01*
X-1701984Y482365D01*
X-1701364Y482058D01*
X-1700537Y481905D01*
X-1699814Y482058D01*
X-1699091Y482441D01*
X-1698677Y482901D01*
X-1698574Y483438D01*
X-1698781Y484051D01*
X-1699297Y484511D01*
X-1700227Y484971D01*
G01X-1686564Y-237962D02*
X-1686027Y-237859D01*
X-1685414Y-237549D01*
X-1685031Y-237032D01*
X-1684877Y-236309D01*
X-1685031Y-235585D01*
X-1685491Y-234965D01*
X-1686181Y-234655D01*
X-1686947D01*
X-1687407Y-234449D01*
X-1687791Y-233932D01*
X-1687944Y-233209D01*
X-1687714Y-232485D01*
X-1687177Y-231969D01*
X-1686564Y-231762D01*
X-1685951Y-231969D01*
X-1685414Y-232485D01*
X-1685184Y-233209D01*
X-1685337Y-233932D01*
X-1685721Y-234449D01*
X-1686181Y-234655D01*
X-1686947D01*
X-1687637Y-234965D01*
X-1688097Y-235585D01*
X-1688251Y-236309D01*
X-1688097Y-237032D01*
X-1687714Y-237549D01*
X-1687101Y-237859D01*
X-1686564Y-237962D01*
G01X-1688451Y-207032D02*
X-1687991Y-207549D01*
X-1687454Y-207859D01*
X-1686764Y-207962D01*
X-1686074Y-207755D01*
X-1685537Y-207342D01*
X-1685154Y-206619D01*
X-1685077Y-205792D01*
X-1685231Y-204965D01*
X-1685614Y-204449D01*
X-1686151Y-204035D01*
X-1686687Y-203932D01*
X-1687224Y-204035D01*
X-1687914Y-204449D01*
X-1687684Y-201762D01*
X-1685614D01*
G01X-1695877Y240688D02*
X-1695557Y240271D01*
X-1695184Y240021D01*
X-1694704Y239938D01*
X-1694224Y240105D01*
X-1693851Y240438D01*
X-1693584Y241021D01*
X-1693531Y241688D01*
X-1693637Y242355D01*
X-1693904Y242771D01*
X-1694277Y243105D01*
X-1694651Y243188D01*
X-1695024Y243105D01*
X-1695504Y242771D01*
X-1695344Y244938D01*
X-1693904D01*
G01X-1680579Y254924D02*
Y250481D01*
X-1680272Y249550D01*
X-1679659Y248931D01*
X-1678892Y248724D01*
X-1678125Y248931D01*
X-1677512Y249550D01*
X-1677205Y250481D01*
Y254924D01*
G01X-1671772Y248724D02*
Y254924D01*
X-1674609Y250481D01*
X-1670775D01*
G01X-1666492Y248724D02*
Y254924D01*
X-1667412Y253684D01*
G01Y248724D02*
X-1665572D01*
G01X-1687217Y284585D02*
X-1687677Y284895D01*
X-1688214Y285102D01*
X-1688827D01*
X-1689517Y284792D01*
X-1690054Y284275D01*
X-1690437Y283655D01*
X-1690744Y282622D01*
X-1690821Y281692D01*
X-1690667Y280762D01*
X-1690437Y280142D01*
X-1689977Y279522D01*
X-1689441Y279109D01*
X-1688904Y278902D01*
X-1688367D01*
X-1687831Y279109D01*
X-1687371Y279419D01*
X-1686987Y279832D01*
G01X-1684237Y278902D02*
Y285102D01*
X-1682321D01*
X-1681707Y284792D01*
X-1681324Y284379D01*
X-1681171Y283552D01*
X-1681324Y282725D01*
X-1681784Y282209D01*
X-1682321Y281899D01*
X-1684237D01*
G01X-1682321D02*
X-1681171Y278902D01*
G01X-1677961Y284069D02*
X-1677501Y284689D01*
X-1676964Y284999D01*
X-1676351Y285102D01*
X-1675584Y284895D01*
X-1675047Y284379D01*
X-1674894Y283759D01*
X-1674971Y283139D01*
X-1675277Y282622D01*
X-1676811Y281589D01*
X-1677501Y280865D01*
X-1677961Y279832D01*
X-1678114Y278902D01*
X-1674894D01*
G01X-1687217Y304585D02*
X-1687677Y304895D01*
X-1688214Y305102D01*
X-1688827D01*
X-1689517Y304792D01*
X-1690054Y304275D01*
X-1690437Y303655D01*
X-1690744Y302622D01*
X-1690821Y301692D01*
X-1690667Y300762D01*
X-1690437Y300142D01*
X-1689977Y299522D01*
X-1689441Y299109D01*
X-1688904Y298902D01*
X-1688367D01*
X-1687831Y299109D01*
X-1687371Y299419D01*
X-1686987Y299832D01*
G01X-1684237Y298902D02*
Y305102D01*
X-1682321D01*
X-1681707Y304792D01*
X-1681324Y304379D01*
X-1681171Y303552D01*
X-1681324Y302725D01*
X-1681784Y302209D01*
X-1682321Y301899D01*
X-1684237D01*
G01X-1682321D02*
X-1681171Y298902D01*
G01X-1676504D02*
Y305102D01*
X-1677424Y303862D01*
G01Y298902D02*
X-1675584D01*
G01X-1685588Y437451D02*
X-1681145D01*
X-1680214Y437758D01*
X-1679595Y438371D01*
X-1679388Y439138D01*
X-1679595Y439905D01*
X-1680214Y440518D01*
X-1681145Y440825D01*
X-1685588D01*
G01X-1680318Y443651D02*
X-1679801Y444111D01*
X-1679491Y444648D01*
X-1679388Y445338D01*
X-1679595Y446028D01*
X-1680008Y446565D01*
X-1680731Y446948D01*
X-1681558Y447025D01*
X-1682385Y446871D01*
X-1682901Y446488D01*
X-1683315Y445951D01*
X-1683418Y445415D01*
X-1683315Y444878D01*
X-1682901Y444188D01*
X-1685588Y444418D01*
Y446488D01*
G01X-1685217Y470721D02*
X-1685677Y471031D01*
X-1686214Y471238D01*
X-1686827D01*
X-1687517Y470928D01*
X-1688054Y470411D01*
X-1688437Y469791D01*
X-1688744Y468758D01*
X-1688821Y467828D01*
X-1688667Y466898D01*
X-1688437Y466278D01*
X-1687977Y465658D01*
X-1687441Y465245D01*
X-1686904Y465038D01*
X-1686367D01*
X-1685831Y465245D01*
X-1685371Y465555D01*
X-1684987Y465968D01*
G01X-1682391Y466278D02*
X-1681931Y465555D01*
X-1681317Y465141D01*
X-1680627Y465038D01*
X-1680014Y465141D01*
X-1679401Y465658D01*
X-1679017Y466278D01*
X-1678941Y466898D01*
X-1679094Y467621D01*
X-1679631Y468138D01*
X-1680167Y468345D01*
X-1680857D01*
G01X-1680167D02*
X-1679707Y468655D01*
X-1679324Y469171D01*
X-1679171Y469791D01*
X-1679324Y470411D01*
X-1679707Y470928D01*
X-1680397Y471238D01*
X-1681087Y471135D01*
X-1681777Y470721D01*
G01X-1676191Y466278D02*
X-1675731Y465555D01*
X-1675117Y465141D01*
X-1674427Y465038D01*
X-1673814Y465141D01*
X-1673201Y465658D01*
X-1672817Y466278D01*
X-1672741Y466898D01*
X-1672894Y467621D01*
X-1673431Y468138D01*
X-1673967Y468345D01*
X-1674657D01*
G01X-1673967D02*
X-1673507Y468655D01*
X-1673124Y469171D01*
X-1672971Y469791D01*
X-1673124Y470411D01*
X-1673507Y470928D01*
X-1674197Y471238D01*
X-1674887Y471135D01*
X-1675577Y470721D01*
G01X-1679017Y481821D02*
X-1679477Y482131D01*
X-1680014Y482338D01*
X-1680627D01*
X-1681317Y482028D01*
X-1681854Y481511D01*
X-1682237Y480891D01*
X-1682544Y479858D01*
X-1682621Y478928D01*
X-1682467Y477998D01*
X-1682237Y477378D01*
X-1681777Y476758D01*
X-1681241Y476345D01*
X-1680704Y476138D01*
X-1680167D01*
X-1679631Y476345D01*
X-1679171Y476655D01*
X-1678787Y477068D01*
G01X-1676191Y477378D02*
X-1675731Y476655D01*
X-1675117Y476241D01*
X-1674427Y476138D01*
X-1673814Y476241D01*
X-1673201Y476758D01*
X-1672817Y477378D01*
X-1672741Y477998D01*
X-1672894Y478721D01*
X-1673431Y479238D01*
X-1673967Y479445D01*
X-1674657D01*
G01X-1673967D02*
X-1673507Y479755D01*
X-1673124Y480271D01*
X-1672971Y480891D01*
X-1673124Y481511D01*
X-1673507Y482028D01*
X-1674197Y482338D01*
X-1674887Y482235D01*
X-1675577Y481821D01*
G01X-1668304Y482338D02*
X-1668917Y482131D01*
X-1669377Y481615D01*
X-1669684Y480995D01*
X-1669914Y480168D01*
X-1669991Y479238D01*
X-1669914Y478308D01*
X-1669684Y477481D01*
X-1669377Y476861D01*
X-1668917Y476345D01*
X-1668304Y476138D01*
X-1667691Y476345D01*
X-1667231Y476861D01*
X-1666924Y477481D01*
X-1666694Y478308D01*
X-1666617Y479238D01*
X-1666694Y480168D01*
X-1666924Y480995D01*
X-1667231Y481615D01*
X-1667691Y482131D01*
X-1668304Y482338D01*
G01X-1673317Y231621D02*
X-1673777Y231931D01*
X-1674314Y232138D01*
X-1674927D01*
X-1675617Y231828D01*
X-1676154Y231311D01*
X-1676537Y230691D01*
X-1676844Y229658D01*
X-1676921Y228728D01*
X-1676767Y227798D01*
X-1676537Y227178D01*
X-1676077Y226558D01*
X-1675541Y226145D01*
X-1675004Y225938D01*
X-1674467D01*
X-1673931Y226145D01*
X-1673471Y226455D01*
X-1673087Y226868D01*
G01X-1670491Y227178D02*
X-1670031Y226455D01*
X-1669417Y226041D01*
X-1668727Y225938D01*
X-1668114Y226041D01*
X-1667501Y226558D01*
X-1667117Y227178D01*
X-1667041Y227798D01*
X-1667194Y228521D01*
X-1667731Y229038D01*
X-1668267Y229245D01*
X-1668957D01*
G01X-1668267D02*
X-1667807Y229555D01*
X-1667424Y230071D01*
X-1667271Y230691D01*
X-1667424Y231311D01*
X-1667807Y231828D01*
X-1668497Y232138D01*
X-1669187Y232035D01*
X-1669877Y231621D01*
G01X-1662604Y232138D02*
X-1663217Y231931D01*
X-1663677Y231415D01*
X-1663984Y230795D01*
X-1664214Y229968D01*
X-1664291Y229038D01*
X-1664214Y228108D01*
X-1663984Y227281D01*
X-1663677Y226661D01*
X-1663217Y226145D01*
X-1662604Y225938D01*
X-1661991Y226145D01*
X-1661531Y226661D01*
X-1661224Y227281D01*
X-1660994Y228108D01*
X-1660917Y229038D01*
X-1660994Y229968D01*
X-1661224Y230795D01*
X-1661531Y231415D01*
X-1661991Y231931D01*
X-1662604Y232138D01*
G01X-1656557Y225938D02*
X-1656404Y227281D01*
X-1656174Y228418D01*
X-1655867Y229451D01*
X-1655484Y230588D01*
X-1654871Y232138D01*
X-1657937D01*
G01X-1667017Y293621D02*
X-1667477Y293931D01*
X-1668014Y294138D01*
X-1668627D01*
X-1669317Y293828D01*
X-1669854Y293311D01*
X-1670237Y292691D01*
X-1670544Y291658D01*
X-1670621Y290728D01*
X-1670467Y289798D01*
X-1670237Y289178D01*
X-1669777Y288558D01*
X-1669241Y288145D01*
X-1668704Y287938D01*
X-1668167D01*
X-1667631Y288145D01*
X-1667171Y288455D01*
X-1666787Y288868D01*
G01X-1666017Y314621D02*
X-1666477Y314931D01*
X-1667014Y315138D01*
X-1667627D01*
X-1668317Y314828D01*
X-1668854Y314311D01*
X-1669237Y313691D01*
X-1669544Y312658D01*
X-1669621Y311728D01*
X-1669467Y310798D01*
X-1669237Y310178D01*
X-1668777Y309558D01*
X-1668241Y309145D01*
X-1667704Y308938D01*
X-1667167D01*
X-1666631Y309145D01*
X-1666171Y309455D01*
X-1665787Y309868D01*
G01X-1673017Y406821D02*
X-1673477Y407131D01*
X-1674014Y407338D01*
X-1674627D01*
X-1675317Y407028D01*
X-1675854Y406511D01*
X-1676237Y405891D01*
X-1676544Y404858D01*
X-1676621Y403928D01*
X-1676467Y402998D01*
X-1676237Y402378D01*
X-1675777Y401758D01*
X-1675241Y401345D01*
X-1674704Y401138D01*
X-1674167D01*
X-1673631Y401345D01*
X-1673171Y401655D01*
X-1672787Y402068D01*
G01X-1670191Y402378D02*
X-1669731Y401655D01*
X-1669117Y401241D01*
X-1668427Y401138D01*
X-1667814Y401241D01*
X-1667201Y401758D01*
X-1666817Y402378D01*
X-1666741Y402998D01*
X-1666894Y403721D01*
X-1667431Y404238D01*
X-1667967Y404445D01*
X-1668657D01*
G01X-1667967D02*
X-1667507Y404755D01*
X-1667124Y405271D01*
X-1666971Y405891D01*
X-1667124Y406511D01*
X-1667507Y407028D01*
X-1668197Y407338D01*
X-1668887Y407235D01*
X-1669577Y406821D01*
G01X-1663761Y406305D02*
X-1663301Y406925D01*
X-1662764Y407235D01*
X-1662151Y407338D01*
X-1661384Y407131D01*
X-1660847Y406615D01*
X-1660694Y405995D01*
X-1660771Y405375D01*
X-1661077Y404858D01*
X-1662611Y403825D01*
X-1663301Y403101D01*
X-1663761Y402068D01*
X-1663914Y401138D01*
X-1660694D01*
G01X-1676217Y418721D02*
X-1676677Y419031D01*
X-1677214Y419238D01*
X-1677827D01*
X-1678517Y418928D01*
X-1679054Y418411D01*
X-1679437Y417791D01*
X-1679744Y416758D01*
X-1679821Y415828D01*
X-1679667Y414898D01*
X-1679437Y414278D01*
X-1678977Y413658D01*
X-1678441Y413245D01*
X-1677904Y413038D01*
X-1677367D01*
X-1676831Y413245D01*
X-1676371Y413555D01*
X-1675987Y413968D01*
G01X-1670784Y413038D02*
Y419238D01*
X-1673621Y414795D01*
X-1669787D01*
G01X-1665504Y413038D02*
Y419238D01*
X-1666424Y417998D01*
G01Y413038D02*
X-1664584D01*
G01X-1672391Y421968D02*
X-1671931Y421451D01*
X-1671394Y421141D01*
X-1670704Y421038D01*
X-1670014Y421245D01*
X-1669477Y421658D01*
X-1669094Y422381D01*
X-1669017Y423208D01*
X-1669171Y424035D01*
X-1669554Y424551D01*
X-1670091Y424965D01*
X-1670627Y425068D01*
X-1671164Y424965D01*
X-1671854Y424551D01*
X-1671624Y427238D01*
X-1669554D01*
G01X-1664161Y429621D02*
X-1663624Y430345D01*
X-1663164Y430758D01*
X-1662551Y430965D01*
X-1662014Y430758D01*
X-1661631Y430345D01*
X-1661324Y429725D01*
X-1661247Y429001D01*
X-1661324Y428381D01*
X-1661631Y427761D01*
X-1662091Y427245D01*
X-1662627Y427038D01*
X-1663241Y427245D01*
X-1663777Y427864D01*
X-1664084Y428795D01*
X-1664161Y429828D01*
X-1664007Y431171D01*
X-1663777Y431895D01*
X-1663394Y432618D01*
X-1662857Y433135D01*
X-1662321Y433238D01*
X-1661784Y433031D01*
X-1661401Y432515D01*
G01X-1663857Y450038D02*
X-1663704Y451381D01*
X-1663474Y452518D01*
X-1663167Y453551D01*
X-1662784Y454688D01*
X-1662171Y456238D01*
X-1665237D01*
G01X-1668704Y458038D02*
X-1668167Y458141D01*
X-1667554Y458451D01*
X-1667171Y458968D01*
X-1667017Y459691D01*
X-1667171Y460415D01*
X-1667631Y461035D01*
X-1668321Y461345D01*
X-1669087D01*
X-1669547Y461551D01*
X-1669931Y462068D01*
X-1670084Y462791D01*
X-1669854Y463515D01*
X-1669317Y464031D01*
X-1668704Y464238D01*
X-1668091Y464031D01*
X-1667554Y463515D01*
X-1667324Y462791D01*
X-1667477Y462068D01*
X-1667861Y461551D01*
X-1668321Y461345D01*
X-1669087D01*
X-1669777Y461035D01*
X-1670237Y460415D01*
X-1670391Y459691D01*
X-1670237Y458968D01*
X-1669854Y458451D01*
X-1669241Y458141D01*
X-1668704Y458038D01*
G01X-1652543Y-293159D02*
X-1652236Y-292849D01*
X-1652006Y-292333D01*
X-1651853Y-291609D01*
X-1652006Y-290989D01*
X-1652313Y-290576D01*
X-1652849Y-290266D01*
X-1654919D01*
Y-296466D01*
X-1652389D01*
X-1651853Y-296053D01*
X-1651546Y-295433D01*
X-1651393Y-294709D01*
X-1651546Y-293986D01*
X-1652006Y-293366D01*
X-1652543Y-293159D01*
X-1654919D01*
G01X-1646956Y-296466D02*
Y-290266D01*
X-1647876Y-291506D01*
G01Y-296466D02*
X-1646036D01*
G01X-1660951Y-214862D02*
Y-219305D01*
X-1660644Y-220236D01*
X-1660031Y-220855D01*
X-1659264Y-221062D01*
X-1658497Y-220855D01*
X-1657884Y-220236D01*
X-1657577Y-219305D01*
Y-214862D01*
G01X-1654521Y-215895D02*
X-1654061Y-215275D01*
X-1653524Y-214965D01*
X-1652911Y-214862D01*
X-1652144Y-215069D01*
X-1651607Y-215585D01*
X-1651454Y-216205D01*
X-1651531Y-216825D01*
X-1651837Y-217342D01*
X-1653371Y-218375D01*
X-1654061Y-219099D01*
X-1654521Y-220132D01*
X-1654674Y-221062D01*
X-1651454D01*
G01X-1641636Y230205D02*
X-1647836D01*
Y232121D01*
X-1647526Y232735D01*
X-1647113Y233118D01*
X-1646286Y233271D01*
X-1645459Y233118D01*
X-1644943Y232658D01*
X-1644633Y232121D01*
Y230205D01*
G01Y232121D02*
X-1641636Y233271D01*
G01Y238858D02*
X-1647836D01*
X-1643393Y236021D01*
Y239855D01*
G01X-1641636Y244138D02*
X-1641739Y244675D01*
X-1642049Y245288D01*
X-1642566Y245671D01*
X-1643289Y245825D01*
X-1644013Y245671D01*
X-1644633Y245211D01*
X-1644943Y244521D01*
Y243755D01*
X-1645149Y243295D01*
X-1645666Y242911D01*
X-1646389Y242758D01*
X-1647113Y242988D01*
X-1647629Y243525D01*
X-1647836Y244138D01*
X-1647629Y244751D01*
X-1647113Y245288D01*
X-1646389Y245518D01*
X-1645666Y245365D01*
X-1645149Y244981D01*
X-1644943Y244521D01*
Y243755D01*
X-1644633Y243065D01*
X-1644013Y242605D01*
X-1643289Y242451D01*
X-1642566Y242605D01*
X-1642049Y242988D01*
X-1641739Y243601D01*
X-1641636Y244138D01*
G01Y250185D02*
X-1642979Y250338D01*
X-1644116Y250568D01*
X-1645149Y250875D01*
X-1646286Y251258D01*
X-1647836Y251871D01*
Y248805D01*
G01X-1656717Y241021D02*
X-1656344Y241605D01*
X-1656024Y241938D01*
X-1655597Y242105D01*
X-1655224Y241938D01*
X-1654957Y241605D01*
X-1654744Y241105D01*
X-1654691Y240521D01*
X-1654744Y240021D01*
X-1654957Y239521D01*
X-1655277Y239105D01*
X-1655651Y238938D01*
X-1656077Y239105D01*
X-1656451Y239605D01*
X-1656664Y240355D01*
X-1656717Y241188D01*
X-1656611Y242271D01*
X-1656451Y242855D01*
X-1656184Y243438D01*
X-1655811Y243855D01*
X-1655437Y243938D01*
X-1655064Y243771D01*
X-1654797Y243355D01*
G01X-1643317Y260621D02*
X-1643777Y260931D01*
X-1644314Y261138D01*
X-1644927D01*
X-1645617Y260828D01*
X-1646154Y260311D01*
X-1646537Y259691D01*
X-1646844Y258658D01*
X-1646921Y257728D01*
X-1646767Y256798D01*
X-1646537Y256178D01*
X-1646077Y255558D01*
X-1645541Y255145D01*
X-1645004Y254938D01*
X-1644467D01*
X-1643931Y255145D01*
X-1643471Y255455D01*
X-1643087Y255868D01*
G01X-1640491Y256178D02*
X-1640031Y255455D01*
X-1639417Y255041D01*
X-1638727Y254938D01*
X-1638114Y255041D01*
X-1637501Y255558D01*
X-1637117Y256178D01*
X-1637041Y256798D01*
X-1637194Y257521D01*
X-1637731Y258038D01*
X-1638267Y258245D01*
X-1638957D01*
G01X-1638267D02*
X-1637807Y258555D01*
X-1637424Y259071D01*
X-1637271Y259691D01*
X-1637424Y260311D01*
X-1637807Y260828D01*
X-1638497Y261138D01*
X-1639187Y261035D01*
X-1639877Y260621D01*
G01X-1632604Y261138D02*
X-1633217Y260931D01*
X-1633677Y260415D01*
X-1633984Y259795D01*
X-1634214Y258968D01*
X-1634291Y258038D01*
X-1634214Y257108D01*
X-1633984Y256281D01*
X-1633677Y255661D01*
X-1633217Y255145D01*
X-1632604Y254938D01*
X-1631991Y255145D01*
X-1631531Y255661D01*
X-1631224Y256281D01*
X-1630994Y257108D01*
X-1630917Y258038D01*
X-1630994Y258968D01*
X-1631224Y259795D01*
X-1631531Y260415D01*
X-1631991Y260931D01*
X-1632604Y261138D01*
G01X-1625484Y254938D02*
Y261138D01*
X-1628321Y256695D01*
X-1624487D01*
G01X-1643317Y272621D02*
X-1643777Y272931D01*
X-1644314Y273138D01*
X-1644927D01*
X-1645617Y272828D01*
X-1646154Y272311D01*
X-1646537Y271691D01*
X-1646844Y270658D01*
X-1646921Y269728D01*
X-1646767Y268798D01*
X-1646537Y268178D01*
X-1646077Y267558D01*
X-1645541Y267145D01*
X-1645004Y266938D01*
X-1644467D01*
X-1643931Y267145D01*
X-1643471Y267455D01*
X-1643087Y267868D01*
G01X-1640491Y268178D02*
X-1640031Y267455D01*
X-1639417Y267041D01*
X-1638727Y266938D01*
X-1638114Y267041D01*
X-1637501Y267558D01*
X-1637117Y268178D01*
X-1637041Y268798D01*
X-1637194Y269521D01*
X-1637731Y270038D01*
X-1638267Y270245D01*
X-1638957D01*
G01X-1638267D02*
X-1637807Y270555D01*
X-1637424Y271071D01*
X-1637271Y271691D01*
X-1637424Y272311D01*
X-1637807Y272828D01*
X-1638497Y273138D01*
X-1639187Y273035D01*
X-1639877Y272621D01*
G01X-1632604Y273138D02*
X-1633217Y272931D01*
X-1633677Y272415D01*
X-1633984Y271795D01*
X-1634214Y270968D01*
X-1634291Y270038D01*
X-1634214Y269108D01*
X-1633984Y268281D01*
X-1633677Y267661D01*
X-1633217Y267145D01*
X-1632604Y266938D01*
X-1631991Y267145D01*
X-1631531Y267661D01*
X-1631224Y268281D01*
X-1630994Y269108D01*
X-1630917Y270038D01*
X-1630994Y270968D01*
X-1631224Y271795D01*
X-1631531Y272415D01*
X-1631991Y272931D01*
X-1632604Y273138D01*
G01X-1626404D02*
X-1627017Y272931D01*
X-1627477Y272415D01*
X-1627784Y271795D01*
X-1628014Y270968D01*
X-1628091Y270038D01*
X-1628014Y269108D01*
X-1627784Y268281D01*
X-1627477Y267661D01*
X-1627017Y267145D01*
X-1626404Y266938D01*
X-1625791Y267145D01*
X-1625331Y267661D01*
X-1625024Y268281D01*
X-1624794Y269108D01*
X-1624717Y270038D01*
X-1624794Y270968D01*
X-1625024Y271795D01*
X-1625331Y272415D01*
X-1625791Y272931D01*
X-1626404Y273138D01*
G01X-1658904Y262938D02*
Y267938D01*
X-1659544Y266938D01*
G01Y262938D02*
X-1658264D01*
G01X-1654504Y267938D02*
X-1654931Y267771D01*
X-1655251Y267355D01*
X-1655464Y266855D01*
X-1655624Y266188D01*
X-1655677Y265438D01*
X-1655624Y264688D01*
X-1655464Y264021D01*
X-1655251Y263521D01*
X-1654931Y263105D01*
X-1654504Y262938D01*
X-1654077Y263105D01*
X-1653757Y263521D01*
X-1653544Y264021D01*
X-1653384Y264688D01*
X-1653331Y265438D01*
X-1653384Y266188D01*
X-1653544Y266855D01*
X-1653757Y267355D01*
X-1654077Y267771D01*
X-1654504Y267938D01*
G01X-1661804Y273305D02*
X-1655604D01*
Y276371D01*
G01X-1660771Y279581D02*
X-1661391Y280041D01*
X-1661701Y280578D01*
X-1661804Y281191D01*
X-1661597Y281958D01*
X-1661081Y282495D01*
X-1660461Y282648D01*
X-1659841Y282571D01*
X-1659324Y282265D01*
X-1658291Y280731D01*
X-1657567Y280041D01*
X-1656534Y279581D01*
X-1655604Y279428D01*
Y282648D01*
G01X-1656844Y285551D02*
X-1656121Y286011D01*
X-1655707Y286625D01*
X-1655604Y287315D01*
X-1655707Y287928D01*
X-1656224Y288541D01*
X-1656844Y288925D01*
X-1657464Y289001D01*
X-1658187Y288848D01*
X-1658704Y288311D01*
X-1658911Y287775D01*
Y287085D01*
G01Y287775D02*
X-1659221Y288235D01*
X-1659737Y288618D01*
X-1660357Y288771D01*
X-1660977Y288618D01*
X-1661494Y288235D01*
X-1661804Y287545D01*
X-1661701Y286855D01*
X-1661287Y286165D01*
G01X-1650317Y290653D02*
X-1650777Y290963D01*
X-1651314Y291170D01*
X-1651927D01*
X-1652617Y290860D01*
X-1653154Y290343D01*
X-1653537Y289723D01*
X-1653844Y288690D01*
X-1653921Y287760D01*
X-1653767Y286830D01*
X-1653537Y286210D01*
X-1653077Y285590D01*
X-1652541Y285177D01*
X-1652004Y284970D01*
X-1651467D01*
X-1650931Y285177D01*
X-1650471Y285487D01*
X-1650087Y285900D01*
G01X-1647261Y290137D02*
X-1646801Y290757D01*
X-1646264Y291067D01*
X-1645651Y291170D01*
X-1644884Y290963D01*
X-1644347Y290447D01*
X-1644194Y289827D01*
X-1644271Y289207D01*
X-1644577Y288690D01*
X-1646111Y287657D01*
X-1646801Y286933D01*
X-1647261Y285900D01*
X-1647414Y284970D01*
X-1644194D01*
G01X-1640907Y285693D02*
X-1640371Y285177D01*
X-1639757Y284970D01*
X-1639144Y285177D01*
X-1638607Y285796D01*
X-1638224Y286727D01*
X-1638071Y287657D01*
Y288793D01*
X-1638224Y289723D01*
X-1638607Y290550D01*
X-1639067Y290963D01*
X-1639604Y291170D01*
X-1640217Y290963D01*
X-1640677Y290550D01*
X-1640984Y289930D01*
X-1641137Y289103D01*
X-1640984Y288380D01*
X-1640601Y287657D01*
X-1640141Y287243D01*
X-1639604Y287140D01*
X-1638991Y287347D01*
X-1638531Y287863D01*
X-1638071Y288793D01*
G01X-1633404Y284970D02*
X-1632867Y285073D01*
X-1632254Y285383D01*
X-1631871Y285900D01*
X-1631717Y286623D01*
X-1631871Y287347D01*
X-1632331Y287967D01*
X-1633021Y288277D01*
X-1633787D01*
X-1634247Y288483D01*
X-1634631Y289000D01*
X-1634784Y289723D01*
X-1634554Y290447D01*
X-1634017Y290963D01*
X-1633404Y291170D01*
X-1632791Y290963D01*
X-1632254Y290447D01*
X-1632024Y289723D01*
X-1632177Y289000D01*
X-1632561Y288483D01*
X-1633021Y288277D01*
X-1633787D01*
X-1634477Y287967D01*
X-1634937Y287347D01*
X-1635091Y286623D01*
X-1634937Y285900D01*
X-1634554Y285383D01*
X-1633941Y285073D01*
X-1633404Y284970D01*
G01X-1655317Y304653D02*
X-1655777Y304963D01*
X-1656314Y305170D01*
X-1656927D01*
X-1657617Y304860D01*
X-1658154Y304343D01*
X-1658537Y303723D01*
X-1658844Y302690D01*
X-1658921Y301760D01*
X-1658767Y300830D01*
X-1658537Y300210D01*
X-1658077Y299590D01*
X-1657541Y299177D01*
X-1657004Y298970D01*
X-1656467D01*
X-1655931Y299177D01*
X-1655471Y299487D01*
X-1655087Y299900D01*
G01X-1652261Y304137D02*
X-1651801Y304757D01*
X-1651264Y305067D01*
X-1650651Y305170D01*
X-1649884Y304963D01*
X-1649347Y304447D01*
X-1649194Y303827D01*
X-1649271Y303207D01*
X-1649577Y302690D01*
X-1651111Y301657D01*
X-1651801Y300933D01*
X-1652261Y299900D01*
X-1652414Y298970D01*
X-1649194D01*
G01X-1644604D02*
X-1644067Y299073D01*
X-1643454Y299383D01*
X-1643071Y299900D01*
X-1642917Y300623D01*
X-1643071Y301347D01*
X-1643531Y301967D01*
X-1644221Y302277D01*
X-1644987D01*
X-1645447Y302483D01*
X-1645831Y303000D01*
X-1645984Y303723D01*
X-1645754Y304447D01*
X-1645217Y304963D01*
X-1644604Y305170D01*
X-1643991Y304963D01*
X-1643454Y304447D01*
X-1643224Y303723D01*
X-1643377Y303000D01*
X-1643761Y302483D01*
X-1644221Y302277D01*
X-1644987D01*
X-1645677Y301967D01*
X-1646137Y301347D01*
X-1646291Y300623D01*
X-1646137Y299900D01*
X-1645754Y299383D01*
X-1645141Y299073D01*
X-1644604Y298970D01*
G01X-1637484D02*
Y305170D01*
X-1640321Y300727D01*
X-1636487D01*
G01X-1652704Y439038D02*
Y445238D01*
X-1653624Y443998D01*
G01Y439038D02*
X-1651784D01*
G01X-1625784Y-204962D02*
Y-198762D01*
X-1628621Y-203205D01*
X-1624787D01*
G01X-1637319Y233425D02*
X-1637629Y232965D01*
X-1637836Y232428D01*
Y231815D01*
X-1637526Y231125D01*
X-1637009Y230588D01*
X-1636389Y230205D01*
X-1635356Y229898D01*
X-1634426Y229821D01*
X-1633496Y229975D01*
X-1632876Y230205D01*
X-1632256Y230665D01*
X-1631843Y231201D01*
X-1631636Y231738D01*
Y232275D01*
X-1631843Y232811D01*
X-1632153Y233271D01*
X-1632566Y233655D01*
G01X-1632876Y236251D02*
X-1632153Y236711D01*
X-1631739Y237325D01*
X-1631636Y238015D01*
X-1631739Y238628D01*
X-1632256Y239241D01*
X-1632876Y239625D01*
X-1633496Y239701D01*
X-1634219Y239548D01*
X-1634736Y239011D01*
X-1634943Y238475D01*
Y237785D01*
G01Y238475D02*
X-1635253Y238935D01*
X-1635769Y239318D01*
X-1636389Y239471D01*
X-1637009Y239318D01*
X-1637526Y238935D01*
X-1637836Y238245D01*
X-1637733Y237555D01*
X-1637319Y236865D01*
G01X-1637836Y244138D02*
X-1637629Y243525D01*
X-1637113Y243065D01*
X-1636493Y242758D01*
X-1635666Y242528D01*
X-1634736Y242451D01*
X-1633806Y242528D01*
X-1632979Y242758D01*
X-1632359Y243065D01*
X-1631843Y243525D01*
X-1631636Y244138D01*
X-1631843Y244751D01*
X-1632359Y245211D01*
X-1632979Y245518D01*
X-1633806Y245748D01*
X-1634736Y245825D01*
X-1635666Y245748D01*
X-1636493Y245518D01*
X-1637113Y245211D01*
X-1637629Y244751D01*
X-1637836Y244138D01*
G01X-1636803Y248881D02*
X-1637423Y249341D01*
X-1637733Y249878D01*
X-1637836Y250491D01*
X-1637629Y251258D01*
X-1637113Y251795D01*
X-1636493Y251948D01*
X-1635873Y251871D01*
X-1635356Y251565D01*
X-1634323Y250031D01*
X-1633599Y249341D01*
X-1632566Y248881D01*
X-1631636Y248728D01*
Y251948D01*
G01X-1608064Y-239595D02*
X-1614264D01*
Y-237679D01*
X-1613954Y-237065D01*
X-1613541Y-236682D01*
X-1612714Y-236529D01*
X-1611887Y-236682D01*
X-1611371Y-237142D01*
X-1611061Y-237679D01*
Y-239595D01*
G01Y-237679D02*
X-1608064Y-236529D01*
G01X-1609304Y-233549D02*
X-1608581Y-233089D01*
X-1608167Y-232475D01*
X-1608064Y-231785D01*
X-1608167Y-231172D01*
X-1608684Y-230559D01*
X-1609304Y-230175D01*
X-1609924Y-230099D01*
X-1610647Y-230252D01*
X-1611164Y-230789D01*
X-1611371Y-231325D01*
Y-232015D01*
G01Y-231325D02*
X-1611681Y-230865D01*
X-1612197Y-230482D01*
X-1612817Y-230329D01*
X-1613437Y-230482D01*
X-1613954Y-230865D01*
X-1614264Y-231555D01*
X-1614161Y-232245D01*
X-1613747Y-232935D01*
G01X-1608994Y-227349D02*
X-1608477Y-226889D01*
X-1608167Y-226352D01*
X-1608064Y-225662D01*
X-1608271Y-224972D01*
X-1608684Y-224435D01*
X-1609407Y-224052D01*
X-1610234Y-223975D01*
X-1611061Y-224129D01*
X-1611577Y-224512D01*
X-1611991Y-225049D01*
X-1612094Y-225585D01*
X-1611991Y-226122D01*
X-1611577Y-226812D01*
X-1614264Y-226582D01*
Y-224512D01*
G01X-1608064Y-218542D02*
X-1614264D01*
X-1609821Y-221379D01*
Y-217545D01*
G01X-1615804Y291805D02*
X-1622004D01*
Y293721D01*
X-1621694Y294335D01*
X-1621281Y294718D01*
X-1620454Y294871D01*
X-1619627Y294718D01*
X-1619111Y294258D01*
X-1618801Y293721D01*
Y291805D01*
G01Y293721D02*
X-1615804Y294871D01*
G01Y300458D02*
X-1622004D01*
X-1617561Y297621D01*
Y301455D01*
G01X-1620971Y304281D02*
X-1621591Y304741D01*
X-1621901Y305278D01*
X-1622004Y305891D01*
X-1621797Y306658D01*
X-1621281Y307195D01*
X-1620661Y307348D01*
X-1620041Y307271D01*
X-1619524Y306965D01*
X-1618491Y305431D01*
X-1617767Y304741D01*
X-1616734Y304281D01*
X-1615804Y304128D01*
Y307348D01*
G01X-1620971Y310481D02*
X-1621591Y310941D01*
X-1621901Y311478D01*
X-1622004Y312091D01*
X-1621797Y312858D01*
X-1621281Y313395D01*
X-1620661Y313548D01*
X-1620041Y313471D01*
X-1619524Y313165D01*
X-1618491Y311631D01*
X-1617767Y310941D01*
X-1616734Y310481D01*
X-1615804Y310328D01*
Y313548D01*
G01X-1623137Y447338D02*
Y441138D01*
X-1620071D01*
G01X-1615404D02*
Y447338D01*
X-1616324Y446098D01*
G01Y441138D02*
X-1614484D01*
G01X-1598064Y-236495D02*
X-1604264D01*
Y-234579D01*
X-1603954Y-233965D01*
X-1603541Y-233582D01*
X-1602714Y-233429D01*
X-1601887Y-233582D01*
X-1601371Y-234042D01*
X-1601061Y-234579D01*
Y-236495D01*
G01Y-234579D02*
X-1598064Y-233429D01*
G01X-1603231Y-230219D02*
X-1603851Y-229759D01*
X-1604161Y-229222D01*
X-1604264Y-228609D01*
X-1604057Y-227842D01*
X-1603541Y-227305D01*
X-1602921Y-227152D01*
X-1602301Y-227229D01*
X-1601784Y-227535D01*
X-1600751Y-229069D01*
X-1600027Y-229759D01*
X-1598994Y-230219D01*
X-1598064Y-230372D01*
Y-227152D01*
G01X-1598994Y-224249D02*
X-1598477Y-223789D01*
X-1598167Y-223252D01*
X-1598064Y-222562D01*
X-1598271Y-221872D01*
X-1598684Y-221335D01*
X-1599407Y-220952D01*
X-1600234Y-220875D01*
X-1601061Y-221029D01*
X-1601577Y-221412D01*
X-1601991Y-221949D01*
X-1602094Y-222485D01*
X-1601991Y-223022D01*
X-1601577Y-223712D01*
X-1604264Y-223482D01*
Y-221412D01*
G01X-1593068Y228605D02*
X-1599268D01*
Y230521D01*
X-1598958Y231135D01*
X-1598545Y231518D01*
X-1597718Y231671D01*
X-1596891Y231518D01*
X-1596375Y231058D01*
X-1596065Y230521D01*
Y228605D01*
G01Y230521D02*
X-1593068Y231671D01*
G01Y237258D02*
X-1599268D01*
X-1594825Y234421D01*
Y238255D01*
G01X-1599268Y242538D02*
X-1599061Y241925D01*
X-1598545Y241465D01*
X-1597925Y241158D01*
X-1597098Y240928D01*
X-1596168Y240851D01*
X-1595238Y240928D01*
X-1594411Y241158D01*
X-1593791Y241465D01*
X-1593275Y241925D01*
X-1593068Y242538D01*
X-1593275Y243151D01*
X-1593791Y243611D01*
X-1594411Y243918D01*
X-1595238Y244148D01*
X-1596168Y244225D01*
X-1597098Y244148D01*
X-1597925Y243918D01*
X-1598545Y243611D01*
X-1599061Y243151D01*
X-1599268Y242538D01*
G01X-1593068Y248738D02*
X-1593171Y249275D01*
X-1593481Y249888D01*
X-1593998Y250271D01*
X-1594721Y250425D01*
X-1595445Y250271D01*
X-1596065Y249811D01*
X-1596375Y249121D01*
Y248355D01*
X-1596581Y247895D01*
X-1597098Y247511D01*
X-1597821Y247358D01*
X-1598545Y247588D01*
X-1599061Y248125D01*
X-1599268Y248738D01*
X-1599061Y249351D01*
X-1598545Y249888D01*
X-1597821Y250118D01*
X-1597098Y249965D01*
X-1596581Y249581D01*
X-1596375Y249121D01*
Y248355D01*
X-1596065Y247665D01*
X-1595445Y247205D01*
X-1594721Y247051D01*
X-1593998Y247205D01*
X-1593481Y247588D01*
X-1593171Y248201D01*
X-1593068Y248738D01*
G01X-1598391Y256868D02*
X-1597931Y256351D01*
X-1597394Y256041D01*
X-1596704Y255938D01*
X-1596014Y256145D01*
X-1595477Y256558D01*
X-1595094Y257281D01*
X-1595017Y258108D01*
X-1595171Y258935D01*
X-1595554Y259451D01*
X-1596091Y259865D01*
X-1596627Y259968D01*
X-1597164Y259865D01*
X-1597854Y259451D01*
X-1597624Y262138D01*
X-1595554D01*
G01X-1609804Y293738D02*
X-1603604D01*
G01X-1609804Y291975D02*
Y295501D01*
G01X-1603604Y298405D02*
X-1609804D01*
Y300245D01*
X-1609494Y300858D01*
X-1608771Y301318D01*
X-1607944Y301471D01*
X-1607117Y301318D01*
X-1606497Y300935D01*
X-1606187Y300245D01*
Y298405D01*
G01X-1608771Y304681D02*
X-1609391Y305141D01*
X-1609701Y305678D01*
X-1609804Y306291D01*
X-1609597Y307058D01*
X-1609081Y307595D01*
X-1608461Y307748D01*
X-1607841Y307671D01*
X-1607324Y307365D01*
X-1606291Y305831D01*
X-1605567Y305141D01*
X-1604534Y304681D01*
X-1603604Y304528D01*
Y307748D01*
G01X-1604844Y310651D02*
X-1604121Y311111D01*
X-1603707Y311725D01*
X-1603604Y312415D01*
X-1603707Y313028D01*
X-1604224Y313641D01*
X-1604844Y314025D01*
X-1605464Y314101D01*
X-1606187Y313948D01*
X-1606704Y313411D01*
X-1606911Y312875D01*
Y312185D01*
G01Y312875D02*
X-1607221Y313335D01*
X-1607737Y313718D01*
X-1608357Y313871D01*
X-1608977Y313718D01*
X-1609494Y313335D01*
X-1609804Y312645D01*
X-1609701Y311955D01*
X-1609287Y311265D01*
G01X-1594784Y306938D02*
Y313138D01*
X-1597621Y308695D01*
X-1593787D01*
G01X-1583287Y-235575D02*
X-1583597Y-236035D01*
X-1583804Y-236572D01*
Y-237185D01*
X-1583494Y-237875D01*
X-1582977Y-238412D01*
X-1582357Y-238795D01*
X-1581324Y-239102D01*
X-1580394Y-239179D01*
X-1579464Y-239025D01*
X-1578844Y-238795D01*
X-1578224Y-238335D01*
X-1577811Y-237799D01*
X-1577604Y-237262D01*
Y-236725D01*
X-1577811Y-236189D01*
X-1578121Y-235729D01*
X-1578534Y-235345D01*
G01X-1582771Y-232519D02*
X-1583391Y-232059D01*
X-1583701Y-231522D01*
X-1583804Y-230909D01*
X-1583597Y-230142D01*
X-1583081Y-229605D01*
X-1582461Y-229452D01*
X-1581841Y-229529D01*
X-1581324Y-229835D01*
X-1580291Y-231369D01*
X-1579567Y-232059D01*
X-1578534Y-232519D01*
X-1577604Y-232672D01*
Y-229452D01*
G01Y-224862D02*
X-1577707Y-224325D01*
X-1578017Y-223712D01*
X-1578534Y-223329D01*
X-1579257Y-223175D01*
X-1579981Y-223329D01*
X-1580601Y-223789D01*
X-1580911Y-224479D01*
Y-225245D01*
X-1581117Y-225705D01*
X-1581634Y-226089D01*
X-1582357Y-226242D01*
X-1583081Y-226012D01*
X-1583597Y-225475D01*
X-1583804Y-224862D01*
X-1583597Y-224249D01*
X-1583081Y-223712D01*
X-1582357Y-223482D01*
X-1581634Y-223635D01*
X-1581117Y-224019D01*
X-1580911Y-224479D01*
Y-225245D01*
X-1580601Y-225935D01*
X-1579981Y-226395D01*
X-1579257Y-226549D01*
X-1578534Y-226395D01*
X-1578017Y-226012D01*
X-1577707Y-225399D01*
X-1577604Y-224862D01*
G01Y-218662D02*
X-1577707Y-218125D01*
X-1578017Y-217512D01*
X-1578534Y-217129D01*
X-1579257Y-216975D01*
X-1579981Y-217129D01*
X-1580601Y-217589D01*
X-1580911Y-218279D01*
Y-219045D01*
X-1581117Y-219505D01*
X-1581634Y-219889D01*
X-1582357Y-220042D01*
X-1583081Y-219812D01*
X-1583597Y-219275D01*
X-1583804Y-218662D01*
X-1583597Y-218049D01*
X-1583081Y-217512D01*
X-1582357Y-217282D01*
X-1581634Y-217435D01*
X-1581117Y-217819D01*
X-1580911Y-218279D01*
Y-219045D01*
X-1580601Y-219735D01*
X-1579981Y-220195D01*
X-1579257Y-220349D01*
X-1578534Y-220195D01*
X-1578017Y-219812D01*
X-1577707Y-219199D01*
X-1577604Y-218662D01*
G01X-1592287Y-235575D02*
X-1592597Y-236035D01*
X-1592804Y-236572D01*
Y-237185D01*
X-1592494Y-237875D01*
X-1591977Y-238412D01*
X-1591357Y-238795D01*
X-1590324Y-239102D01*
X-1589394Y-239179D01*
X-1588464Y-239025D01*
X-1587844Y-238795D01*
X-1587224Y-238335D01*
X-1586811Y-237799D01*
X-1586604Y-237262D01*
Y-236725D01*
X-1586811Y-236189D01*
X-1587121Y-235729D01*
X-1587534Y-235345D01*
G01X-1591771Y-232519D02*
X-1592391Y-232059D01*
X-1592701Y-231522D01*
X-1592804Y-230909D01*
X-1592597Y-230142D01*
X-1592081Y-229605D01*
X-1591461Y-229452D01*
X-1590841Y-229529D01*
X-1590324Y-229835D01*
X-1589291Y-231369D01*
X-1588567Y-232059D01*
X-1587534Y-232519D01*
X-1586604Y-232672D01*
Y-229452D01*
G01Y-224862D02*
X-1586707Y-224325D01*
X-1587017Y-223712D01*
X-1587534Y-223329D01*
X-1588257Y-223175D01*
X-1588981Y-223329D01*
X-1589601Y-223789D01*
X-1589911Y-224479D01*
Y-225245D01*
X-1590117Y-225705D01*
X-1590634Y-226089D01*
X-1591357Y-226242D01*
X-1592081Y-226012D01*
X-1592597Y-225475D01*
X-1592804Y-224862D01*
X-1592597Y-224249D01*
X-1592081Y-223712D01*
X-1591357Y-223482D01*
X-1590634Y-223635D01*
X-1590117Y-224019D01*
X-1589911Y-224479D01*
Y-225245D01*
X-1589601Y-225935D01*
X-1588981Y-226395D01*
X-1588257Y-226549D01*
X-1587534Y-226395D01*
X-1587017Y-226012D01*
X-1586707Y-225399D01*
X-1586604Y-224862D01*
G01Y-218815D02*
X-1587947Y-218662D01*
X-1589084Y-218432D01*
X-1590117Y-218125D01*
X-1591254Y-217742D01*
X-1592804Y-217129D01*
Y-220195D01*
G01X-1575068Y228605D02*
X-1581268D01*
Y230521D01*
X-1580958Y231135D01*
X-1580545Y231518D01*
X-1579718Y231671D01*
X-1578891Y231518D01*
X-1578375Y231058D01*
X-1578065Y230521D01*
Y228605D01*
G01Y230521D02*
X-1575068Y231671D01*
G01Y237258D02*
X-1581268D01*
X-1576825Y234421D01*
Y238255D01*
G01X-1575068Y242538D02*
X-1581268D01*
X-1580028Y241618D01*
G01X-1575068D02*
Y243458D01*
G01Y248738D02*
X-1575171Y249275D01*
X-1575481Y249888D01*
X-1575998Y250271D01*
X-1576721Y250425D01*
X-1577445Y250271D01*
X-1578065Y249811D01*
X-1578375Y249121D01*
Y248355D01*
X-1578581Y247895D01*
X-1579098Y247511D01*
X-1579821Y247358D01*
X-1580545Y247588D01*
X-1581061Y248125D01*
X-1581268Y248738D01*
X-1581061Y249351D01*
X-1580545Y249888D01*
X-1579821Y250118D01*
X-1579098Y249965D01*
X-1578581Y249581D01*
X-1578375Y249121D01*
Y248355D01*
X-1578065Y247665D01*
X-1577445Y247205D01*
X-1576721Y247051D01*
X-1575998Y247205D01*
X-1575481Y247588D01*
X-1575171Y248201D01*
X-1575068Y248738D01*
G01X-1584068Y228605D02*
X-1590268D01*
Y230521D01*
X-1589958Y231135D01*
X-1589545Y231518D01*
X-1588718Y231671D01*
X-1587891Y231518D01*
X-1587375Y231058D01*
X-1587065Y230521D01*
Y228605D01*
G01Y230521D02*
X-1584068Y231671D01*
G01Y237258D02*
X-1590268D01*
X-1585825Y234421D01*
Y238255D01*
G01X-1584068Y242538D02*
X-1590268D01*
X-1589028Y241618D01*
G01X-1584068D02*
Y243458D01*
G01X-1589235Y247281D02*
X-1589855Y247741D01*
X-1590165Y248278D01*
X-1590268Y248891D01*
X-1590061Y249658D01*
X-1589545Y250195D01*
X-1588925Y250348D01*
X-1588305Y250271D01*
X-1587788Y249965D01*
X-1586755Y248431D01*
X-1586031Y247741D01*
X-1584998Y247281D01*
X-1584068Y247128D01*
Y250348D01*
G01X-1587804Y279151D02*
X-1583361D01*
X-1582430Y279458D01*
X-1581811Y280071D01*
X-1581604Y280838D01*
X-1581811Y281605D01*
X-1582430Y282218D01*
X-1583361Y282525D01*
X-1587804D01*
G01X-1582844Y285351D02*
X-1582121Y285811D01*
X-1581707Y286425D01*
X-1581604Y287115D01*
X-1581707Y287728D01*
X-1582224Y288341D01*
X-1582844Y288725D01*
X-1583464Y288801D01*
X-1584187Y288648D01*
X-1584704Y288111D01*
X-1584911Y287575D01*
Y286885D01*
G01Y287575D02*
X-1585221Y288035D01*
X-1585737Y288418D01*
X-1586357Y288571D01*
X-1586977Y288418D01*
X-1587494Y288035D01*
X-1587804Y287345D01*
X-1587701Y286655D01*
X-1587287Y285965D01*
G01X-1582534Y291551D02*
X-1582017Y292011D01*
X-1581707Y292548D01*
X-1581604Y293238D01*
X-1581811Y293928D01*
X-1582224Y294465D01*
X-1582947Y294848D01*
X-1583774Y294925D01*
X-1584601Y294771D01*
X-1585117Y294388D01*
X-1585531Y293851D01*
X-1585634Y293315D01*
X-1585531Y292778D01*
X-1585117Y292088D01*
X-1587804Y292318D01*
Y294388D01*
G01X-1578087Y417725D02*
X-1578397Y417265D01*
X-1578604Y416728D01*
Y416115D01*
X-1578294Y415425D01*
X-1577777Y414888D01*
X-1577157Y414505D01*
X-1576124Y414198D01*
X-1575194Y414121D01*
X-1574264Y414275D01*
X-1573644Y414505D01*
X-1573024Y414965D01*
X-1572611Y415501D01*
X-1572404Y416038D01*
Y416575D01*
X-1572611Y417111D01*
X-1572921Y417571D01*
X-1573334Y417955D01*
G01X-1572404Y422238D02*
X-1578604D01*
X-1577364Y421318D01*
G01X-1572404D02*
Y423158D01*
G01X-1577571Y426981D02*
X-1578191Y427441D01*
X-1578501Y427978D01*
X-1578604Y428591D01*
X-1578397Y429358D01*
X-1577881Y429895D01*
X-1577261Y430048D01*
X-1576641Y429971D01*
X-1576124Y429665D01*
X-1575091Y428131D01*
X-1574367Y427441D01*
X-1573334Y426981D01*
X-1572404Y426828D01*
Y430048D01*
G01X-1584161Y446205D02*
X-1583701Y446825D01*
X-1583164Y447135D01*
X-1582551Y447238D01*
X-1581784Y447031D01*
X-1581247Y446515D01*
X-1581094Y445895D01*
X-1581171Y445275D01*
X-1581477Y444758D01*
X-1583011Y443725D01*
X-1583701Y443001D01*
X-1584161Y441968D01*
X-1584314Y441038D01*
X-1581094D01*
G01X-1576087Y458725D02*
X-1576397Y458265D01*
X-1576604Y457728D01*
Y457115D01*
X-1576294Y456425D01*
X-1575777Y455888D01*
X-1575157Y455505D01*
X-1574124Y455198D01*
X-1573194Y455121D01*
X-1572264Y455275D01*
X-1571644Y455505D01*
X-1571024Y455965D01*
X-1570611Y456501D01*
X-1570404Y457038D01*
Y457575D01*
X-1570611Y458111D01*
X-1570921Y458571D01*
X-1571334Y458955D01*
G01X-1570404Y463238D02*
X-1576604D01*
X-1575364Y462318D01*
G01X-1570404D02*
Y464158D01*
G01Y470358D02*
X-1576604D01*
X-1572161Y467521D01*
Y471355D01*
G01X-1559674Y-249944D02*
Y-256144D01*
G01X-1561437Y-249944D02*
X-1557911D01*
G01X-1555007Y-256144D02*
Y-249944D01*
X-1553167D01*
X-1552554Y-250254D01*
X-1552094Y-250977D01*
X-1551941Y-251804D01*
X-1552094Y-252631D01*
X-1552477Y-253251D01*
X-1553167Y-253561D01*
X-1555007D01*
G01X-1546354Y-256144D02*
Y-249944D01*
X-1549191Y-254387D01*
X-1545357D01*
G01X-1541074Y-256144D02*
X-1540537Y-256041D01*
X-1539924Y-255731D01*
X-1539541Y-255214D01*
X-1539387Y-254491D01*
X-1539541Y-253767D01*
X-1540001Y-253147D01*
X-1540691Y-252837D01*
X-1541457D01*
X-1541917Y-252631D01*
X-1542301Y-252114D01*
X-1542454Y-251391D01*
X-1542224Y-250667D01*
X-1541687Y-250151D01*
X-1541074Y-249944D01*
X-1540461Y-250151D01*
X-1539924Y-250667D01*
X-1539694Y-251391D01*
X-1539847Y-252114D01*
X-1540231Y-252631D01*
X-1540691Y-252837D01*
X-1541457D01*
X-1542147Y-253147D01*
X-1542607Y-253767D01*
X-1542761Y-254491D01*
X-1542607Y-255214D01*
X-1542224Y-255731D01*
X-1541611Y-256041D01*
X-1541074Y-256144D01*
G01X-1571751Y231825D02*
X-1572061Y231365D01*
X-1572268Y230828D01*
Y230215D01*
X-1571958Y229525D01*
X-1571441Y228988D01*
X-1570821Y228605D01*
X-1569788Y228298D01*
X-1568858Y228221D01*
X-1567928Y228375D01*
X-1567308Y228605D01*
X-1566688Y229065D01*
X-1566275Y229601D01*
X-1566068Y230138D01*
Y230675D01*
X-1566275Y231211D01*
X-1566585Y231671D01*
X-1566998Y232055D01*
G01X-1567308Y234651D02*
X-1566585Y235111D01*
X-1566171Y235725D01*
X-1566068Y236415D01*
X-1566171Y237028D01*
X-1566688Y237641D01*
X-1567308Y238025D01*
X-1567928Y238101D01*
X-1568651Y237948D01*
X-1569168Y237411D01*
X-1569375Y236875D01*
Y236185D01*
G01Y236875D02*
X-1569685Y237335D01*
X-1570201Y237718D01*
X-1570821Y237871D01*
X-1571441Y237718D01*
X-1571958Y237335D01*
X-1572268Y236645D01*
X-1572165Y235955D01*
X-1571751Y235265D01*
G01X-1572268Y242538D02*
X-1572061Y241925D01*
X-1571545Y241465D01*
X-1570925Y241158D01*
X-1570098Y240928D01*
X-1569168Y240851D01*
X-1568238Y240928D01*
X-1567411Y241158D01*
X-1566791Y241465D01*
X-1566275Y241925D01*
X-1566068Y242538D01*
X-1566275Y243151D01*
X-1566791Y243611D01*
X-1567411Y243918D01*
X-1568238Y244148D01*
X-1569168Y244225D01*
X-1570098Y244148D01*
X-1570925Y243918D01*
X-1571545Y243611D01*
X-1572061Y243151D01*
X-1572268Y242538D01*
G01X-1568651Y247281D02*
X-1569375Y247818D01*
X-1569788Y248278D01*
X-1569995Y248891D01*
X-1569788Y249428D01*
X-1569375Y249811D01*
X-1568755Y250118D01*
X-1568031Y250195D01*
X-1567411Y250118D01*
X-1566791Y249811D01*
X-1566275Y249351D01*
X-1566068Y248815D01*
X-1566275Y248201D01*
X-1566894Y247665D01*
X-1567825Y247358D01*
X-1568858Y247281D01*
X-1570201Y247435D01*
X-1570925Y247665D01*
X-1571648Y248048D01*
X-1572165Y248585D01*
X-1572268Y249121D01*
X-1572061Y249658D01*
X-1571545Y250041D01*
G01X-1568704Y255938D02*
X-1568167Y256041D01*
X-1567554Y256351D01*
X-1567171Y256868D01*
X-1567017Y257591D01*
X-1567171Y258315D01*
X-1567631Y258935D01*
X-1568321Y259245D01*
X-1569087D01*
X-1569547Y259451D01*
X-1569931Y259968D01*
X-1570084Y260691D01*
X-1569854Y261415D01*
X-1569317Y261931D01*
X-1568704Y262138D01*
X-1568091Y261931D01*
X-1567554Y261415D01*
X-1567324Y260691D01*
X-1567477Y259968D01*
X-1567861Y259451D01*
X-1568321Y259245D01*
X-1569087D01*
X-1569777Y258935D01*
X-1570237Y258315D01*
X-1570391Y257591D01*
X-1570237Y256868D01*
X-1569854Y256351D01*
X-1569241Y256041D01*
X-1568704Y255938D01*
G01X-1555044Y291405D02*
X-1561244D01*
Y293321D01*
X-1560934Y293935D01*
X-1560521Y294318D01*
X-1559694Y294471D01*
X-1558867Y294318D01*
X-1558351Y293858D01*
X-1558041Y293321D01*
Y291405D01*
G01Y293321D02*
X-1555044Y294471D01*
G01Y300058D02*
X-1561244D01*
X-1556801Y297221D01*
Y301055D01*
G01X-1561244Y305338D02*
X-1561037Y304725D01*
X-1560521Y304265D01*
X-1559901Y303958D01*
X-1559074Y303728D01*
X-1558144Y303651D01*
X-1557214Y303728D01*
X-1556387Y303958D01*
X-1555767Y304265D01*
X-1555251Y304725D01*
X-1555044Y305338D01*
X-1555251Y305951D01*
X-1555767Y306411D01*
X-1556387Y306718D01*
X-1557214Y306948D01*
X-1558144Y307025D01*
X-1559074Y306948D01*
X-1559901Y306718D01*
X-1560521Y306411D01*
X-1561037Y305951D01*
X-1561244Y305338D01*
G01X-1557627Y310081D02*
X-1558351Y310618D01*
X-1558764Y311078D01*
X-1558971Y311691D01*
X-1558764Y312228D01*
X-1558351Y312611D01*
X-1557731Y312918D01*
X-1557007Y312995D01*
X-1556387Y312918D01*
X-1555767Y312611D01*
X-1555251Y312151D01*
X-1555044Y311615D01*
X-1555251Y311001D01*
X-1555870Y310465D01*
X-1556801Y310158D01*
X-1557834Y310081D01*
X-1559177Y310235D01*
X-1559901Y310465D01*
X-1560624Y310848D01*
X-1561141Y311385D01*
X-1561244Y311921D01*
X-1561037Y312458D01*
X-1560521Y312841D01*
G01X-1566087Y416725D02*
X-1566397Y416265D01*
X-1566604Y415728D01*
Y415115D01*
X-1566294Y414425D01*
X-1565777Y413888D01*
X-1565157Y413505D01*
X-1564124Y413198D01*
X-1563194Y413121D01*
X-1562264Y413275D01*
X-1561644Y413505D01*
X-1561024Y413965D01*
X-1560611Y414501D01*
X-1560404Y415038D01*
Y415575D01*
X-1560611Y416111D01*
X-1560921Y416571D01*
X-1561334Y416955D01*
G01X-1560404Y421238D02*
X-1566604D01*
X-1565364Y420318D01*
G01X-1560404D02*
Y422158D01*
G01X-1561644Y425751D02*
X-1560921Y426211D01*
X-1560507Y426825D01*
X-1560404Y427515D01*
X-1560507Y428128D01*
X-1561024Y428741D01*
X-1561644Y429125D01*
X-1562264Y429201D01*
X-1562987Y429048D01*
X-1563504Y428511D01*
X-1563711Y427975D01*
Y427285D01*
G01Y427975D02*
X-1564021Y428435D01*
X-1564537Y428818D01*
X-1565157Y428971D01*
X-1565777Y428818D01*
X-1566294Y428435D01*
X-1566604Y427745D01*
X-1566501Y427055D01*
X-1566087Y426365D01*
G01X-1570004Y444138D02*
Y437938D01*
G01X-1571767Y444138D02*
X-1568241D01*
G01X-1565337Y437938D02*
Y444138D01*
X-1563497D01*
X-1562884Y443828D01*
X-1562424Y443105D01*
X-1562271Y442278D01*
X-1562424Y441451D01*
X-1562807Y440831D01*
X-1563497Y440521D01*
X-1565337D01*
G01X-1559061D02*
X-1558524Y441245D01*
X-1558064Y441658D01*
X-1557451Y441865D01*
X-1556914Y441658D01*
X-1556531Y441245D01*
X-1556224Y440625D01*
X-1556147Y439901D01*
X-1556224Y439281D01*
X-1556531Y438661D01*
X-1556991Y438145D01*
X-1557527Y437938D01*
X-1558141Y438145D01*
X-1558677Y438764D01*
X-1558984Y439695D01*
X-1559061Y440728D01*
X-1558907Y442071D01*
X-1558677Y442795D01*
X-1558294Y443518D01*
X-1557757Y444035D01*
X-1557221Y444138D01*
X-1556684Y443931D01*
X-1556301Y443415D01*
G01X-1551404Y444138D02*
X-1552017Y443931D01*
X-1552477Y443415D01*
X-1552784Y442795D01*
X-1553014Y441968D01*
X-1553091Y441038D01*
X-1553014Y440108D01*
X-1552784Y439281D01*
X-1552477Y438661D01*
X-1552017Y438145D01*
X-1551404Y437938D01*
X-1550791Y438145D01*
X-1550331Y438661D01*
X-1550024Y439281D01*
X-1549794Y440108D01*
X-1549717Y441038D01*
X-1549794Y441968D01*
X-1550024Y442795D01*
X-1550331Y443415D01*
X-1550791Y443931D01*
X-1551404Y444138D01*
G01X-1561087Y458725D02*
X-1561397Y458265D01*
X-1561604Y457728D01*
Y457115D01*
X-1561294Y456425D01*
X-1560777Y455888D01*
X-1560157Y455505D01*
X-1559124Y455198D01*
X-1558194Y455121D01*
X-1557264Y455275D01*
X-1556644Y455505D01*
X-1556024Y455965D01*
X-1555611Y456501D01*
X-1555404Y457038D01*
Y457575D01*
X-1555611Y458111D01*
X-1555921Y458571D01*
X-1556334Y458955D01*
G01X-1555404Y463238D02*
X-1561604D01*
X-1560364Y462318D01*
G01X-1555404D02*
Y464158D01*
G01X-1556334Y467751D02*
X-1555817Y468211D01*
X-1555507Y468748D01*
X-1555404Y469438D01*
X-1555611Y470128D01*
X-1556024Y470665D01*
X-1556747Y471048D01*
X-1557574Y471125D01*
X-1558401Y470971D01*
X-1558917Y470588D01*
X-1559331Y470051D01*
X-1559434Y469515D01*
X-1559331Y468978D01*
X-1558917Y468288D01*
X-1561604Y468518D01*
Y470588D01*
G01X-1552397Y-166962D02*
Y-160762D01*
X-1550404Y-165929D01*
X-1548411Y-160762D01*
Y-166962D01*
G01X-1546121D02*
X-1544204Y-160762D01*
X-1542287Y-166962D01*
G01X-1542977Y-164792D02*
X-1545431D01*
G01X-1536317Y-161279D02*
X-1536777Y-160969D01*
X-1537314Y-160762D01*
X-1537927D01*
X-1538617Y-161072D01*
X-1539154Y-161589D01*
X-1539537Y-162209D01*
X-1539844Y-163242D01*
X-1539921Y-164172D01*
X-1539767Y-165102D01*
X-1539537Y-165722D01*
X-1539077Y-166342D01*
X-1538541Y-166755D01*
X-1538004Y-166962D01*
X-1537467D01*
X-1536931Y-166755D01*
X-1536471Y-166445D01*
X-1536087Y-166032D01*
G01X-1534104Y-169029D02*
X-1529504D01*
G01X-1527137Y-166962D02*
Y-160762D01*
X-1525297D01*
X-1524684Y-161072D01*
X-1524224Y-161795D01*
X-1524071Y-162622D01*
X-1524224Y-163449D01*
X-1524607Y-164069D01*
X-1525297Y-164379D01*
X-1527137D01*
G01X-1520324Y-160762D02*
X-1518484D01*
G01X-1519404D02*
Y-166962D01*
G01X-1520324D02*
X-1518484D01*
G01X-1514967D02*
Y-160762D01*
X-1511441Y-166962D01*
Y-160762D01*
G01X-1507004Y-166962D02*
X-1506467Y-166859D01*
X-1505854Y-166549D01*
X-1505471Y-166032D01*
X-1505317Y-165309D01*
X-1505471Y-164585D01*
X-1505931Y-163965D01*
X-1506621Y-163655D01*
X-1507387D01*
X-1507847Y-163449D01*
X-1508231Y-162932D01*
X-1508384Y-162209D01*
X-1508154Y-161485D01*
X-1507617Y-160969D01*
X-1507004Y-160762D01*
X-1506391Y-160969D01*
X-1505854Y-161485D01*
X-1505624Y-162209D01*
X-1505777Y-162932D01*
X-1506161Y-163449D01*
X-1506621Y-163655D01*
X-1507387D01*
X-1508077Y-163965D01*
X-1508537Y-164585D01*
X-1508691Y-165309D01*
X-1508537Y-166032D01*
X-1508154Y-166549D01*
X-1507541Y-166859D01*
X-1507004Y-166962D01*
G01X-1527076Y-321450D02*
X-1525543D01*
Y-323310D01*
X-1526003Y-323930D01*
X-1526539Y-324343D01*
X-1527306Y-324550D01*
X-1528073Y-324343D01*
X-1528609Y-323930D01*
X-1529069Y-323310D01*
X-1529376Y-322587D01*
X-1529529Y-321760D01*
Y-321037D01*
X-1529376Y-320417D01*
X-1529069Y-319693D01*
X-1528609Y-319073D01*
X-1528149Y-318660D01*
X-1527536Y-318350D01*
X-1526999D01*
X-1526386Y-318557D01*
X-1525926Y-318970D01*
G01X-1522793Y-324550D02*
Y-318350D01*
X-1519879D01*
G01X-1520953Y-321347D02*
X-1522793D01*
G01X-1515136Y-324550D02*
Y-318350D01*
X-1516056Y-319590D01*
G01Y-324550D02*
X-1514216D01*
G01X-1505360Y-237695D02*
X-1511560D01*
Y-235779D01*
X-1511250Y-235165D01*
X-1510837Y-234782D01*
X-1510010Y-234629D01*
X-1509183Y-234782D01*
X-1508667Y-235242D01*
X-1508357Y-235779D01*
Y-237695D01*
G01Y-235779D02*
X-1505360Y-234629D01*
G01X-1510527Y-231419D02*
X-1511147Y-230959D01*
X-1511457Y-230422D01*
X-1511560Y-229809D01*
X-1511353Y-229042D01*
X-1510837Y-228505D01*
X-1510217Y-228352D01*
X-1509597Y-228429D01*
X-1509080Y-228735D01*
X-1508047Y-230269D01*
X-1507323Y-230959D01*
X-1506290Y-231419D01*
X-1505360Y-231572D01*
Y-228352D01*
G01X-1510527Y-225219D02*
X-1511147Y-224759D01*
X-1511457Y-224222D01*
X-1511560Y-223609D01*
X-1511353Y-222842D01*
X-1510837Y-222305D01*
X-1510217Y-222152D01*
X-1509597Y-222229D01*
X-1509080Y-222535D01*
X-1508047Y-224069D01*
X-1507323Y-224759D01*
X-1506290Y-225219D01*
X-1505360Y-225372D01*
Y-222152D01*
G01X-1507085Y265230D02*
Y271430D01*
X-1505092Y266263D01*
X-1503099Y271430D01*
Y265230D01*
G01X-1497359D02*
X-1500425D01*
Y271430D01*
X-1497359D01*
G01X-1498585Y268433D02*
X-1500425D01*
G01X-1494149Y270397D02*
X-1493689Y271017D01*
X-1493152Y271327D01*
X-1492539Y271430D01*
X-1491772Y271223D01*
X-1491235Y270707D01*
X-1491082Y270087D01*
X-1491159Y269467D01*
X-1491465Y268950D01*
X-1492999Y267917D01*
X-1493689Y267193D01*
X-1494149Y266160D01*
X-1494302Y265230D01*
X-1491082D01*
G01X-1507085Y469954D02*
Y476154D01*
X-1505092Y470987D01*
X-1503099Y476154D01*
Y469954D01*
G01X-1497359D02*
X-1500425D01*
Y476154D01*
X-1497359D01*
G01X-1498585Y473157D02*
X-1500425D01*
G01X-1492692Y469954D02*
Y476154D01*
X-1493612Y474914D01*
G01Y469954D02*
X-1491772D01*
G01X-1495237Y-233062D02*
Y-226862D01*
X-1493321D01*
X-1492707Y-227172D01*
X-1492324Y-227585D01*
X-1492171Y-228412D01*
X-1492324Y-229239D01*
X-1492784Y-229755D01*
X-1493321Y-230065D01*
X-1495237D01*
G01X-1493321D02*
X-1492171Y-233062D01*
G01X-1489191Y-232132D02*
X-1488731Y-232649D01*
X-1488194Y-232959D01*
X-1487504Y-233062D01*
X-1486814Y-232855D01*
X-1486277Y-232442D01*
X-1485894Y-231719D01*
X-1485817Y-230892D01*
X-1485971Y-230065D01*
X-1486354Y-229549D01*
X-1486891Y-229135D01*
X-1487427Y-229032D01*
X-1487964Y-229135D01*
X-1488654Y-229549D01*
X-1488424Y-226862D01*
X-1486354D01*
G01X-1482761Y-230479D02*
X-1482224Y-229755D01*
X-1481764Y-229342D01*
X-1481151Y-229135D01*
X-1480614Y-229342D01*
X-1480231Y-229755D01*
X-1479924Y-230375D01*
X-1479847Y-231099D01*
X-1479924Y-231719D01*
X-1480231Y-232339D01*
X-1480691Y-232855D01*
X-1481227Y-233062D01*
X-1481841Y-232855D01*
X-1482377Y-232236D01*
X-1482684Y-231305D01*
X-1482761Y-230272D01*
X-1482607Y-228929D01*
X-1482377Y-228205D01*
X-1481994Y-227482D01*
X-1481457Y-226965D01*
X-1480921Y-226862D01*
X-1480384Y-227069D01*
X-1480001Y-227585D01*
G01X-1495237Y-223062D02*
Y-216862D01*
X-1493321D01*
X-1492707Y-217172D01*
X-1492324Y-217585D01*
X-1492171Y-218412D01*
X-1492324Y-219239D01*
X-1492784Y-219755D01*
X-1493321Y-220065D01*
X-1495237D01*
G01X-1493321D02*
X-1492171Y-223062D01*
G01X-1489191Y-222132D02*
X-1488731Y-222649D01*
X-1488194Y-222959D01*
X-1487504Y-223062D01*
X-1486814Y-222855D01*
X-1486277Y-222442D01*
X-1485894Y-221719D01*
X-1485817Y-220892D01*
X-1485971Y-220065D01*
X-1486354Y-219549D01*
X-1486891Y-219135D01*
X-1487427Y-219032D01*
X-1487964Y-219135D01*
X-1488654Y-219549D01*
X-1488424Y-216862D01*
X-1486354D01*
G01X-1482991Y-222132D02*
X-1482531Y-222649D01*
X-1481994Y-222959D01*
X-1481304Y-223062D01*
X-1480614Y-222855D01*
X-1480077Y-222442D01*
X-1479694Y-221719D01*
X-1479617Y-220892D01*
X-1479771Y-220065D01*
X-1480154Y-219549D01*
X-1480691Y-219135D01*
X-1481227Y-219032D01*
X-1481764Y-219135D01*
X-1482454Y-219549D01*
X-1482224Y-216862D01*
X-1480154D01*
G01X-1478704Y-198655D02*
X-1484904D01*
X-1479737Y-196662D01*
X-1484904Y-194669D01*
X-1478704D01*
G01Y-192379D02*
X-1484904Y-190462D01*
X-1478704Y-188545D01*
G01X-1480874Y-189235D02*
Y-191689D01*
G01X-1484387Y-182575D02*
X-1484697Y-183035D01*
X-1484904Y-183572D01*
Y-184185D01*
X-1484594Y-184875D01*
X-1484077Y-185412D01*
X-1483457Y-185795D01*
X-1482424Y-186102D01*
X-1481494Y-186179D01*
X-1480564Y-186025D01*
X-1479944Y-185795D01*
X-1479324Y-185335D01*
X-1478911Y-184799D01*
X-1478704Y-184262D01*
Y-183725D01*
X-1478911Y-183189D01*
X-1479221Y-182729D01*
X-1479634Y-182345D01*
G01X-1476637Y-180362D02*
Y-175762D01*
G01X-1478704Y-173395D02*
X-1484904D01*
Y-171555D01*
X-1484594Y-170942D01*
X-1483871Y-170482D01*
X-1483044Y-170329D01*
X-1482217Y-170482D01*
X-1481597Y-170865D01*
X-1481287Y-171555D01*
Y-173395D01*
G01X-1484904Y-166582D02*
Y-164742D01*
G01Y-165662D02*
X-1478704D01*
G01Y-166582D02*
Y-164742D01*
G01Y-161225D02*
X-1484904D01*
X-1478704Y-157699D01*
X-1484904D01*
G01X-1478704Y-153415D02*
X-1480047Y-153262D01*
X-1481184Y-153032D01*
X-1482217Y-152725D01*
X-1483354Y-152342D01*
X-1484904Y-151729D01*
Y-154795D01*
G01X-1481763Y-129776D02*
Y-123576D01*
X-1479770Y-128743D01*
X-1477777Y-123576D01*
Y-129776D01*
G01X-1472037D02*
X-1475103D01*
Y-123576D01*
X-1472037D01*
G01X-1473263Y-126573D02*
X-1475103D01*
G01X-1467370Y-129776D02*
X-1466833Y-129673D01*
X-1466220Y-129363D01*
X-1465837Y-128846D01*
X-1465683Y-128123D01*
X-1465837Y-127399D01*
X-1466297Y-126779D01*
X-1466987Y-126469D01*
X-1467753D01*
X-1468213Y-126263D01*
X-1468597Y-125746D01*
X-1468750Y-125023D01*
X-1468520Y-124299D01*
X-1467983Y-123783D01*
X-1467370Y-123576D01*
X-1466757Y-123783D01*
X-1466220Y-124299D01*
X-1465990Y-125023D01*
X-1466143Y-125746D01*
X-1466527Y-126263D01*
X-1466987Y-126469D01*
X-1467753D01*
X-1468443Y-126779D01*
X-1468903Y-127399D01*
X-1469057Y-128123D01*
X-1468903Y-128846D01*
X-1468520Y-129363D01*
X-1467907Y-129673D01*
X-1467370Y-129776D01*
G01X-1473804Y-9962D02*
Y-3762D01*
X-1474724Y-5002D01*
G01Y-9962D02*
X-1472884D01*
G01X-1468907Y-9239D02*
X-1468371Y-9755D01*
X-1467757Y-9962D01*
X-1467144Y-9755D01*
X-1466607Y-9136D01*
X-1466224Y-8205D01*
X-1466071Y-7275D01*
Y-6139D01*
X-1466224Y-5209D01*
X-1466607Y-4382D01*
X-1467067Y-3969D01*
X-1467604Y-3762D01*
X-1468217Y-3969D01*
X-1468677Y-4382D01*
X-1468984Y-5002D01*
X-1469137Y-5829D01*
X-1468984Y-6552D01*
X-1468601Y-7275D01*
X-1468141Y-7689D01*
X-1467604Y-7792D01*
X-1466991Y-7585D01*
X-1466531Y-7069D01*
X-1466071Y-6139D01*
G01X-1481763Y157824D02*
Y164024D01*
X-1479770Y158857D01*
X-1477777Y164024D01*
Y157824D01*
G01X-1472037D02*
X-1475103D01*
Y164024D01*
X-1472037D01*
G01X-1473263Y161027D02*
X-1475103D01*
G01X-1468827Y160407D02*
X-1468290Y161131D01*
X-1467830Y161544D01*
X-1467217Y161751D01*
X-1466680Y161544D01*
X-1466297Y161131D01*
X-1465990Y160511D01*
X-1465913Y159787D01*
X-1465990Y159167D01*
X-1466297Y158547D01*
X-1466757Y158031D01*
X-1467293Y157824D01*
X-1467907Y158031D01*
X-1468443Y158650D01*
X-1468750Y159581D01*
X-1468827Y160614D01*
X-1468673Y161957D01*
X-1468443Y162681D01*
X-1468060Y163404D01*
X-1467523Y163921D01*
X-1466987Y164024D01*
X-1466450Y163817D01*
X-1466067Y163301D01*
G01X-1469191Y-237790D02*
X-1468731Y-238513D01*
X-1468117Y-238927D01*
X-1467427Y-239030D01*
X-1466814Y-238927D01*
X-1466201Y-238410D01*
X-1465817Y-237790D01*
X-1465741Y-237170D01*
X-1465894Y-236447D01*
X-1466431Y-235930D01*
X-1466967Y-235723D01*
X-1467657D01*
G01X-1466967D02*
X-1466507Y-235413D01*
X-1466124Y-234897D01*
X-1465971Y-234277D01*
X-1466124Y-233657D01*
X-1466507Y-233140D01*
X-1467197Y-232830D01*
X-1467887Y-232933D01*
X-1468577Y-233347D01*
G01X-1455291Y-226862D02*
Y-231305D01*
X-1454984Y-232236D01*
X-1454371Y-232855D01*
X-1453604Y-233062D01*
X-1452837Y-232855D01*
X-1452224Y-232236D01*
X-1451917Y-231305D01*
Y-226862D01*
G01X-1449091Y-231822D02*
X-1448631Y-232545D01*
X-1448017Y-232959D01*
X-1447327Y-233062D01*
X-1446714Y-232959D01*
X-1446101Y-232442D01*
X-1445717Y-231822D01*
X-1445641Y-231202D01*
X-1445794Y-230479D01*
X-1446331Y-229962D01*
X-1446867Y-229755D01*
X-1447557D01*
G01X-1446867D02*
X-1446407Y-229445D01*
X-1446024Y-228929D01*
X-1445871Y-228309D01*
X-1446024Y-227689D01*
X-1446407Y-227172D01*
X-1447097Y-226862D01*
X-1447787Y-226965D01*
X-1448477Y-227379D01*
G01X-1461397Y-168962D02*
Y-162762D01*
X-1459404Y-167929D01*
X-1457411Y-162762D01*
Y-168962D01*
G01X-1455121D02*
X-1453204Y-162762D01*
X-1451287Y-168962D01*
G01X-1451977Y-166792D02*
X-1454431D01*
G01X-1445317Y-163279D02*
X-1445777Y-162969D01*
X-1446314Y-162762D01*
X-1446927D01*
X-1447617Y-163072D01*
X-1448154Y-163589D01*
X-1448537Y-164209D01*
X-1448844Y-165242D01*
X-1448921Y-166172D01*
X-1448767Y-167102D01*
X-1448537Y-167722D01*
X-1448077Y-168342D01*
X-1447541Y-168755D01*
X-1447004Y-168962D01*
X-1446467D01*
X-1445931Y-168755D01*
X-1445471Y-168445D01*
X-1445087Y-168032D01*
G01X-1443104Y-171029D02*
X-1438504D01*
G01X-1436137Y-168962D02*
Y-162762D01*
X-1434297D01*
X-1433684Y-163072D01*
X-1433224Y-163795D01*
X-1433071Y-164622D01*
X-1433224Y-165449D01*
X-1433607Y-166069D01*
X-1434297Y-166379D01*
X-1436137D01*
G01X-1429324Y-162762D02*
X-1427484D01*
G01X-1428404D02*
Y-168962D01*
G01X-1429324D02*
X-1427484D01*
G01X-1423967D02*
Y-162762D01*
X-1420441Y-168962D01*
Y-162762D01*
G01X-1417461Y-166379D02*
X-1416924Y-165655D01*
X-1416464Y-165242D01*
X-1415851Y-165035D01*
X-1415314Y-165242D01*
X-1414931Y-165655D01*
X-1414624Y-166275D01*
X-1414547Y-166999D01*
X-1414624Y-167619D01*
X-1414931Y-168239D01*
X-1415391Y-168755D01*
X-1415927Y-168962D01*
X-1416541Y-168755D01*
X-1417077Y-168136D01*
X-1417384Y-167205D01*
X-1417461Y-166172D01*
X-1417307Y-164829D01*
X-1417077Y-164105D01*
X-1416694Y-163382D01*
X-1416157Y-162865D01*
X-1415621Y-162762D01*
X-1415084Y-162969D01*
X-1414701Y-163485D01*
G01X-1465714Y35490D02*
Y41690D01*
X-1466634Y40450D01*
G01Y35490D02*
X-1464794D01*
G01X-1442397Y-146962D02*
Y-140762D01*
X-1440404Y-145929D01*
X-1438411Y-140762D01*
Y-146962D01*
G01X-1436121D02*
X-1434204Y-140762D01*
X-1432287Y-146962D01*
G01X-1432977Y-144792D02*
X-1435431D01*
G01X-1426317Y-141279D02*
X-1426777Y-140969D01*
X-1427314Y-140762D01*
X-1427927D01*
X-1428617Y-141072D01*
X-1429154Y-141589D01*
X-1429537Y-142209D01*
X-1429844Y-143242D01*
X-1429921Y-144172D01*
X-1429767Y-145102D01*
X-1429537Y-145722D01*
X-1429077Y-146342D01*
X-1428541Y-146755D01*
X-1428004Y-146962D01*
X-1427467D01*
X-1426931Y-146755D01*
X-1426471Y-146445D01*
X-1426087Y-146032D01*
G01X-1424104Y-149029D02*
X-1419504D01*
G01X-1417137Y-146962D02*
Y-140762D01*
X-1415297D01*
X-1414684Y-141072D01*
X-1414224Y-141795D01*
X-1414071Y-142622D01*
X-1414224Y-143449D01*
X-1414607Y-144069D01*
X-1415297Y-144379D01*
X-1417137D01*
G01X-1410324Y-140762D02*
X-1408484D01*
G01X-1409404D02*
Y-146962D01*
G01X-1410324D02*
X-1408484D01*
G01X-1404967D02*
Y-140762D01*
X-1401441Y-146962D01*
Y-140762D01*
G01X-1396084Y-146962D02*
Y-140762D01*
X-1398921Y-145205D01*
X-1395087D01*
G01X-1437884Y12489D02*
X-1444084D01*
Y14329D01*
X-1443774Y14942D01*
X-1443051Y15402D01*
X-1442224Y15555D01*
X-1441397Y15402D01*
X-1440777Y15019D01*
X-1440467Y14329D01*
Y12489D01*
G01X-1437884Y20222D02*
X-1444084D01*
X-1442844Y19302D01*
G01X-1437884D02*
Y21142D01*
G01X-1448397Y174038D02*
Y180238D01*
X-1446404Y175071D01*
X-1444411Y180238D01*
Y174038D01*
G01X-1442121D02*
X-1440204Y180238D01*
X-1438287Y174038D01*
G01X-1438977Y176208D02*
X-1441431D01*
G01X-1432317Y179721D02*
X-1432777Y180031D01*
X-1433314Y180238D01*
X-1433927D01*
X-1434617Y179928D01*
X-1435154Y179411D01*
X-1435537Y178791D01*
X-1435844Y177758D01*
X-1435921Y176828D01*
X-1435767Y175898D01*
X-1435537Y175278D01*
X-1435077Y174658D01*
X-1434541Y174245D01*
X-1434004Y174038D01*
X-1433467D01*
X-1432931Y174245D01*
X-1432471Y174555D01*
X-1432087Y174968D01*
G01X-1430104Y171971D02*
X-1425504D01*
G01X-1423137Y174038D02*
Y180238D01*
X-1421297D01*
X-1420684Y179928D01*
X-1420224Y179205D01*
X-1420071Y178378D01*
X-1420224Y177551D01*
X-1420607Y176931D01*
X-1421297Y176621D01*
X-1423137D01*
G01X-1416324Y180238D02*
X-1414484D01*
G01X-1415404D02*
Y174038D01*
G01X-1416324D02*
X-1414484D01*
G01X-1410967D02*
Y180238D01*
X-1407441Y174038D01*
Y180238D01*
G01X-1404691Y174968D02*
X-1404231Y174451D01*
X-1403694Y174141D01*
X-1403004Y174038D01*
X-1402314Y174245D01*
X-1401777Y174658D01*
X-1401394Y175381D01*
X-1401317Y176208D01*
X-1401471Y177035D01*
X-1401854Y177551D01*
X-1402391Y177965D01*
X-1402927Y178068D01*
X-1403464Y177965D01*
X-1404154Y177551D01*
X-1403924Y180238D01*
X-1401854D01*
G01X-1438337Y297738D02*
Y303938D01*
X-1436421D01*
X-1435807Y303628D01*
X-1435424Y303215D01*
X-1435271Y302388D01*
X-1435424Y301561D01*
X-1435884Y301045D01*
X-1436421Y300735D01*
X-1438337D01*
G01X-1436421D02*
X-1435271Y297738D01*
G01X-1432291Y298978D02*
X-1431831Y298255D01*
X-1431217Y297841D01*
X-1430527Y297738D01*
X-1429914Y297841D01*
X-1429301Y298358D01*
X-1428917Y298978D01*
X-1428841Y299598D01*
X-1428994Y300321D01*
X-1429531Y300838D01*
X-1430067Y301045D01*
X-1430757D01*
G01X-1430067D02*
X-1429607Y301355D01*
X-1429224Y301871D01*
X-1429071Y302491D01*
X-1429224Y303111D01*
X-1429607Y303628D01*
X-1430297Y303938D01*
X-1430987Y303835D01*
X-1431677Y303421D01*
G01X-1424404Y297738D02*
Y303938D01*
X-1425324Y302698D01*
G01Y297738D02*
X-1423484D01*
G01X-1418204Y303938D02*
X-1418817Y303731D01*
X-1419277Y303215D01*
X-1419584Y302595D01*
X-1419814Y301768D01*
X-1419891Y300838D01*
X-1419814Y299908D01*
X-1419584Y299081D01*
X-1419277Y298461D01*
X-1418817Y297945D01*
X-1418204Y297738D01*
X-1417591Y297945D01*
X-1417131Y298461D01*
X-1416824Y299081D01*
X-1416594Y299908D01*
X-1416517Y300838D01*
X-1416594Y301768D01*
X-1416824Y302595D01*
X-1417131Y303215D01*
X-1417591Y303731D01*
X-1418204Y303938D01*
G01X-1438137Y312338D02*
Y318538D01*
X-1436221D01*
X-1435607Y318228D01*
X-1435224Y317815D01*
X-1435071Y316988D01*
X-1435224Y316161D01*
X-1435684Y315645D01*
X-1436221Y315335D01*
X-1438137D01*
G01X-1436221D02*
X-1435071Y312338D01*
G01X-1432091Y313578D02*
X-1431631Y312855D01*
X-1431017Y312441D01*
X-1430327Y312338D01*
X-1429714Y312441D01*
X-1429101Y312958D01*
X-1428717Y313578D01*
X-1428641Y314198D01*
X-1428794Y314921D01*
X-1429331Y315438D01*
X-1429867Y315645D01*
X-1430557D01*
G01X-1429867D02*
X-1429407Y315955D01*
X-1429024Y316471D01*
X-1428871Y317091D01*
X-1429024Y317711D01*
X-1429407Y318228D01*
X-1430097Y318538D01*
X-1430787Y318435D01*
X-1431477Y318021D01*
G01X-1424204Y312338D02*
Y318538D01*
X-1425124Y317298D01*
G01Y312338D02*
X-1423284D01*
G01X-1418004D02*
Y318538D01*
X-1418924Y317298D01*
G01Y312338D02*
X-1417084D01*
G01X-1432348Y-238852D02*
Y-232652D01*
X-1435185Y-237095D01*
X-1431351D01*
G01X-1423437Y-239180D02*
Y-232980D01*
X-1421521D01*
X-1420907Y-233290D01*
X-1420524Y-233703D01*
X-1420371Y-234530D01*
X-1420524Y-235357D01*
X-1420984Y-235873D01*
X-1421521Y-236183D01*
X-1423437D01*
G01X-1421521D02*
X-1420371Y-239180D01*
G01X-1417391Y-238250D02*
X-1416931Y-238767D01*
X-1416394Y-239077D01*
X-1415704Y-239180D01*
X-1415014Y-238973D01*
X-1414477Y-238560D01*
X-1414094Y-237837D01*
X-1414017Y-237010D01*
X-1414171Y-236183D01*
X-1414554Y-235667D01*
X-1415091Y-235253D01*
X-1415627Y-235150D01*
X-1416164Y-235253D01*
X-1416854Y-235667D01*
X-1416624Y-232980D01*
X-1414554D01*
G01X-1409657Y-239180D02*
X-1409504Y-237837D01*
X-1409274Y-236700D01*
X-1408967Y-235667D01*
X-1408584Y-234530D01*
X-1407971Y-232980D01*
X-1411037D01*
G01X-1435191Y-227098D02*
X-1434731Y-227615D01*
X-1434194Y-227925D01*
X-1433504Y-228028D01*
X-1432814Y-227821D01*
X-1432277Y-227408D01*
X-1431894Y-226685D01*
X-1431817Y-225858D01*
X-1431971Y-225031D01*
X-1432354Y-224515D01*
X-1432891Y-224101D01*
X-1433427Y-223998D01*
X-1433964Y-224101D01*
X-1434654Y-224515D01*
X-1434424Y-221828D01*
X-1432354D01*
G01X-1423237Y-229862D02*
Y-223662D01*
X-1421321D01*
X-1420707Y-223972D01*
X-1420324Y-224385D01*
X-1420171Y-225212D01*
X-1420324Y-226039D01*
X-1420784Y-226555D01*
X-1421321Y-226865D01*
X-1423237D01*
G01X-1421321D02*
X-1420171Y-229862D01*
G01X-1416961Y-227279D02*
X-1416424Y-226555D01*
X-1415964Y-226142D01*
X-1415351Y-225935D01*
X-1414814Y-226142D01*
X-1414431Y-226555D01*
X-1414124Y-227175D01*
X-1414047Y-227899D01*
X-1414124Y-228519D01*
X-1414431Y-229139D01*
X-1414891Y-229655D01*
X-1415427Y-229862D01*
X-1416041Y-229655D01*
X-1416577Y-229036D01*
X-1416884Y-228105D01*
X-1416961Y-227072D01*
X-1416807Y-225729D01*
X-1416577Y-225005D01*
X-1416194Y-224282D01*
X-1415657Y-223765D01*
X-1415121Y-223662D01*
X-1414584Y-223869D01*
X-1414201Y-224385D01*
G01X-1410991Y-228622D02*
X-1410531Y-229345D01*
X-1409917Y-229759D01*
X-1409227Y-229862D01*
X-1408614Y-229759D01*
X-1408001Y-229242D01*
X-1407617Y-228622D01*
X-1407541Y-228002D01*
X-1407694Y-227279D01*
X-1408231Y-226762D01*
X-1408767Y-226555D01*
X-1409457D01*
G01X-1408767D02*
X-1408307Y-226245D01*
X-1407924Y-225729D01*
X-1407771Y-225109D01*
X-1407924Y-224489D01*
X-1408307Y-223972D01*
X-1408997Y-223662D01*
X-1409687Y-223765D01*
X-1410377Y-224179D01*
G01X-1419977Y-214819D02*
X-1420437Y-214509D01*
X-1420974Y-214302D01*
X-1421587D01*
X-1422277Y-214612D01*
X-1422814Y-215129D01*
X-1423197Y-215749D01*
X-1423504Y-216782D01*
X-1423581Y-217712D01*
X-1423427Y-218642D01*
X-1423197Y-219262D01*
X-1422737Y-219882D01*
X-1422201Y-220295D01*
X-1421664Y-220502D01*
X-1421127D01*
X-1420591Y-220295D01*
X-1420131Y-219985D01*
X-1419747Y-219572D01*
G01X-1417151Y-219262D02*
X-1416691Y-219985D01*
X-1416077Y-220399D01*
X-1415387Y-220502D01*
X-1414774Y-220399D01*
X-1414161Y-219882D01*
X-1413777Y-219262D01*
X-1413701Y-218642D01*
X-1413854Y-217919D01*
X-1414391Y-217402D01*
X-1414927Y-217195D01*
X-1415617D01*
G01X-1414927D02*
X-1414467Y-216885D01*
X-1414084Y-216369D01*
X-1413931Y-215749D01*
X-1414084Y-215129D01*
X-1414467Y-214612D01*
X-1415157Y-214302D01*
X-1415847Y-214405D01*
X-1416537Y-214819D01*
G01X-1409417Y-220502D02*
X-1409264Y-219159D01*
X-1409034Y-218022D01*
X-1408727Y-216989D01*
X-1408344Y-215852D01*
X-1407731Y-214302D01*
X-1410797D01*
G01X-1432017Y292821D02*
X-1432477Y293131D01*
X-1433014Y293338D01*
X-1433627D01*
X-1434317Y293028D01*
X-1434854Y292511D01*
X-1435237Y291891D01*
X-1435544Y290858D01*
X-1435621Y289928D01*
X-1435467Y288998D01*
X-1435237Y288378D01*
X-1434777Y287758D01*
X-1434241Y287345D01*
X-1433704Y287138D01*
X-1433167D01*
X-1432631Y287345D01*
X-1432171Y287655D01*
X-1431787Y288068D01*
G01X-1429191Y288378D02*
X-1428731Y287655D01*
X-1428117Y287241D01*
X-1427427Y287138D01*
X-1426814Y287241D01*
X-1426201Y287758D01*
X-1425817Y288378D01*
X-1425741Y288998D01*
X-1425894Y289721D01*
X-1426431Y290238D01*
X-1426967Y290445D01*
X-1427657D01*
G01X-1426967D02*
X-1426507Y290755D01*
X-1426124Y291271D01*
X-1425971Y291891D01*
X-1426124Y292511D01*
X-1426507Y293028D01*
X-1427197Y293338D01*
X-1427887Y293235D01*
X-1428577Y292821D01*
G01X-1421304Y287138D02*
X-1420767Y287241D01*
X-1420154Y287551D01*
X-1419771Y288068D01*
X-1419617Y288791D01*
X-1419771Y289515D01*
X-1420231Y290135D01*
X-1420921Y290445D01*
X-1421687D01*
X-1422147Y290651D01*
X-1422531Y291168D01*
X-1422684Y291891D01*
X-1422454Y292615D01*
X-1421917Y293131D01*
X-1421304Y293338D01*
X-1420691Y293131D01*
X-1420154Y292615D01*
X-1419924Y291891D01*
X-1420077Y291168D01*
X-1420461Y290651D01*
X-1420921Y290445D01*
X-1421687D01*
X-1422377Y290135D01*
X-1422837Y289515D01*
X-1422991Y288791D01*
X-1422837Y288068D01*
X-1422454Y287551D01*
X-1421841Y287241D01*
X-1421304Y287138D01*
G01X-1400443Y-292759D02*
X-1400136Y-292449D01*
X-1399906Y-291933D01*
X-1399753Y-291209D01*
X-1399906Y-290589D01*
X-1400213Y-290176D01*
X-1400749Y-289866D01*
X-1402819D01*
Y-296066D01*
X-1400289D01*
X-1399753Y-295653D01*
X-1399446Y-295033D01*
X-1399293Y-294309D01*
X-1399446Y-293586D01*
X-1399906Y-292966D01*
X-1400443Y-292759D01*
X-1402819D01*
G01X-1396543Y-294826D02*
X-1396083Y-295549D01*
X-1395469Y-295963D01*
X-1394779Y-296066D01*
X-1394166Y-295963D01*
X-1393553Y-295446D01*
X-1393169Y-294826D01*
X-1393093Y-294206D01*
X-1393246Y-293483D01*
X-1393783Y-292966D01*
X-1394319Y-292759D01*
X-1395009D01*
G01X-1394319D02*
X-1393859Y-292449D01*
X-1393476Y-291933D01*
X-1393323Y-291313D01*
X-1393476Y-290693D01*
X-1393859Y-290176D01*
X-1394549Y-289866D01*
X-1395239Y-289969D01*
X-1395929Y-290383D01*
G01X-1390113Y-290899D02*
X-1389653Y-290279D01*
X-1389116Y-289969D01*
X-1388503Y-289866D01*
X-1387736Y-290073D01*
X-1387199Y-290589D01*
X-1387046Y-291209D01*
X-1387123Y-291829D01*
X-1387429Y-292346D01*
X-1388963Y-293379D01*
X-1389653Y-294103D01*
X-1390113Y-295136D01*
X-1390266Y-296066D01*
X-1387046D01*
G01X-1414901Y-3969D02*
X-1414441Y-3349D01*
X-1413904Y-3039D01*
X-1413291Y-2936D01*
X-1412524Y-3143D01*
X-1411987Y-3659D01*
X-1411834Y-4279D01*
X-1411911Y-4899D01*
X-1412217Y-5416D01*
X-1413751Y-6449D01*
X-1414441Y-7173D01*
X-1414901Y-8206D01*
X-1415054Y-9136D01*
X-1411834D01*
G01X-1407244Y-2936D02*
X-1407857Y-3143D01*
X-1408317Y-3659D01*
X-1408624Y-4279D01*
X-1408854Y-5106D01*
X-1408931Y-6036D01*
X-1408854Y-6966D01*
X-1408624Y-7793D01*
X-1408317Y-8413D01*
X-1407857Y-8929D01*
X-1407244Y-9136D01*
X-1406631Y-8929D01*
X-1406171Y-8413D01*
X-1405864Y-7793D01*
X-1405634Y-6966D01*
X-1405557Y-6036D01*
X-1405634Y-5106D01*
X-1405864Y-4279D01*
X-1406171Y-3659D01*
X-1406631Y-3143D01*
X-1407244Y-2936D01*
G01X-1412123Y34267D02*
X-1411663Y34887D01*
X-1411126Y35197D01*
X-1410513Y35300D01*
X-1409746Y35093D01*
X-1409209Y34577D01*
X-1409056Y33957D01*
X-1409133Y33337D01*
X-1409439Y32820D01*
X-1410973Y31787D01*
X-1411663Y31063D01*
X-1412123Y30030D01*
X-1412276Y29100D01*
X-1409056D01*
G01X-1405804Y290038D02*
Y296238D01*
X-1406724Y294998D01*
G01Y290038D02*
X-1404884D01*
G01X-1401061Y292621D02*
X-1400524Y293345D01*
X-1400064Y293758D01*
X-1399451Y293965D01*
X-1398914Y293758D01*
X-1398531Y293345D01*
X-1398224Y292725D01*
X-1398147Y292001D01*
X-1398224Y291381D01*
X-1398531Y290761D01*
X-1398991Y290245D01*
X-1399527Y290038D01*
X-1400141Y290245D01*
X-1400677Y290864D01*
X-1400984Y291795D01*
X-1401061Y292828D01*
X-1400907Y294171D01*
X-1400677Y294895D01*
X-1400294Y295618D01*
X-1399757Y296135D01*
X-1399221Y296238D01*
X-1398684Y296031D01*
X-1398301Y295515D01*
G01X-1403007Y327761D02*
X-1402471Y327245D01*
X-1401857Y327038D01*
X-1401244Y327245D01*
X-1400707Y327864D01*
X-1400324Y328795D01*
X-1400171Y329725D01*
Y330861D01*
X-1400324Y331791D01*
X-1400707Y332618D01*
X-1401167Y333031D01*
X-1401704Y333238D01*
X-1402317Y333031D01*
X-1402777Y332618D01*
X-1403084Y331998D01*
X-1403237Y331171D01*
X-1403084Y330448D01*
X-1402701Y329725D01*
X-1402241Y329311D01*
X-1401704Y329208D01*
X-1401091Y329415D01*
X-1400631Y329931D01*
X-1400171Y330861D01*
G01X-1402161Y388205D02*
X-1401701Y388825D01*
X-1401164Y389135D01*
X-1400551Y389238D01*
X-1399784Y389031D01*
X-1399247Y388515D01*
X-1399094Y387895D01*
X-1399171Y387275D01*
X-1399477Y386758D01*
X-1401011Y385725D01*
X-1401701Y385001D01*
X-1402161Y383968D01*
X-1402314Y383038D01*
X-1399094D01*
G01X-1403804Y417405D02*
X-1397604D01*
Y420471D01*
G01X-1402771Y423681D02*
X-1403391Y424141D01*
X-1403701Y424678D01*
X-1403804Y425291D01*
X-1403597Y426058D01*
X-1403081Y426595D01*
X-1402461Y426748D01*
X-1401841Y426671D01*
X-1401324Y426365D01*
X-1400291Y424831D01*
X-1399567Y424141D01*
X-1398534Y423681D01*
X-1397604Y423528D01*
Y426748D01*
G01X-1400704Y456038D02*
Y462238D01*
X-1401624Y460998D01*
G01Y456038D02*
X-1399784D01*
G01X-1400804Y-14262D02*
X-1394604D01*
G01X-1400804Y-16025D02*
Y-12499D01*
G01X-1394604Y-9595D02*
X-1400804D01*
Y-7755D01*
X-1400494Y-7142D01*
X-1399771Y-6682D01*
X-1398944Y-6529D01*
X-1398117Y-6682D01*
X-1397497Y-7065D01*
X-1397187Y-7755D01*
Y-9595D01*
G01X-1395534Y-3549D02*
X-1395017Y-3089D01*
X-1394707Y-2552D01*
X-1394604Y-1862D01*
X-1394811Y-1172D01*
X-1395224Y-635D01*
X-1395947Y-252D01*
X-1396774Y-175D01*
X-1397601Y-329D01*
X-1398117Y-712D01*
X-1398531Y-1249D01*
X-1398634Y-1785D01*
X-1398531Y-2322D01*
X-1398117Y-3012D01*
X-1400804Y-2782D01*
Y-712D01*
G01X-1394604Y4338D02*
X-1400804D01*
X-1399564Y3418D01*
G01X-1394604D02*
Y5258D01*
G01X-1392537Y-25062D02*
Y-18862D01*
X-1390621D01*
X-1390007Y-19172D01*
X-1389624Y-19585D01*
X-1389471Y-20412D01*
X-1389624Y-21239D01*
X-1390084Y-21755D01*
X-1390621Y-22065D01*
X-1392537D01*
G01X-1390621D02*
X-1389471Y-25062D01*
G01X-1386261Y-19895D02*
X-1385801Y-19275D01*
X-1385264Y-18965D01*
X-1384651Y-18862D01*
X-1383884Y-19069D01*
X-1383347Y-19585D01*
X-1383194Y-20205D01*
X-1383271Y-20825D01*
X-1383577Y-21342D01*
X-1385111Y-22375D01*
X-1385801Y-23099D01*
X-1386261Y-24132D01*
X-1386414Y-25062D01*
X-1383194D01*
G01X-1378604D02*
X-1378067Y-24959D01*
X-1377454Y-24649D01*
X-1377071Y-24132D01*
X-1376917Y-23409D01*
X-1377071Y-22685D01*
X-1377531Y-22065D01*
X-1378221Y-21755D01*
X-1378987D01*
X-1379447Y-21549D01*
X-1379831Y-21032D01*
X-1379984Y-20309D01*
X-1379754Y-19585D01*
X-1379217Y-19069D01*
X-1378604Y-18862D01*
X-1377991Y-19069D01*
X-1377454Y-19585D01*
X-1377224Y-20309D01*
X-1377377Y-21032D01*
X-1377761Y-21549D01*
X-1378221Y-21755D01*
X-1378987D01*
X-1379677Y-22065D01*
X-1380137Y-22685D01*
X-1380291Y-23409D01*
X-1380137Y-24132D01*
X-1379754Y-24649D01*
X-1379141Y-24959D01*
X-1378604Y-25062D01*
G01X-1372557D02*
X-1372404Y-23719D01*
X-1372174Y-22582D01*
X-1371867Y-21549D01*
X-1371484Y-20412D01*
X-1370871Y-18862D01*
X-1373937D01*
G01X-1389437Y-15062D02*
Y-8862D01*
X-1387521D01*
X-1386907Y-9172D01*
X-1386524Y-9585D01*
X-1386371Y-10412D01*
X-1386524Y-11239D01*
X-1386984Y-11755D01*
X-1387521Y-12065D01*
X-1389437D01*
G01X-1387521D02*
X-1386371Y-15062D01*
G01X-1383007Y-14339D02*
X-1382471Y-14855D01*
X-1381857Y-15062D01*
X-1381244Y-14855D01*
X-1380707Y-14236D01*
X-1380324Y-13305D01*
X-1380171Y-12375D01*
Y-11239D01*
X-1380324Y-10309D01*
X-1380707Y-9482D01*
X-1381167Y-9069D01*
X-1381704Y-8862D01*
X-1382317Y-9069D01*
X-1382777Y-9482D01*
X-1383084Y-10102D01*
X-1383237Y-10929D01*
X-1383084Y-11652D01*
X-1382701Y-12375D01*
X-1382241Y-12789D01*
X-1381704Y-12892D01*
X-1381091Y-12685D01*
X-1380631Y-12169D01*
X-1380171Y-11239D01*
G01X-1376961Y-12479D02*
X-1376424Y-11755D01*
X-1375964Y-11342D01*
X-1375351Y-11135D01*
X-1374814Y-11342D01*
X-1374431Y-11755D01*
X-1374124Y-12375D01*
X-1374047Y-13099D01*
X-1374124Y-13719D01*
X-1374431Y-14339D01*
X-1374891Y-14855D01*
X-1375427Y-15062D01*
X-1376041Y-14855D01*
X-1376577Y-14236D01*
X-1376884Y-13305D01*
X-1376961Y-12272D01*
X-1376807Y-10929D01*
X-1376577Y-10205D01*
X-1376194Y-9482D01*
X-1375657Y-8965D01*
X-1375121Y-8862D01*
X-1374584Y-9069D01*
X-1374201Y-9585D01*
G01X-1389637Y-4062D02*
Y2138D01*
X-1387721D01*
X-1387107Y1828D01*
X-1386724Y1415D01*
X-1386571Y588D01*
X-1386724Y-239D01*
X-1387184Y-755D01*
X-1387721Y-1065D01*
X-1389637D01*
G01X-1387721D02*
X-1386571Y-4062D01*
G01X-1381904D02*
X-1381367Y-3959D01*
X-1380754Y-3649D01*
X-1380371Y-3132D01*
X-1380217Y-2409D01*
X-1380371Y-1685D01*
X-1380831Y-1065D01*
X-1381521Y-755D01*
X-1382287D01*
X-1382747Y-549D01*
X-1383131Y-32D01*
X-1383284Y691D01*
X-1383054Y1415D01*
X-1382517Y1931D01*
X-1381904Y2138D01*
X-1381291Y1931D01*
X-1380754Y1415D01*
X-1380524Y691D01*
X-1380677Y-32D01*
X-1381061Y-549D01*
X-1381521Y-755D01*
X-1382287D01*
X-1382977Y-1065D01*
X-1383437Y-1685D01*
X-1383591Y-2409D01*
X-1383437Y-3132D01*
X-1383054Y-3649D01*
X-1382441Y-3959D01*
X-1381904Y-4062D01*
G01X-1375704D02*
X-1375167Y-3959D01*
X-1374554Y-3649D01*
X-1374171Y-3132D01*
X-1374017Y-2409D01*
X-1374171Y-1685D01*
X-1374631Y-1065D01*
X-1375321Y-755D01*
X-1376087D01*
X-1376547Y-549D01*
X-1376931Y-32D01*
X-1377084Y691D01*
X-1376854Y1415D01*
X-1376317Y1931D01*
X-1375704Y2138D01*
X-1375091Y1931D01*
X-1374554Y1415D01*
X-1374324Y691D01*
X-1374477Y-32D01*
X-1374861Y-549D01*
X-1375321Y-755D01*
X-1376087D01*
X-1376777Y-1065D01*
X-1377237Y-1685D01*
X-1377391Y-2409D01*
X-1377237Y-3132D01*
X-1376854Y-3649D01*
X-1376241Y-3959D01*
X-1375704Y-4062D01*
G01X-1389637Y5938D02*
Y12138D01*
X-1387721D01*
X-1387107Y11828D01*
X-1386724Y11415D01*
X-1386571Y10588D01*
X-1386724Y9761D01*
X-1387184Y9245D01*
X-1387721Y8935D01*
X-1389637D01*
G01X-1387721D02*
X-1386571Y5938D01*
G01X-1381904D02*
X-1381367Y6041D01*
X-1380754Y6351D01*
X-1380371Y6868D01*
X-1380217Y7591D01*
X-1380371Y8315D01*
X-1380831Y8935D01*
X-1381521Y9245D01*
X-1382287D01*
X-1382747Y9451D01*
X-1383131Y9968D01*
X-1383284Y10691D01*
X-1383054Y11415D01*
X-1382517Y11931D01*
X-1381904Y12138D01*
X-1381291Y11931D01*
X-1380754Y11415D01*
X-1380524Y10691D01*
X-1380677Y9968D01*
X-1381061Y9451D01*
X-1381521Y9245D01*
X-1382287D01*
X-1382977Y8935D01*
X-1383437Y8315D01*
X-1383591Y7591D01*
X-1383437Y6868D01*
X-1383054Y6351D01*
X-1382441Y6041D01*
X-1381904Y5938D01*
G01X-1375857D02*
X-1375704Y7281D01*
X-1375474Y8418D01*
X-1375167Y9451D01*
X-1374784Y10588D01*
X-1374171Y12138D01*
X-1377237D01*
G01X-1390437Y15938D02*
Y22138D01*
X-1388521D01*
X-1387907Y21828D01*
X-1387524Y21415D01*
X-1387371Y20588D01*
X-1387524Y19761D01*
X-1387984Y19245D01*
X-1388521Y18935D01*
X-1390437D01*
G01X-1388521D02*
X-1387371Y15938D01*
G01X-1384007Y16661D02*
X-1383471Y16145D01*
X-1382857Y15938D01*
X-1382244Y16145D01*
X-1381707Y16764D01*
X-1381324Y17695D01*
X-1381171Y18625D01*
Y19761D01*
X-1381324Y20691D01*
X-1381707Y21518D01*
X-1382167Y21931D01*
X-1382704Y22138D01*
X-1383317Y21931D01*
X-1383777Y21518D01*
X-1384084Y20898D01*
X-1384237Y20071D01*
X-1384084Y19348D01*
X-1383701Y18625D01*
X-1383241Y18211D01*
X-1382704Y18108D01*
X-1382091Y18315D01*
X-1381631Y18831D01*
X-1381171Y19761D01*
G01X-1376504Y15938D02*
X-1375967Y16041D01*
X-1375354Y16351D01*
X-1374971Y16868D01*
X-1374817Y17591D01*
X-1374971Y18315D01*
X-1375431Y18935D01*
X-1376121Y19245D01*
X-1376887D01*
X-1377347Y19451D01*
X-1377731Y19968D01*
X-1377884Y20691D01*
X-1377654Y21415D01*
X-1377117Y21931D01*
X-1376504Y22138D01*
X-1375891Y21931D01*
X-1375354Y21415D01*
X-1375124Y20691D01*
X-1375277Y19968D01*
X-1375661Y19451D01*
X-1376121Y19245D01*
X-1376887D01*
X-1377577Y18935D01*
X-1378037Y18315D01*
X-1378191Y17591D01*
X-1378037Y16868D01*
X-1377654Y16351D01*
X-1377041Y16041D01*
X-1376504Y15938D01*
G01X-1390437Y24938D02*
Y31138D01*
X-1388521D01*
X-1387907Y30828D01*
X-1387524Y30415D01*
X-1387371Y29588D01*
X-1387524Y28761D01*
X-1387984Y28245D01*
X-1388521Y27935D01*
X-1390437D01*
G01X-1388521D02*
X-1387371Y24938D01*
G01X-1384007Y25661D02*
X-1383471Y25145D01*
X-1382857Y24938D01*
X-1382244Y25145D01*
X-1381707Y25764D01*
X-1381324Y26695D01*
X-1381171Y27625D01*
Y28761D01*
X-1381324Y29691D01*
X-1381707Y30518D01*
X-1382167Y30931D01*
X-1382704Y31138D01*
X-1383317Y30931D01*
X-1383777Y30518D01*
X-1384084Y29898D01*
X-1384237Y29071D01*
X-1384084Y28348D01*
X-1383701Y27625D01*
X-1383241Y27211D01*
X-1382704Y27108D01*
X-1382091Y27315D01*
X-1381631Y27831D01*
X-1381171Y28761D01*
G01X-1376657Y24938D02*
X-1376504Y26281D01*
X-1376274Y27418D01*
X-1375967Y28451D01*
X-1375584Y29588D01*
X-1374971Y31138D01*
X-1378037D01*
G01X-1391537Y79738D02*
Y85938D01*
X-1389621D01*
X-1389007Y85628D01*
X-1388624Y85215D01*
X-1388471Y84388D01*
X-1388624Y83561D01*
X-1389084Y83045D01*
X-1389621Y82735D01*
X-1391537D01*
G01X-1389621D02*
X-1388471Y79738D01*
G01X-1385491Y80978D02*
X-1385031Y80255D01*
X-1384417Y79841D01*
X-1383727Y79738D01*
X-1383114Y79841D01*
X-1382501Y80358D01*
X-1382117Y80978D01*
X-1382041Y81598D01*
X-1382194Y82321D01*
X-1382731Y82838D01*
X-1383267Y83045D01*
X-1383957D01*
G01X-1383267D02*
X-1382807Y83355D01*
X-1382424Y83871D01*
X-1382271Y84491D01*
X-1382424Y85111D01*
X-1382807Y85628D01*
X-1383497Y85938D01*
X-1384187Y85835D01*
X-1384877Y85421D01*
G01X-1377604Y85938D02*
X-1378217Y85731D01*
X-1378677Y85215D01*
X-1378984Y84595D01*
X-1379214Y83768D01*
X-1379291Y82838D01*
X-1379214Y81908D01*
X-1378984Y81081D01*
X-1378677Y80461D01*
X-1378217Y79945D01*
X-1377604Y79738D01*
X-1376991Y79945D01*
X-1376531Y80461D01*
X-1376224Y81081D01*
X-1375994Y81908D01*
X-1375917Y82838D01*
X-1375994Y83768D01*
X-1376224Y84595D01*
X-1376531Y85215D01*
X-1376991Y85731D01*
X-1377604Y85938D01*
G01X-1372861Y84905D02*
X-1372401Y85525D01*
X-1371864Y85835D01*
X-1371251Y85938D01*
X-1370484Y85731D01*
X-1369947Y85215D01*
X-1369794Y84595D01*
X-1369871Y83975D01*
X-1370177Y83458D01*
X-1371711Y82425D01*
X-1372401Y81701D01*
X-1372861Y80668D01*
X-1373014Y79738D01*
X-1369794D01*
G01X-1391537Y88738D02*
Y94938D01*
X-1389621D01*
X-1389007Y94628D01*
X-1388624Y94215D01*
X-1388471Y93388D01*
X-1388624Y92561D01*
X-1389084Y92045D01*
X-1389621Y91735D01*
X-1391537D01*
G01X-1389621D02*
X-1388471Y88738D01*
G01X-1385261Y93905D02*
X-1384801Y94525D01*
X-1384264Y94835D01*
X-1383651Y94938D01*
X-1382884Y94731D01*
X-1382347Y94215D01*
X-1382194Y93595D01*
X-1382271Y92975D01*
X-1382577Y92458D01*
X-1384111Y91425D01*
X-1384801Y90701D01*
X-1385261Y89668D01*
X-1385414Y88738D01*
X-1382194D01*
G01X-1377604D02*
X-1377067Y88841D01*
X-1376454Y89151D01*
X-1376071Y89668D01*
X-1375917Y90391D01*
X-1376071Y91115D01*
X-1376531Y91735D01*
X-1377221Y92045D01*
X-1377987D01*
X-1378447Y92251D01*
X-1378831Y92768D01*
X-1378984Y93491D01*
X-1378754Y94215D01*
X-1378217Y94731D01*
X-1377604Y94938D01*
X-1376991Y94731D01*
X-1376454Y94215D01*
X-1376224Y93491D01*
X-1376377Y92768D01*
X-1376761Y92251D01*
X-1377221Y92045D01*
X-1377987D01*
X-1378677Y91735D01*
X-1379137Y91115D01*
X-1379291Y90391D01*
X-1379137Y89668D01*
X-1378754Y89151D01*
X-1378141Y88841D01*
X-1377604Y88738D01*
G01X-1372707Y89461D02*
X-1372171Y88945D01*
X-1371557Y88738D01*
X-1370944Y88945D01*
X-1370407Y89564D01*
X-1370024Y90495D01*
X-1369871Y91425D01*
Y92561D01*
X-1370024Y93491D01*
X-1370407Y94318D01*
X-1370867Y94731D01*
X-1371404Y94938D01*
X-1372017Y94731D01*
X-1372477Y94318D01*
X-1372784Y93698D01*
X-1372937Y92871D01*
X-1372784Y92148D01*
X-1372401Y91425D01*
X-1371941Y91011D01*
X-1371404Y90908D01*
X-1370791Y91115D01*
X-1370331Y91631D01*
X-1369871Y92561D01*
G01X-1385537Y114738D02*
Y120938D01*
X-1383621D01*
X-1383007Y120628D01*
X-1382624Y120215D01*
X-1382471Y119388D01*
X-1382624Y118561D01*
X-1383084Y118045D01*
X-1383621Y117735D01*
X-1385537D01*
G01X-1383621D02*
X-1382471Y114738D01*
G01X-1379491Y115978D02*
X-1379031Y115255D01*
X-1378417Y114841D01*
X-1377727Y114738D01*
X-1377114Y114841D01*
X-1376501Y115358D01*
X-1376117Y115978D01*
X-1376041Y116598D01*
X-1376194Y117321D01*
X-1376731Y117838D01*
X-1377267Y118045D01*
X-1377957D01*
G01X-1377267D02*
X-1376807Y118355D01*
X-1376424Y118871D01*
X-1376271Y119491D01*
X-1376424Y120111D01*
X-1376807Y120628D01*
X-1377497Y120938D01*
X-1378187Y120835D01*
X-1378877Y120421D01*
G01X-1371604Y120938D02*
X-1372217Y120731D01*
X-1372677Y120215D01*
X-1372984Y119595D01*
X-1373214Y118768D01*
X-1373291Y117838D01*
X-1373214Y116908D01*
X-1372984Y116081D01*
X-1372677Y115461D01*
X-1372217Y114945D01*
X-1371604Y114738D01*
X-1370991Y114945D01*
X-1370531Y115461D01*
X-1370224Y116081D01*
X-1369994Y116908D01*
X-1369917Y117838D01*
X-1369994Y118768D01*
X-1370224Y119595D01*
X-1370531Y120215D01*
X-1370991Y120731D01*
X-1371604Y120938D01*
G01X-1365404Y114738D02*
Y120938D01*
X-1366324Y119698D01*
G01Y114738D02*
X-1364484D01*
G01X-1385537Y123738D02*
Y129938D01*
X-1383621D01*
X-1383007Y129628D01*
X-1382624Y129215D01*
X-1382471Y128388D01*
X-1382624Y127561D01*
X-1383084Y127045D01*
X-1383621Y126735D01*
X-1385537D01*
G01X-1383621D02*
X-1382471Y123738D01*
G01X-1379261Y128905D02*
X-1378801Y129525D01*
X-1378264Y129835D01*
X-1377651Y129938D01*
X-1376884Y129731D01*
X-1376347Y129215D01*
X-1376194Y128595D01*
X-1376271Y127975D01*
X-1376577Y127458D01*
X-1378111Y126425D01*
X-1378801Y125701D01*
X-1379261Y124668D01*
X-1379414Y123738D01*
X-1376194D01*
G01X-1372907Y124461D02*
X-1372371Y123945D01*
X-1371757Y123738D01*
X-1371144Y123945D01*
X-1370607Y124564D01*
X-1370224Y125495D01*
X-1370071Y126425D01*
Y127561D01*
X-1370224Y128491D01*
X-1370607Y129318D01*
X-1371067Y129731D01*
X-1371604Y129938D01*
X-1372217Y129731D01*
X-1372677Y129318D01*
X-1372984Y128698D01*
X-1373137Y127871D01*
X-1372984Y127148D01*
X-1372601Y126425D01*
X-1372141Y126011D01*
X-1371604Y125908D01*
X-1370991Y126115D01*
X-1370531Y126631D01*
X-1370071Y127561D01*
G01X-1365404Y123738D02*
Y129938D01*
X-1366324Y128698D01*
G01Y123738D02*
X-1364484D01*
G01X-1385537Y132738D02*
Y138938D01*
X-1383621D01*
X-1383007Y138628D01*
X-1382624Y138215D01*
X-1382471Y137388D01*
X-1382624Y136561D01*
X-1383084Y136045D01*
X-1383621Y135735D01*
X-1385537D01*
G01X-1383621D02*
X-1382471Y132738D01*
G01X-1379491Y133978D02*
X-1379031Y133255D01*
X-1378417Y132841D01*
X-1377727Y132738D01*
X-1377114Y132841D01*
X-1376501Y133358D01*
X-1376117Y133978D01*
X-1376041Y134598D01*
X-1376194Y135321D01*
X-1376731Y135838D01*
X-1377267Y136045D01*
X-1377957D01*
G01X-1377267D02*
X-1376807Y136355D01*
X-1376424Y136871D01*
X-1376271Y137491D01*
X-1376424Y138111D01*
X-1376807Y138628D01*
X-1377497Y138938D01*
X-1378187Y138835D01*
X-1378877Y138421D01*
G01X-1371604Y138938D02*
X-1372217Y138731D01*
X-1372677Y138215D01*
X-1372984Y137595D01*
X-1373214Y136768D01*
X-1373291Y135838D01*
X-1373214Y134908D01*
X-1372984Y134081D01*
X-1372677Y133461D01*
X-1372217Y132945D01*
X-1371604Y132738D01*
X-1370991Y132945D01*
X-1370531Y133461D01*
X-1370224Y134081D01*
X-1369994Y134908D01*
X-1369917Y135838D01*
X-1369994Y136768D01*
X-1370224Y137595D01*
X-1370531Y138215D01*
X-1370991Y138731D01*
X-1371604Y138938D01*
G01X-1366861Y135321D02*
X-1366324Y136045D01*
X-1365864Y136458D01*
X-1365251Y136665D01*
X-1364714Y136458D01*
X-1364331Y136045D01*
X-1364024Y135425D01*
X-1363947Y134701D01*
X-1364024Y134081D01*
X-1364331Y133461D01*
X-1364791Y132945D01*
X-1365327Y132738D01*
X-1365941Y132945D01*
X-1366477Y133564D01*
X-1366784Y134495D01*
X-1366861Y135528D01*
X-1366707Y136871D01*
X-1366477Y137595D01*
X-1366094Y138318D01*
X-1365557Y138835D01*
X-1365021Y138938D01*
X-1364484Y138731D01*
X-1364101Y138215D01*
G01X-1385537Y141738D02*
Y147938D01*
X-1383621D01*
X-1383007Y147628D01*
X-1382624Y147215D01*
X-1382471Y146388D01*
X-1382624Y145561D01*
X-1383084Y145045D01*
X-1383621Y144735D01*
X-1385537D01*
G01X-1383621D02*
X-1382471Y141738D01*
G01X-1379491Y142978D02*
X-1379031Y142255D01*
X-1378417Y141841D01*
X-1377727Y141738D01*
X-1377114Y141841D01*
X-1376501Y142358D01*
X-1376117Y142978D01*
X-1376041Y143598D01*
X-1376194Y144321D01*
X-1376731Y144838D01*
X-1377267Y145045D01*
X-1377957D01*
G01X-1377267D02*
X-1376807Y145355D01*
X-1376424Y145871D01*
X-1376271Y146491D01*
X-1376424Y147111D01*
X-1376807Y147628D01*
X-1377497Y147938D01*
X-1378187Y147835D01*
X-1378877Y147421D01*
G01X-1371604Y147938D02*
X-1372217Y147731D01*
X-1372677Y147215D01*
X-1372984Y146595D01*
X-1373214Y145768D01*
X-1373291Y144838D01*
X-1373214Y143908D01*
X-1372984Y143081D01*
X-1372677Y142461D01*
X-1372217Y141945D01*
X-1371604Y141738D01*
X-1370991Y141945D01*
X-1370531Y142461D01*
X-1370224Y143081D01*
X-1369994Y143908D01*
X-1369917Y144838D01*
X-1369994Y145768D01*
X-1370224Y146595D01*
X-1370531Y147215D01*
X-1370991Y147731D01*
X-1371604Y147938D01*
G01X-1365557Y141738D02*
X-1365404Y143081D01*
X-1365174Y144218D01*
X-1364867Y145251D01*
X-1364484Y146388D01*
X-1363871Y147938D01*
X-1366937D01*
G01X-1382317Y156421D02*
X-1382777Y156731D01*
X-1383314Y156938D01*
X-1383927D01*
X-1384617Y156628D01*
X-1385154Y156111D01*
X-1385537Y155491D01*
X-1385844Y154458D01*
X-1385921Y153528D01*
X-1385767Y152598D01*
X-1385537Y151978D01*
X-1385077Y151358D01*
X-1384541Y150945D01*
X-1384004Y150738D01*
X-1383467D01*
X-1382931Y150945D01*
X-1382471Y151255D01*
X-1382087Y151668D01*
G01X-1379261Y155905D02*
X-1378801Y156525D01*
X-1378264Y156835D01*
X-1377651Y156938D01*
X-1376884Y156731D01*
X-1376347Y156215D01*
X-1376194Y155595D01*
X-1376271Y154975D01*
X-1376577Y154458D01*
X-1378111Y153425D01*
X-1378801Y152701D01*
X-1379261Y151668D01*
X-1379414Y150738D01*
X-1376194D01*
G01X-1371604D02*
X-1371067Y150841D01*
X-1370454Y151151D01*
X-1370071Y151668D01*
X-1369917Y152391D01*
X-1370071Y153115D01*
X-1370531Y153735D01*
X-1371221Y154045D01*
X-1371987D01*
X-1372447Y154251D01*
X-1372831Y154768D01*
X-1372984Y155491D01*
X-1372754Y156215D01*
X-1372217Y156731D01*
X-1371604Y156938D01*
X-1370991Y156731D01*
X-1370454Y156215D01*
X-1370224Y155491D01*
X-1370377Y154768D01*
X-1370761Y154251D01*
X-1371221Y154045D01*
X-1371987D01*
X-1372677Y153735D01*
X-1373137Y153115D01*
X-1373291Y152391D01*
X-1373137Y151668D01*
X-1372754Y151151D01*
X-1372141Y150841D01*
X-1371604Y150738D01*
G01X-1367091Y151668D02*
X-1366631Y151151D01*
X-1366094Y150841D01*
X-1365404Y150738D01*
X-1364714Y150945D01*
X-1364177Y151358D01*
X-1363794Y152081D01*
X-1363717Y152908D01*
X-1363871Y153735D01*
X-1364254Y154251D01*
X-1364791Y154665D01*
X-1365327Y154768D01*
X-1365864Y154665D01*
X-1366554Y154251D01*
X-1366324Y156938D01*
X-1364254D01*
G01X-1385537Y159738D02*
Y165938D01*
X-1383621D01*
X-1383007Y165628D01*
X-1382624Y165215D01*
X-1382471Y164388D01*
X-1382624Y163561D01*
X-1383084Y163045D01*
X-1383621Y162735D01*
X-1385537D01*
G01X-1383621D02*
X-1382471Y159738D01*
G01X-1379491Y160978D02*
X-1379031Y160255D01*
X-1378417Y159841D01*
X-1377727Y159738D01*
X-1377114Y159841D01*
X-1376501Y160358D01*
X-1376117Y160978D01*
X-1376041Y161598D01*
X-1376194Y162321D01*
X-1376731Y162838D01*
X-1377267Y163045D01*
X-1377957D01*
G01X-1377267D02*
X-1376807Y163355D01*
X-1376424Y163871D01*
X-1376271Y164491D01*
X-1376424Y165111D01*
X-1376807Y165628D01*
X-1377497Y165938D01*
X-1378187Y165835D01*
X-1378877Y165421D01*
G01X-1371604Y165938D02*
X-1372217Y165731D01*
X-1372677Y165215D01*
X-1372984Y164595D01*
X-1373214Y163768D01*
X-1373291Y162838D01*
X-1373214Y161908D01*
X-1372984Y161081D01*
X-1372677Y160461D01*
X-1372217Y159945D01*
X-1371604Y159738D01*
X-1370991Y159945D01*
X-1370531Y160461D01*
X-1370224Y161081D01*
X-1369994Y161908D01*
X-1369917Y162838D01*
X-1369994Y163768D01*
X-1370224Y164595D01*
X-1370531Y165215D01*
X-1370991Y165731D01*
X-1371604Y165938D01*
G01X-1367091Y160668D02*
X-1366631Y160151D01*
X-1366094Y159841D01*
X-1365404Y159738D01*
X-1364714Y159945D01*
X-1364177Y160358D01*
X-1363794Y161081D01*
X-1363717Y161908D01*
X-1363871Y162735D01*
X-1364254Y163251D01*
X-1364791Y163665D01*
X-1365327Y163768D01*
X-1365864Y163665D01*
X-1366554Y163251D01*
X-1366324Y165938D01*
X-1364254D01*
G01X-1380637Y38938D02*
Y45138D01*
X-1378721D01*
X-1378107Y44828D01*
X-1377724Y44415D01*
X-1377571Y43588D01*
X-1377724Y42761D01*
X-1378184Y42245D01*
X-1378721Y41935D01*
X-1380637D01*
G01X-1378721D02*
X-1377571Y38938D01*
G01X-1372904D02*
X-1372367Y39041D01*
X-1371754Y39351D01*
X-1371371Y39868D01*
X-1371217Y40591D01*
X-1371371Y41315D01*
X-1371831Y41935D01*
X-1372521Y42245D01*
X-1373287D01*
X-1373747Y42451D01*
X-1374131Y42968D01*
X-1374284Y43691D01*
X-1374054Y44415D01*
X-1373517Y44931D01*
X-1372904Y45138D01*
X-1372291Y44931D01*
X-1371754Y44415D01*
X-1371524Y43691D01*
X-1371677Y42968D01*
X-1372061Y42451D01*
X-1372521Y42245D01*
X-1373287D01*
X-1373977Y41935D01*
X-1374437Y41315D01*
X-1374591Y40591D01*
X-1374437Y39868D01*
X-1374054Y39351D01*
X-1373441Y39041D01*
X-1372904Y38938D01*
G01X-1368161Y41521D02*
X-1367624Y42245D01*
X-1367164Y42658D01*
X-1366551Y42865D01*
X-1366014Y42658D01*
X-1365631Y42245D01*
X-1365324Y41625D01*
X-1365247Y40901D01*
X-1365324Y40281D01*
X-1365631Y39661D01*
X-1366091Y39145D01*
X-1366627Y38938D01*
X-1367241Y39145D01*
X-1367777Y39764D01*
X-1368084Y40695D01*
X-1368161Y41728D01*
X-1368007Y43071D01*
X-1367777Y43795D01*
X-1367394Y44518D01*
X-1366857Y45035D01*
X-1366321Y45138D01*
X-1365784Y44931D01*
X-1365401Y44415D01*
G01X-1380637Y48938D02*
Y55138D01*
X-1378721D01*
X-1378107Y54828D01*
X-1377724Y54415D01*
X-1377571Y53588D01*
X-1377724Y52761D01*
X-1378184Y52245D01*
X-1378721Y51935D01*
X-1380637D01*
G01X-1378721D02*
X-1377571Y48938D01*
G01X-1372904D02*
X-1372367Y49041D01*
X-1371754Y49351D01*
X-1371371Y49868D01*
X-1371217Y50591D01*
X-1371371Y51315D01*
X-1371831Y51935D01*
X-1372521Y52245D01*
X-1373287D01*
X-1373747Y52451D01*
X-1374131Y52968D01*
X-1374284Y53691D01*
X-1374054Y54415D01*
X-1373517Y54931D01*
X-1372904Y55138D01*
X-1372291Y54931D01*
X-1371754Y54415D01*
X-1371524Y53691D01*
X-1371677Y52968D01*
X-1372061Y52451D01*
X-1372521Y52245D01*
X-1373287D01*
X-1373977Y51935D01*
X-1374437Y51315D01*
X-1374591Y50591D01*
X-1374437Y49868D01*
X-1374054Y49351D01*
X-1373441Y49041D01*
X-1372904Y48938D01*
G01X-1368391Y49868D02*
X-1367931Y49351D01*
X-1367394Y49041D01*
X-1366704Y48938D01*
X-1366014Y49145D01*
X-1365477Y49558D01*
X-1365094Y50281D01*
X-1365017Y51108D01*
X-1365171Y51935D01*
X-1365554Y52451D01*
X-1366091Y52865D01*
X-1366627Y52968D01*
X-1367164Y52865D01*
X-1367854Y52451D01*
X-1367624Y55138D01*
X-1365554D01*
G01X-1380637Y57938D02*
Y64138D01*
X-1378721D01*
X-1378107Y63828D01*
X-1377724Y63415D01*
X-1377571Y62588D01*
X-1377724Y61761D01*
X-1378184Y61245D01*
X-1378721Y60935D01*
X-1380637D01*
G01X-1378721D02*
X-1377571Y57938D01*
G01X-1372904D02*
X-1372367Y58041D01*
X-1371754Y58351D01*
X-1371371Y58868D01*
X-1371217Y59591D01*
X-1371371Y60315D01*
X-1371831Y60935D01*
X-1372521Y61245D01*
X-1373287D01*
X-1373747Y61451D01*
X-1374131Y61968D01*
X-1374284Y62691D01*
X-1374054Y63415D01*
X-1373517Y63931D01*
X-1372904Y64138D01*
X-1372291Y63931D01*
X-1371754Y63415D01*
X-1371524Y62691D01*
X-1371677Y61968D01*
X-1372061Y61451D01*
X-1372521Y61245D01*
X-1373287D01*
X-1373977Y60935D01*
X-1374437Y60315D01*
X-1374591Y59591D01*
X-1374437Y58868D01*
X-1374054Y58351D01*
X-1373441Y58041D01*
X-1372904Y57938D01*
G01X-1365784D02*
Y64138D01*
X-1368621Y59695D01*
X-1364787D01*
G01X-1380637Y67938D02*
Y74138D01*
X-1378721D01*
X-1378107Y73828D01*
X-1377724Y73415D01*
X-1377571Y72588D01*
X-1377724Y71761D01*
X-1378184Y71245D01*
X-1378721Y70935D01*
X-1380637D01*
G01X-1378721D02*
X-1377571Y67938D01*
G01X-1372904D02*
X-1372367Y68041D01*
X-1371754Y68351D01*
X-1371371Y68868D01*
X-1371217Y69591D01*
X-1371371Y70315D01*
X-1371831Y70935D01*
X-1372521Y71245D01*
X-1373287D01*
X-1373747Y71451D01*
X-1374131Y71968D01*
X-1374284Y72691D01*
X-1374054Y73415D01*
X-1373517Y73931D01*
X-1372904Y74138D01*
X-1372291Y73931D01*
X-1371754Y73415D01*
X-1371524Y72691D01*
X-1371677Y71968D01*
X-1372061Y71451D01*
X-1372521Y71245D01*
X-1373287D01*
X-1373977Y70935D01*
X-1374437Y70315D01*
X-1374591Y69591D01*
X-1374437Y68868D01*
X-1374054Y68351D01*
X-1373441Y68041D01*
X-1372904Y67938D01*
G01X-1368391Y69178D02*
X-1367931Y68455D01*
X-1367317Y68041D01*
X-1366627Y67938D01*
X-1366014Y68041D01*
X-1365401Y68558D01*
X-1365017Y69178D01*
X-1364941Y69798D01*
X-1365094Y70521D01*
X-1365631Y71038D01*
X-1366167Y71245D01*
X-1366857D01*
G01X-1366167D02*
X-1365707Y71555D01*
X-1365324Y72071D01*
X-1365171Y72691D01*
X-1365324Y73311D01*
X-1365707Y73828D01*
X-1366397Y74138D01*
X-1367087Y74035D01*
X-1367777Y73621D01*
G01X-1366537Y78938D02*
Y85138D01*
X-1364621D01*
X-1364007Y84828D01*
X-1363624Y84415D01*
X-1363471Y83588D01*
X-1363624Y82761D01*
X-1364084Y82245D01*
X-1364621Y81935D01*
X-1366537D01*
G01X-1364621D02*
X-1363471Y78938D01*
G01X-1360261Y84105D02*
X-1359801Y84725D01*
X-1359264Y85035D01*
X-1358651Y85138D01*
X-1357884Y84931D01*
X-1357347Y84415D01*
X-1357194Y83795D01*
X-1357271Y83175D01*
X-1357577Y82658D01*
X-1359111Y81625D01*
X-1359801Y80901D01*
X-1360261Y79868D01*
X-1360414Y78938D01*
X-1357194D01*
G01X-1353907Y79661D02*
X-1353371Y79145D01*
X-1352757Y78938D01*
X-1352144Y79145D01*
X-1351607Y79764D01*
X-1351224Y80695D01*
X-1351071Y81625D01*
Y82761D01*
X-1351224Y83691D01*
X-1351607Y84518D01*
X-1352067Y84931D01*
X-1352604Y85138D01*
X-1353217Y84931D01*
X-1353677Y84518D01*
X-1353984Y83898D01*
X-1354137Y83071D01*
X-1353984Y82348D01*
X-1353601Y81625D01*
X-1353141Y81211D01*
X-1352604Y81108D01*
X-1351991Y81315D01*
X-1351531Y81831D01*
X-1351071Y82761D01*
G01X-1346404Y85138D02*
X-1347017Y84931D01*
X-1347477Y84415D01*
X-1347784Y83795D01*
X-1348014Y82968D01*
X-1348091Y82038D01*
X-1348014Y81108D01*
X-1347784Y80281D01*
X-1347477Y79661D01*
X-1347017Y79145D01*
X-1346404Y78938D01*
X-1345791Y79145D01*
X-1345331Y79661D01*
X-1345024Y80281D01*
X-1344794Y81108D01*
X-1344717Y82038D01*
X-1344794Y82968D01*
X-1345024Y83795D01*
X-1345331Y84415D01*
X-1345791Y84931D01*
X-1346404Y85138D01*
G01X-1382437Y96738D02*
Y102938D01*
X-1380521D01*
X-1379907Y102628D01*
X-1379524Y102215D01*
X-1379371Y101388D01*
X-1379524Y100561D01*
X-1379984Y100045D01*
X-1380521Y99735D01*
X-1382437D01*
G01X-1380521D02*
X-1379371Y96738D01*
G01X-1374857D02*
X-1374704Y98081D01*
X-1374474Y99218D01*
X-1374167Y100251D01*
X-1373784Y101388D01*
X-1373171Y102938D01*
X-1376237D01*
G01X-1369807Y97461D02*
X-1369271Y96945D01*
X-1368657Y96738D01*
X-1368044Y96945D01*
X-1367507Y97564D01*
X-1367124Y98495D01*
X-1366971Y99425D01*
Y100561D01*
X-1367124Y101491D01*
X-1367507Y102318D01*
X-1367967Y102731D01*
X-1368504Y102938D01*
X-1369117Y102731D01*
X-1369577Y102318D01*
X-1369884Y101698D01*
X-1370037Y100871D01*
X-1369884Y100148D01*
X-1369501Y99425D01*
X-1369041Y99011D01*
X-1368504Y98908D01*
X-1367891Y99115D01*
X-1367431Y99631D01*
X-1366971Y100561D01*
G01X-1382437Y105738D02*
Y111938D01*
X-1380521D01*
X-1379907Y111628D01*
X-1379524Y111215D01*
X-1379371Y110388D01*
X-1379524Y109561D01*
X-1379984Y109045D01*
X-1380521Y108735D01*
X-1382437D01*
G01X-1380521D02*
X-1379371Y105738D01*
G01X-1374857D02*
X-1374704Y107081D01*
X-1374474Y108218D01*
X-1374167Y109251D01*
X-1373784Y110388D01*
X-1373171Y111938D01*
X-1376237D01*
G01X-1368504Y105738D02*
X-1367967Y105841D01*
X-1367354Y106151D01*
X-1366971Y106668D01*
X-1366817Y107391D01*
X-1366971Y108115D01*
X-1367431Y108735D01*
X-1368121Y109045D01*
X-1368887D01*
X-1369347Y109251D01*
X-1369731Y109768D01*
X-1369884Y110491D01*
X-1369654Y111215D01*
X-1369117Y111731D01*
X-1368504Y111938D01*
X-1367891Y111731D01*
X-1367354Y111215D01*
X-1367124Y110491D01*
X-1367277Y109768D01*
X-1367661Y109251D01*
X-1368121Y109045D01*
X-1368887D01*
X-1369577Y108735D01*
X-1370037Y108115D01*
X-1370191Y107391D01*
X-1370037Y106668D01*
X-1369654Y106151D01*
X-1369041Y105841D01*
X-1368504Y105738D01*
G01X-1371261Y201289D02*
X-1370801Y201909D01*
X-1370264Y202219D01*
X-1369651Y202322D01*
X-1368884Y202115D01*
X-1368347Y201599D01*
X-1368194Y200979D01*
X-1368271Y200359D01*
X-1368577Y199842D01*
X-1370111Y198809D01*
X-1370801Y198085D01*
X-1371261Y197052D01*
X-1371414Y196122D01*
X-1368194D01*
G01X-1369146Y217982D02*
Y224182D01*
X-1371983Y219739D01*
X-1368149D01*
G01X-1383091Y315138D02*
Y310695D01*
X-1382784Y309764D01*
X-1382171Y309145D01*
X-1381404Y308938D01*
X-1380637Y309145D01*
X-1380024Y309764D01*
X-1379717Y310695D01*
Y315138D01*
G01X-1374284Y308938D02*
Y315138D01*
X-1377121Y310695D01*
X-1373287D01*
G01X-1355704Y31205D02*
X-1361904D01*
Y33121D01*
X-1361594Y33735D01*
X-1361181Y34118D01*
X-1360354Y34271D01*
X-1359527Y34118D01*
X-1359011Y33658D01*
X-1358701Y33121D01*
Y31205D01*
G01Y33121D02*
X-1355704Y34271D01*
G01X-1360871Y37481D02*
X-1361491Y37941D01*
X-1361801Y38478D01*
X-1361904Y39091D01*
X-1361697Y39858D01*
X-1361181Y40395D01*
X-1360561Y40548D01*
X-1359941Y40471D01*
X-1359424Y40165D01*
X-1358391Y38631D01*
X-1357667Y37941D01*
X-1356634Y37481D01*
X-1355704Y37328D01*
Y40548D01*
G01Y44985D02*
X-1357047Y45138D01*
X-1358184Y45368D01*
X-1359217Y45675D01*
X-1360354Y46058D01*
X-1361904Y46671D01*
Y43605D01*
G01X-1358287Y49881D02*
X-1359011Y50418D01*
X-1359424Y50878D01*
X-1359631Y51491D01*
X-1359424Y52028D01*
X-1359011Y52411D01*
X-1358391Y52718D01*
X-1357667Y52795D01*
X-1357047Y52718D01*
X-1356427Y52411D01*
X-1355911Y51951D01*
X-1355704Y51415D01*
X-1355911Y50801D01*
X-1356530Y50265D01*
X-1357461Y49958D01*
X-1358494Y49881D01*
X-1359837Y50035D01*
X-1360561Y50265D01*
X-1361284Y50648D01*
X-1361801Y51185D01*
X-1361904Y51721D01*
X-1361697Y52258D01*
X-1361181Y52641D01*
G01X-1355804Y55205D02*
X-1362004D01*
Y57121D01*
X-1361694Y57735D01*
X-1361281Y58118D01*
X-1360454Y58271D01*
X-1359627Y58118D01*
X-1359111Y57658D01*
X-1358801Y57121D01*
Y55205D01*
G01Y57121D02*
X-1355804Y58271D01*
G01X-1360971Y61481D02*
X-1361591Y61941D01*
X-1361901Y62478D01*
X-1362004Y63091D01*
X-1361797Y63858D01*
X-1361281Y64395D01*
X-1360661Y64548D01*
X-1360041Y64471D01*
X-1359524Y64165D01*
X-1358491Y62631D01*
X-1357767Y61941D01*
X-1356734Y61481D01*
X-1355804Y61328D01*
Y64548D01*
G01Y68985D02*
X-1357147Y69138D01*
X-1358284Y69368D01*
X-1359317Y69675D01*
X-1360454Y70058D01*
X-1362004Y70671D01*
Y67605D01*
G01X-1355804Y75185D02*
X-1357147Y75338D01*
X-1358284Y75568D01*
X-1359317Y75875D01*
X-1360454Y76258D01*
X-1362004Y76871D01*
Y73805D01*
G01X-1360528Y90370D02*
Y96570D01*
X-1361448Y95330D01*
G01Y90370D02*
X-1359608D01*
G01X-1356015Y91300D02*
X-1355555Y90783D01*
X-1355018Y90473D01*
X-1354328Y90370D01*
X-1353638Y90577D01*
X-1353101Y90990D01*
X-1352718Y91713D01*
X-1352641Y92540D01*
X-1352795Y93367D01*
X-1353178Y93883D01*
X-1353715Y94297D01*
X-1354251Y94400D01*
X-1354788Y94297D01*
X-1355478Y93883D01*
X-1355248Y96570D01*
X-1353178D01*
G01X-1356217Y130529D02*
X-1355680Y131253D01*
X-1355220Y131666D01*
X-1354607Y131873D01*
X-1354070Y131666D01*
X-1353687Y131253D01*
X-1353380Y130633D01*
X-1353303Y129909D01*
X-1353380Y129289D01*
X-1353687Y128669D01*
X-1354147Y128153D01*
X-1354683Y127946D01*
X-1355297Y128153D01*
X-1355833Y128772D01*
X-1356140Y129703D01*
X-1356217Y130736D01*
X-1356063Y132079D01*
X-1355833Y132803D01*
X-1355450Y133526D01*
X-1354913Y134043D01*
X-1354377Y134146D01*
X-1353840Y133939D01*
X-1353457Y133423D01*
G01X-1350604Y144605D02*
X-1356804D01*
Y146521D01*
X-1356494Y147135D01*
X-1356081Y147518D01*
X-1355254Y147671D01*
X-1354427Y147518D01*
X-1353911Y147058D01*
X-1353601Y146521D01*
Y144605D01*
G01Y146521D02*
X-1350604Y147671D01*
G01X-1351844Y150651D02*
X-1351121Y151111D01*
X-1350707Y151725D01*
X-1350604Y152415D01*
X-1350707Y153028D01*
X-1351224Y153641D01*
X-1351844Y154025D01*
X-1352464Y154101D01*
X-1353187Y153948D01*
X-1353704Y153411D01*
X-1353911Y152875D01*
Y152185D01*
G01Y152875D02*
X-1354221Y153335D01*
X-1354737Y153718D01*
X-1355357Y153871D01*
X-1355977Y153718D01*
X-1356494Y153335D01*
X-1356804Y152645D01*
X-1356701Y151955D01*
X-1356287Y151265D01*
G01X-1356804Y158538D02*
X-1356597Y157925D01*
X-1356081Y157465D01*
X-1355461Y157158D01*
X-1354634Y156928D01*
X-1353704Y156851D01*
X-1352774Y156928D01*
X-1351947Y157158D01*
X-1351327Y157465D01*
X-1350811Y157925D01*
X-1350604Y158538D01*
X-1350811Y159151D01*
X-1351327Y159611D01*
X-1351947Y159918D01*
X-1352774Y160148D01*
X-1353704Y160225D01*
X-1354634Y160148D01*
X-1355461Y159918D01*
X-1356081Y159611D01*
X-1356597Y159151D01*
X-1356804Y158538D01*
G01X-1351844Y163051D02*
X-1351121Y163511D01*
X-1350707Y164125D01*
X-1350604Y164815D01*
X-1350707Y165428D01*
X-1351224Y166041D01*
X-1351844Y166425D01*
X-1352464Y166501D01*
X-1353187Y166348D01*
X-1353704Y165811D01*
X-1353911Y165275D01*
Y164585D01*
G01Y165275D02*
X-1354221Y165735D01*
X-1354737Y166118D01*
X-1355357Y166271D01*
X-1355977Y166118D01*
X-1356494Y165735D01*
X-1356804Y165045D01*
X-1356701Y164355D01*
X-1356287Y163665D01*
G01X-1366804Y170738D02*
X-1360604D01*
G01X-1366804Y168975D02*
Y172501D01*
G01X-1360604Y175405D02*
X-1366804D01*
Y177245D01*
X-1366494Y177858D01*
X-1365771Y178318D01*
X-1364944Y178471D01*
X-1364117Y178318D01*
X-1363497Y177935D01*
X-1363187Y177245D01*
Y175405D01*
G01X-1360604Y183138D02*
X-1366804D01*
X-1365564Y182218D01*
G01X-1360604D02*
Y184058D01*
G01X-1363187Y187881D02*
X-1363911Y188418D01*
X-1364324Y188878D01*
X-1364531Y189491D01*
X-1364324Y190028D01*
X-1363911Y190411D01*
X-1363291Y190718D01*
X-1362567Y190795D01*
X-1361947Y190718D01*
X-1361327Y190411D01*
X-1360811Y189951D01*
X-1360604Y189415D01*
X-1360811Y188801D01*
X-1361430Y188265D01*
X-1362361Y187958D01*
X-1363394Y187881D01*
X-1364737Y188035D01*
X-1365461Y188265D01*
X-1366184Y188648D01*
X-1366701Y189185D01*
X-1366804Y189721D01*
X-1366597Y190258D01*
X-1366081Y190641D01*
G01X-1352804Y170738D02*
X-1346604D01*
G01X-1352804Y168975D02*
Y172501D01*
G01X-1346604Y175405D02*
X-1352804D01*
Y177245D01*
X-1352494Y177858D01*
X-1351771Y178318D01*
X-1350944Y178471D01*
X-1350117Y178318D01*
X-1349497Y177935D01*
X-1349187Y177245D01*
Y175405D01*
G01X-1346604Y183138D02*
X-1352804D01*
X-1351564Y182218D01*
G01X-1346604D02*
Y184058D01*
G01Y189185D02*
X-1347947Y189338D01*
X-1349084Y189568D01*
X-1350117Y189875D01*
X-1351254Y190258D01*
X-1352804Y190871D01*
Y187805D01*
G01X-1356704Y328038D02*
X-1356167Y328141D01*
X-1355554Y328451D01*
X-1355171Y328968D01*
X-1355017Y329691D01*
X-1355171Y330415D01*
X-1355631Y331035D01*
X-1356321Y331345D01*
X-1357087D01*
X-1357547Y331551D01*
X-1357931Y332068D01*
X-1358084Y332791D01*
X-1357854Y333515D01*
X-1357317Y334031D01*
X-1356704Y334238D01*
X-1356091Y334031D01*
X-1355554Y333515D01*
X-1355324Y332791D01*
X-1355477Y332068D01*
X-1355861Y331551D01*
X-1356321Y331345D01*
X-1357087D01*
X-1357777Y331035D01*
X-1358237Y330415D01*
X-1358391Y329691D01*
X-1358237Y328968D01*
X-1357854Y328451D01*
X-1357241Y328141D01*
X-1356704Y328038D01*
G01X-1362287Y381525D02*
X-1362597Y381065D01*
X-1362804Y380528D01*
Y379915D01*
X-1362494Y379225D01*
X-1361977Y378688D01*
X-1361357Y378305D01*
X-1360324Y377998D01*
X-1359394Y377921D01*
X-1358464Y378075D01*
X-1357844Y378305D01*
X-1357224Y378765D01*
X-1356811Y379301D01*
X-1356604Y379838D01*
Y380375D01*
X-1356811Y380911D01*
X-1357121Y381371D01*
X-1357534Y381755D01*
G01X-1356604Y386038D02*
X-1362804D01*
X-1361564Y385118D01*
G01X-1356604D02*
Y386958D01*
G01Y392238D02*
X-1356707Y392775D01*
X-1357017Y393388D01*
X-1357534Y393771D01*
X-1358257Y393925D01*
X-1358981Y393771D01*
X-1359601Y393311D01*
X-1359911Y392621D01*
Y391855D01*
X-1360117Y391395D01*
X-1360634Y391011D01*
X-1361357Y390858D01*
X-1362081Y391088D01*
X-1362597Y391625D01*
X-1362804Y392238D01*
X-1362597Y392851D01*
X-1362081Y393388D01*
X-1361357Y393618D01*
X-1360634Y393465D01*
X-1360117Y393081D01*
X-1359911Y392621D01*
Y391855D01*
X-1359601Y391165D01*
X-1358981Y390705D01*
X-1358257Y390551D01*
X-1357534Y390705D01*
X-1357017Y391088D01*
X-1356707Y391701D01*
X-1356604Y392238D01*
G01X-1351617Y417021D02*
X-1352077Y417331D01*
X-1352614Y417538D01*
X-1353227D01*
X-1353917Y417228D01*
X-1354454Y416711D01*
X-1354837Y416091D01*
X-1355144Y415058D01*
X-1355221Y414128D01*
X-1355067Y413198D01*
X-1354837Y412578D01*
X-1354377Y411958D01*
X-1353841Y411545D01*
X-1353304Y411338D01*
X-1352767D01*
X-1352231Y411545D01*
X-1351771Y411855D01*
X-1351387Y412268D01*
G01X-1346184Y411338D02*
Y417538D01*
X-1349021Y413095D01*
X-1345187D01*
G01X-1340904Y411338D02*
X-1340367Y411441D01*
X-1339754Y411751D01*
X-1339371Y412268D01*
X-1339217Y412991D01*
X-1339371Y413715D01*
X-1339831Y414335D01*
X-1340521Y414645D01*
X-1341287D01*
X-1341747Y414851D01*
X-1342131Y415368D01*
X-1342284Y416091D01*
X-1342054Y416815D01*
X-1341517Y417331D01*
X-1340904Y417538D01*
X-1340291Y417331D01*
X-1339754Y416815D01*
X-1339524Y416091D01*
X-1339677Y415368D01*
X-1340061Y414851D01*
X-1340521Y414645D01*
X-1341287D01*
X-1341977Y414335D01*
X-1342437Y413715D01*
X-1342591Y412991D01*
X-1342437Y412268D01*
X-1342054Y411751D01*
X-1341441Y411441D01*
X-1340904Y411338D01*
G01X-1349617Y429021D02*
X-1350077Y429331D01*
X-1350614Y429538D01*
X-1351227D01*
X-1351917Y429228D01*
X-1352454Y428711D01*
X-1352837Y428091D01*
X-1353144Y427058D01*
X-1353221Y426128D01*
X-1353067Y425198D01*
X-1352837Y424578D01*
X-1352377Y423958D01*
X-1351841Y423545D01*
X-1351304Y423338D01*
X-1350767D01*
X-1350231Y423545D01*
X-1349771Y423855D01*
X-1349387Y424268D01*
G01X-1346791D02*
X-1346331Y423751D01*
X-1345794Y423441D01*
X-1345104Y423338D01*
X-1344414Y423545D01*
X-1343877Y423958D01*
X-1343494Y424681D01*
X-1343417Y425508D01*
X-1343571Y426335D01*
X-1343954Y426851D01*
X-1344491Y427265D01*
X-1345027Y427368D01*
X-1345564Y427265D01*
X-1346254Y426851D01*
X-1346024Y429538D01*
X-1343954D01*
G01X-1340361Y428505D02*
X-1339901Y429125D01*
X-1339364Y429435D01*
X-1338751Y429538D01*
X-1337984Y429331D01*
X-1337447Y428815D01*
X-1337294Y428195D01*
X-1337371Y427575D01*
X-1337677Y427058D01*
X-1339211Y426025D01*
X-1339901Y425301D01*
X-1340361Y424268D01*
X-1340514Y423338D01*
X-1337294D01*
G01X-1354704Y430038D02*
X-1354167Y430141D01*
X-1353554Y430451D01*
X-1353171Y430968D01*
X-1353017Y431691D01*
X-1353171Y432415D01*
X-1353631Y433035D01*
X-1354321Y433345D01*
X-1355087D01*
X-1355547Y433551D01*
X-1355931Y434068D01*
X-1356084Y434791D01*
X-1355854Y435515D01*
X-1355317Y436031D01*
X-1354704Y436238D01*
X-1354091Y436031D01*
X-1353554Y435515D01*
X-1353324Y434791D01*
X-1353477Y434068D01*
X-1353861Y433551D01*
X-1354321Y433345D01*
X-1355087D01*
X-1355777Y433035D01*
X-1356237Y432415D01*
X-1356391Y431691D01*
X-1356237Y430968D01*
X-1355854Y430451D01*
X-1355241Y430141D01*
X-1354704Y430038D01*
G01X-1358857Y440038D02*
X-1358704Y441381D01*
X-1358474Y442518D01*
X-1358167Y443551D01*
X-1357784Y444688D01*
X-1357171Y446238D01*
X-1360237D01*
G01X-1360161Y459621D02*
X-1359624Y460345D01*
X-1359164Y460758D01*
X-1358551Y460965D01*
X-1358014Y460758D01*
X-1357631Y460345D01*
X-1357324Y459725D01*
X-1357247Y459001D01*
X-1357324Y458381D01*
X-1357631Y457761D01*
X-1358091Y457245D01*
X-1358627Y457038D01*
X-1359241Y457245D01*
X-1359777Y457864D01*
X-1360084Y458795D01*
X-1360161Y459828D01*
X-1360007Y461171D01*
X-1359777Y461895D01*
X-1359394Y462618D01*
X-1358857Y463135D01*
X-1358321Y463238D01*
X-1357784Y463031D01*
X-1357401Y462515D01*
G01X-1358391Y465968D02*
X-1357931Y465451D01*
X-1357394Y465141D01*
X-1356704Y465038D01*
X-1356014Y465245D01*
X-1355477Y465658D01*
X-1355094Y466381D01*
X-1355017Y467208D01*
X-1355171Y468035D01*
X-1355554Y468551D01*
X-1356091Y468965D01*
X-1356627Y469068D01*
X-1357164Y468965D01*
X-1357854Y468551D01*
X-1357624Y471238D01*
X-1355554D01*
G01X-1353617Y479021D02*
X-1354077Y479331D01*
X-1354614Y479538D01*
X-1355227D01*
X-1355917Y479228D01*
X-1356454Y478711D01*
X-1356837Y478091D01*
X-1357144Y477058D01*
X-1357221Y476128D01*
X-1357067Y475198D01*
X-1356837Y474578D01*
X-1356377Y473958D01*
X-1355841Y473545D01*
X-1355304Y473338D01*
X-1354767D01*
X-1354231Y473545D01*
X-1353771Y473855D01*
X-1353387Y474268D01*
G01X-1350791D02*
X-1350331Y473751D01*
X-1349794Y473441D01*
X-1349104Y473338D01*
X-1348414Y473545D01*
X-1347877Y473958D01*
X-1347494Y474681D01*
X-1347417Y475508D01*
X-1347571Y476335D01*
X-1347954Y476851D01*
X-1348491Y477265D01*
X-1349027Y477368D01*
X-1349564Y477265D01*
X-1350254Y476851D01*
X-1350024Y479538D01*
X-1347954D01*
G01X-1344591Y474578D02*
X-1344131Y473855D01*
X-1343517Y473441D01*
X-1342827Y473338D01*
X-1342214Y473441D01*
X-1341601Y473958D01*
X-1341217Y474578D01*
X-1341141Y475198D01*
X-1341294Y475921D01*
X-1341831Y476438D01*
X-1342367Y476645D01*
X-1343057D01*
G01X-1342367D02*
X-1341907Y476955D01*
X-1341524Y477471D01*
X-1341371Y478091D01*
X-1341524Y478711D01*
X-1341907Y479228D01*
X-1342597Y479538D01*
X-1343287Y479435D01*
X-1343977Y479021D01*
G01X-1357617Y492021D02*
X-1358077Y492331D01*
X-1358614Y492538D01*
X-1359227D01*
X-1359917Y492228D01*
X-1360454Y491711D01*
X-1360837Y491091D01*
X-1361144Y490058D01*
X-1361221Y489128D01*
X-1361067Y488198D01*
X-1360837Y487578D01*
X-1360377Y486958D01*
X-1359841Y486545D01*
X-1359304Y486338D01*
X-1358767D01*
X-1358231Y486545D01*
X-1357771Y486855D01*
X-1357387Y487268D01*
G01X-1354791D02*
X-1354331Y486751D01*
X-1353794Y486441D01*
X-1353104Y486338D01*
X-1352414Y486545D01*
X-1351877Y486958D01*
X-1351494Y487681D01*
X-1351417Y488508D01*
X-1351571Y489335D01*
X-1351954Y489851D01*
X-1352491Y490265D01*
X-1353027Y490368D01*
X-1353564Y490265D01*
X-1354254Y489851D01*
X-1354024Y492538D01*
X-1351954D01*
G01X-1346904D02*
X-1347517Y492331D01*
X-1347977Y491815D01*
X-1348284Y491195D01*
X-1348514Y490368D01*
X-1348591Y489438D01*
X-1348514Y488508D01*
X-1348284Y487681D01*
X-1347977Y487061D01*
X-1347517Y486545D01*
X-1346904Y486338D01*
X-1346291Y486545D01*
X-1345831Y487061D01*
X-1345524Y487681D01*
X-1345294Y488508D01*
X-1345217Y489438D01*
X-1345294Y490368D01*
X-1345524Y491195D01*
X-1345831Y491815D01*
X-1346291Y492331D01*
X-1346904Y492538D01*
G01X-1339004Y79138D02*
Y72938D01*
G01X-1340767Y79138D02*
X-1337241D01*
G01X-1334337Y72938D02*
Y79138D01*
X-1332497D01*
X-1331884Y78828D01*
X-1331424Y78105D01*
X-1331271Y77278D01*
X-1331424Y76451D01*
X-1331807Y75831D01*
X-1332497Y75521D01*
X-1334337D01*
G01X-1328061D02*
X-1327524Y76245D01*
X-1327064Y76658D01*
X-1326451Y76865D01*
X-1325914Y76658D01*
X-1325531Y76245D01*
X-1325224Y75625D01*
X-1325147Y74901D01*
X-1325224Y74281D01*
X-1325531Y73661D01*
X-1325991Y73145D01*
X-1326527Y72938D01*
X-1327141Y73145D01*
X-1327677Y73764D01*
X-1327984Y74695D01*
X-1328061Y75728D01*
X-1327907Y77071D01*
X-1327677Y77795D01*
X-1327294Y78518D01*
X-1326757Y79035D01*
X-1326221Y79138D01*
X-1325684Y78931D01*
X-1325301Y78415D01*
G01X-1320404Y72938D02*
Y79138D01*
X-1321324Y77898D01*
G01Y72938D02*
X-1319484D01*
G01X-1340534Y82608D02*
Y88808D01*
X-1341454Y87568D01*
G01Y82608D02*
X-1339614D01*
G01X-1335791Y85191D02*
X-1335254Y85915D01*
X-1334794Y86328D01*
X-1334181Y86535D01*
X-1333644Y86328D01*
X-1333261Y85915D01*
X-1332954Y85295D01*
X-1332877Y84571D01*
X-1332954Y83951D01*
X-1333261Y83331D01*
X-1333721Y82815D01*
X-1334257Y82608D01*
X-1334871Y82815D01*
X-1335407Y83434D01*
X-1335714Y84365D01*
X-1335791Y85398D01*
X-1335637Y86741D01*
X-1335407Y87465D01*
X-1335024Y88188D01*
X-1334487Y88705D01*
X-1333951Y88808D01*
X-1333414Y88601D01*
X-1333031Y88085D01*
G01X-1340591Y114938D02*
Y110495D01*
X-1340284Y109564D01*
X-1339671Y108945D01*
X-1338904Y108738D01*
X-1338137Y108945D01*
X-1337524Y109564D01*
X-1337217Y110495D01*
Y114938D01*
G01X-1334161Y113905D02*
X-1333701Y114525D01*
X-1333164Y114835D01*
X-1332551Y114938D01*
X-1331784Y114731D01*
X-1331247Y114215D01*
X-1331094Y113595D01*
X-1331171Y112975D01*
X-1331477Y112458D01*
X-1333011Y111425D01*
X-1333701Y110701D01*
X-1334161Y109668D01*
X-1334314Y108738D01*
X-1331094D01*
G01X-1327807Y109461D02*
X-1327271Y108945D01*
X-1326657Y108738D01*
X-1326044Y108945D01*
X-1325507Y109564D01*
X-1325124Y110495D01*
X-1324971Y111425D01*
Y112561D01*
X-1325124Y113491D01*
X-1325507Y114318D01*
X-1325967Y114731D01*
X-1326504Y114938D01*
X-1327117Y114731D01*
X-1327577Y114318D01*
X-1327884Y113698D01*
X-1328037Y112871D01*
X-1327884Y112148D01*
X-1327501Y111425D01*
X-1327041Y111011D01*
X-1326504Y110908D01*
X-1325891Y111115D01*
X-1325431Y111631D01*
X-1324971Y112561D01*
G01X-1341585Y135476D02*
X-1341125Y134959D01*
X-1340588Y134649D01*
X-1339898Y134546D01*
X-1339208Y134753D01*
X-1338671Y135166D01*
X-1338288Y135889D01*
X-1338211Y136716D01*
X-1338365Y137543D01*
X-1338748Y138059D01*
X-1339285Y138473D01*
X-1339821Y138576D01*
X-1340358Y138473D01*
X-1341048Y138059D01*
X-1340818Y140746D01*
X-1338748D01*
G01X-1340604Y144605D02*
X-1346804D01*
Y146521D01*
X-1346494Y147135D01*
X-1346081Y147518D01*
X-1345254Y147671D01*
X-1344427Y147518D01*
X-1343911Y147058D01*
X-1343601Y146521D01*
Y144605D01*
G01Y146521D02*
X-1340604Y147671D01*
G01X-1341844Y150651D02*
X-1341121Y151111D01*
X-1340707Y151725D01*
X-1340604Y152415D01*
X-1340707Y153028D01*
X-1341224Y153641D01*
X-1341844Y154025D01*
X-1342464Y154101D01*
X-1343187Y153948D01*
X-1343704Y153411D01*
X-1343911Y152875D01*
Y152185D01*
G01Y152875D02*
X-1344221Y153335D01*
X-1344737Y153718D01*
X-1345357Y153871D01*
X-1345977Y153718D01*
X-1346494Y153335D01*
X-1346804Y152645D01*
X-1346701Y151955D01*
X-1346287Y151265D01*
G01X-1346804Y158538D02*
X-1346597Y157925D01*
X-1346081Y157465D01*
X-1345461Y157158D01*
X-1344634Y156928D01*
X-1343704Y156851D01*
X-1342774Y156928D01*
X-1341947Y157158D01*
X-1341327Y157465D01*
X-1340811Y157925D01*
X-1340604Y158538D01*
X-1340811Y159151D01*
X-1341327Y159611D01*
X-1341947Y159918D01*
X-1342774Y160148D01*
X-1343704Y160225D01*
X-1344634Y160148D01*
X-1345461Y159918D01*
X-1346081Y159611D01*
X-1346597Y159151D01*
X-1346804Y158538D01*
G01X-1340604Y165658D02*
X-1346804D01*
X-1342361Y162821D01*
Y166655D01*
G01X-1336319Y147825D02*
X-1336629Y147365D01*
X-1336836Y146828D01*
Y146215D01*
X-1336526Y145525D01*
X-1336009Y144988D01*
X-1335389Y144605D01*
X-1334356Y144298D01*
X-1333426Y144221D01*
X-1332496Y144375D01*
X-1331876Y144605D01*
X-1331256Y145065D01*
X-1330843Y145601D01*
X-1330636Y146138D01*
Y146675D01*
X-1330843Y147211D01*
X-1331153Y147671D01*
X-1331566Y148055D01*
G01X-1335803Y150881D02*
X-1336423Y151341D01*
X-1336733Y151878D01*
X-1336836Y152491D01*
X-1336629Y153258D01*
X-1336113Y153795D01*
X-1335493Y153948D01*
X-1334873Y153871D01*
X-1334356Y153565D01*
X-1333323Y152031D01*
X-1332599Y151341D01*
X-1331566Y150881D01*
X-1330636Y150728D01*
Y153948D01*
G01Y158538D02*
X-1330739Y159075D01*
X-1331049Y159688D01*
X-1331566Y160071D01*
X-1332289Y160225D01*
X-1333013Y160071D01*
X-1333633Y159611D01*
X-1333943Y158921D01*
Y158155D01*
X-1334149Y157695D01*
X-1334666Y157311D01*
X-1335389Y157158D01*
X-1336113Y157388D01*
X-1336629Y157925D01*
X-1336836Y158538D01*
X-1336629Y159151D01*
X-1336113Y159688D01*
X-1335389Y159918D01*
X-1334666Y159765D01*
X-1334149Y159381D01*
X-1333943Y158921D01*
Y158155D01*
X-1333633Y157465D01*
X-1333013Y157005D01*
X-1332289Y156851D01*
X-1331566Y157005D01*
X-1331049Y157388D01*
X-1330739Y158001D01*
X-1330636Y158538D01*
G01X-1336836Y164738D02*
X-1336629Y164125D01*
X-1336113Y163665D01*
X-1335493Y163358D01*
X-1334666Y163128D01*
X-1333736Y163051D01*
X-1332806Y163128D01*
X-1331979Y163358D01*
X-1331359Y163665D01*
X-1330843Y164125D01*
X-1330636Y164738D01*
X-1330843Y165351D01*
X-1331359Y165811D01*
X-1331979Y166118D01*
X-1332806Y166348D01*
X-1333736Y166425D01*
X-1334666Y166348D01*
X-1335493Y166118D01*
X-1336113Y165811D01*
X-1336629Y165351D01*
X-1336836Y164738D01*
G01X-1338804Y171738D02*
X-1332604D01*
G01X-1338804Y169975D02*
Y173501D01*
G01X-1332604Y176405D02*
X-1338804D01*
Y178245D01*
X-1338494Y178858D01*
X-1337771Y179318D01*
X-1336944Y179471D01*
X-1336117Y179318D01*
X-1335497Y178935D01*
X-1335187Y178245D01*
Y176405D01*
G01X-1332604Y184138D02*
X-1338804D01*
X-1337564Y183218D01*
G01X-1332604D02*
Y185058D01*
G01Y190338D02*
X-1332707Y190875D01*
X-1333017Y191488D01*
X-1333534Y191871D01*
X-1334257Y192025D01*
X-1334981Y191871D01*
X-1335601Y191411D01*
X-1335911Y190721D01*
Y189955D01*
X-1336117Y189495D01*
X-1336634Y189111D01*
X-1337357Y188958D01*
X-1338081Y189188D01*
X-1338597Y189725D01*
X-1338804Y190338D01*
X-1338597Y190951D01*
X-1338081Y191488D01*
X-1337357Y191718D01*
X-1336634Y191565D01*
X-1336117Y191181D01*
X-1335911Y190721D01*
Y189955D01*
X-1335601Y189265D01*
X-1334981Y188805D01*
X-1334257Y188651D01*
X-1333534Y188805D01*
X-1333017Y189188D01*
X-1332707Y189801D01*
X-1332604Y190338D01*
G01X-1340844Y204305D02*
X-1340224Y204688D01*
X-1339811Y205148D01*
X-1339604Y205685D01*
X-1339811Y206298D01*
X-1340224Y206758D01*
X-1340844Y207218D01*
X-1341671Y207371D01*
X-1345804D01*
G01X-1339604Y212038D02*
X-1345804D01*
X-1344564Y211118D01*
G01X-1339604D02*
Y212958D01*
G01Y218085D02*
X-1340947Y218238D01*
X-1342084Y218468D01*
X-1343117Y218775D01*
X-1344254Y219158D01*
X-1345804Y219771D01*
Y216705D01*
G01X-1344838Y340220D02*
Y334020D01*
G01X-1346601Y340220D02*
X-1343075D01*
G01X-1340171Y334020D02*
Y340220D01*
X-1338331D01*
X-1337718Y339910D01*
X-1337258Y339187D01*
X-1337105Y338360D01*
X-1337258Y337533D01*
X-1337641Y336913D01*
X-1338331Y336603D01*
X-1340171D01*
G01X-1333895Y339187D02*
X-1333435Y339807D01*
X-1332898Y340117D01*
X-1332285Y340220D01*
X-1331518Y340013D01*
X-1330981Y339497D01*
X-1330828Y338877D01*
X-1330905Y338257D01*
X-1331211Y337740D01*
X-1332745Y336707D01*
X-1333435Y335983D01*
X-1333895Y334950D01*
X-1334048Y334020D01*
X-1330828D01*
G01X-1326238D02*
Y340220D01*
X-1327158Y338980D01*
G01Y334020D02*
X-1325318D01*
G01X-1349287Y381525D02*
X-1349597Y381065D01*
X-1349804Y380528D01*
Y379915D01*
X-1349494Y379225D01*
X-1348977Y378688D01*
X-1348357Y378305D01*
X-1347324Y377998D01*
X-1346394Y377921D01*
X-1345464Y378075D01*
X-1344844Y378305D01*
X-1344224Y378765D01*
X-1343811Y379301D01*
X-1343604Y379838D01*
Y380375D01*
X-1343811Y380911D01*
X-1344121Y381371D01*
X-1344534Y381755D01*
G01X-1348771Y384581D02*
X-1349391Y385041D01*
X-1349701Y385578D01*
X-1349804Y386191D01*
X-1349597Y386958D01*
X-1349081Y387495D01*
X-1348461Y387648D01*
X-1347841Y387571D01*
X-1347324Y387265D01*
X-1346291Y385731D01*
X-1345567Y385041D01*
X-1344534Y384581D01*
X-1343604Y384428D01*
Y387648D01*
G01Y392238D02*
X-1349804D01*
X-1348564Y391318D01*
G01X-1343604D02*
Y393158D01*
G01X-1333287Y381525D02*
X-1333597Y381065D01*
X-1333804Y380528D01*
Y379915D01*
X-1333494Y379225D01*
X-1332977Y378688D01*
X-1332357Y378305D01*
X-1331324Y377998D01*
X-1330394Y377921D01*
X-1329464Y378075D01*
X-1328844Y378305D01*
X-1328224Y378765D01*
X-1327811Y379301D01*
X-1327604Y379838D01*
Y380375D01*
X-1327811Y380911D01*
X-1328121Y381371D01*
X-1328534Y381755D01*
G01X-1332771Y384581D02*
X-1333391Y385041D01*
X-1333701Y385578D01*
X-1333804Y386191D01*
X-1333597Y386958D01*
X-1333081Y387495D01*
X-1332461Y387648D01*
X-1331841Y387571D01*
X-1331324Y387265D01*
X-1330291Y385731D01*
X-1329567Y385041D01*
X-1328534Y384581D01*
X-1327604Y384428D01*
Y387648D01*
G01X-1332771Y390781D02*
X-1333391Y391241D01*
X-1333701Y391778D01*
X-1333804Y392391D01*
X-1333597Y393158D01*
X-1333081Y393695D01*
X-1332461Y393848D01*
X-1331841Y393771D01*
X-1331324Y393465D01*
X-1330291Y391931D01*
X-1329567Y391241D01*
X-1328534Y390781D01*
X-1327604Y390628D01*
Y393848D01*
G01X-1333804Y430038D02*
Y436238D01*
X-1334724Y434998D01*
G01Y430038D02*
X-1332884D01*
G01X-1329061Y435205D02*
X-1328601Y435825D01*
X-1328064Y436135D01*
X-1327451Y436238D01*
X-1326684Y436031D01*
X-1326147Y435515D01*
X-1325994Y434895D01*
X-1326071Y434275D01*
X-1326377Y433758D01*
X-1327911Y432725D01*
X-1328601Y432001D01*
X-1329061Y430968D01*
X-1329214Y430038D01*
X-1325994D01*
G01X-1342220Y446651D02*
X-1337777D01*
X-1336846Y446958D01*
X-1336227Y447571D01*
X-1336020Y448338D01*
X-1336227Y449105D01*
X-1336846Y449718D01*
X-1337777Y450025D01*
X-1342220D01*
G01X-1338603Y453081D02*
X-1339327Y453618D01*
X-1339740Y454078D01*
X-1339947Y454691D01*
X-1339740Y455228D01*
X-1339327Y455611D01*
X-1338707Y455918D01*
X-1337983Y455995D01*
X-1337363Y455918D01*
X-1336743Y455611D01*
X-1336227Y455151D01*
X-1336020Y454615D01*
X-1336227Y454001D01*
X-1336846Y453465D01*
X-1337777Y453158D01*
X-1338810Y453081D01*
X-1340153Y453235D01*
X-1340877Y453465D01*
X-1341600Y453848D01*
X-1342117Y454385D01*
X-1342220Y454921D01*
X-1342013Y455458D01*
X-1341497Y455841D01*
G01X-1320804Y24038D02*
Y30238D01*
X-1321724Y28998D01*
G01Y24038D02*
X-1319884D01*
G01X-1316061Y29205D02*
X-1315601Y29825D01*
X-1315064Y30135D01*
X-1314451Y30238D01*
X-1313684Y30031D01*
X-1313147Y29515D01*
X-1312994Y28895D01*
X-1313071Y28275D01*
X-1313377Y27758D01*
X-1314911Y26725D01*
X-1315601Y26001D01*
X-1316061Y24968D01*
X-1316214Y24038D01*
X-1312994D01*
G01X-1317007Y35761D02*
X-1316471Y35245D01*
X-1315857Y35038D01*
X-1315244Y35245D01*
X-1314707Y35864D01*
X-1314324Y36795D01*
X-1314171Y37725D01*
Y38861D01*
X-1314324Y39791D01*
X-1314707Y40618D01*
X-1315167Y41031D01*
X-1315704Y41238D01*
X-1316317Y41031D01*
X-1316777Y40618D01*
X-1317084Y39998D01*
X-1317237Y39171D01*
X-1317084Y38448D01*
X-1316701Y37725D01*
X-1316241Y37311D01*
X-1315704Y37208D01*
X-1315091Y37415D01*
X-1314631Y37931D01*
X-1314171Y38861D01*
G01X-1325074Y82930D02*
Y89130D01*
X-1325994Y87890D01*
G01Y82930D02*
X-1324154D01*
G01X-1320177Y83653D02*
X-1319641Y83137D01*
X-1319027Y82930D01*
X-1318414Y83137D01*
X-1317877Y83756D01*
X-1317494Y84687D01*
X-1317341Y85617D01*
Y86753D01*
X-1317494Y87683D01*
X-1317877Y88510D01*
X-1318337Y88923D01*
X-1318874Y89130D01*
X-1319487Y88923D01*
X-1319947Y88510D01*
X-1320254Y87890D01*
X-1320407Y87063D01*
X-1320254Y86340D01*
X-1319871Y85617D01*
X-1319411Y85203D01*
X-1318874Y85100D01*
X-1318261Y85307D01*
X-1317801Y85823D01*
X-1317341Y86753D01*
G01X-1327719Y140249D02*
X-1327259Y140869D01*
X-1326722Y141179D01*
X-1326109Y141282D01*
X-1325342Y141075D01*
X-1324805Y140559D01*
X-1324652Y139939D01*
X-1324729Y139319D01*
X-1325035Y138802D01*
X-1326569Y137769D01*
X-1327259Y137045D01*
X-1327719Y136012D01*
X-1327872Y135082D01*
X-1324652D01*
G01X-1326287Y147825D02*
X-1326597Y147365D01*
X-1326804Y146828D01*
Y146215D01*
X-1326494Y145525D01*
X-1325977Y144988D01*
X-1325357Y144605D01*
X-1324324Y144298D01*
X-1323394Y144221D01*
X-1322464Y144375D01*
X-1321844Y144605D01*
X-1321224Y145065D01*
X-1320811Y145601D01*
X-1320604Y146138D01*
Y146675D01*
X-1320811Y147211D01*
X-1321121Y147671D01*
X-1321534Y148055D01*
G01X-1325771Y150881D02*
X-1326391Y151341D01*
X-1326701Y151878D01*
X-1326804Y152491D01*
X-1326597Y153258D01*
X-1326081Y153795D01*
X-1325461Y153948D01*
X-1324841Y153871D01*
X-1324324Y153565D01*
X-1323291Y152031D01*
X-1322567Y151341D01*
X-1321534Y150881D01*
X-1320604Y150728D01*
Y153948D01*
G01Y158538D02*
X-1320707Y159075D01*
X-1321017Y159688D01*
X-1321534Y160071D01*
X-1322257Y160225D01*
X-1322981Y160071D01*
X-1323601Y159611D01*
X-1323911Y158921D01*
Y158155D01*
X-1324117Y157695D01*
X-1324634Y157311D01*
X-1325357Y157158D01*
X-1326081Y157388D01*
X-1326597Y157925D01*
X-1326804Y158538D01*
X-1326597Y159151D01*
X-1326081Y159688D01*
X-1325357Y159918D01*
X-1324634Y159765D01*
X-1324117Y159381D01*
X-1323911Y158921D01*
Y158155D01*
X-1323601Y157465D01*
X-1322981Y157005D01*
X-1322257Y156851D01*
X-1321534Y157005D01*
X-1321017Y157388D01*
X-1320707Y158001D01*
X-1320604Y158538D01*
G01Y164738D02*
X-1326804D01*
X-1325564Y163818D01*
G01X-1320604D02*
Y165658D01*
G01X-1316636Y148505D02*
X-1310436D01*
Y151571D01*
G01Y156238D02*
X-1316636D01*
X-1315396Y155318D01*
G01X-1310436D02*
Y157158D01*
G01X-1311159Y161135D02*
X-1310643Y161671D01*
X-1310436Y162285D01*
X-1310643Y162898D01*
X-1311262Y163435D01*
X-1312193Y163818D01*
X-1313123Y163971D01*
X-1314259D01*
X-1315189Y163818D01*
X-1316016Y163435D01*
X-1316429Y162975D01*
X-1316636Y162438D01*
X-1316429Y161825D01*
X-1316016Y161365D01*
X-1315396Y161058D01*
X-1314569Y160905D01*
X-1313846Y161058D01*
X-1313123Y161441D01*
X-1312709Y161901D01*
X-1312606Y162438D01*
X-1312813Y163051D01*
X-1313329Y163511D01*
X-1314259Y163971D01*
G01X-1324804Y170738D02*
X-1318604D01*
G01X-1324804Y168975D02*
Y172501D01*
G01X-1318604Y175405D02*
X-1324804D01*
Y177245D01*
X-1324494Y177858D01*
X-1323771Y178318D01*
X-1322944Y178471D01*
X-1322117Y178318D01*
X-1321497Y177935D01*
X-1321187Y177245D01*
Y175405D01*
G01X-1318604Y183138D02*
X-1324804D01*
X-1323564Y182218D01*
G01X-1318604D02*
Y184058D01*
G01X-1319327Y188035D02*
X-1318811Y188571D01*
X-1318604Y189185D01*
X-1318811Y189798D01*
X-1319430Y190335D01*
X-1320361Y190718D01*
X-1321291Y190871D01*
X-1322427D01*
X-1323357Y190718D01*
X-1324184Y190335D01*
X-1324597Y189875D01*
X-1324804Y189338D01*
X-1324597Y188725D01*
X-1324184Y188265D01*
X-1323564Y187958D01*
X-1322737Y187805D01*
X-1322014Y187958D01*
X-1321291Y188341D01*
X-1320877Y188801D01*
X-1320774Y189338D01*
X-1320981Y189951D01*
X-1321497Y190411D01*
X-1322427Y190871D01*
G01X-1317258Y198378D02*
Y204578D01*
X-1318178Y203338D01*
G01Y198378D02*
X-1316338D01*
G01X-1318945Y220418D02*
X-1318485Y219695D01*
X-1317871Y219281D01*
X-1317181Y219178D01*
X-1316568Y219281D01*
X-1315955Y219798D01*
X-1315571Y220418D01*
X-1315495Y221038D01*
X-1315648Y221761D01*
X-1316185Y222278D01*
X-1316721Y222485D01*
X-1317411D01*
G01X-1316721D02*
X-1316261Y222795D01*
X-1315878Y223311D01*
X-1315725Y223931D01*
X-1315878Y224551D01*
X-1316261Y225068D01*
X-1316951Y225378D01*
X-1317641Y225275D01*
X-1318331Y224861D01*
G01X-1314704Y290038D02*
X-1314167Y290141D01*
X-1313554Y290451D01*
X-1313171Y290968D01*
X-1313017Y291691D01*
X-1313171Y292415D01*
X-1313631Y293035D01*
X-1314321Y293345D01*
X-1315087D01*
X-1315547Y293551D01*
X-1315931Y294068D01*
X-1316084Y294791D01*
X-1315854Y295515D01*
X-1315317Y296031D01*
X-1314704Y296238D01*
X-1314091Y296031D01*
X-1313554Y295515D01*
X-1313324Y294791D01*
X-1313477Y294068D01*
X-1313861Y293551D01*
X-1314321Y293345D01*
X-1315087D01*
X-1315777Y293035D01*
X-1316237Y292415D01*
X-1316391Y291691D01*
X-1316237Y290968D01*
X-1315854Y290451D01*
X-1315241Y290141D01*
X-1314704Y290038D01*
G01X-1316391Y320968D02*
X-1315931Y320451D01*
X-1315394Y320141D01*
X-1314704Y320038D01*
X-1314014Y320245D01*
X-1313477Y320658D01*
X-1313094Y321381D01*
X-1313017Y322208D01*
X-1313171Y323035D01*
X-1313554Y323551D01*
X-1314091Y323965D01*
X-1314627Y324068D01*
X-1315164Y323965D01*
X-1315854Y323551D01*
X-1315624Y326238D01*
X-1313554D01*
G01X-1317287Y381525D02*
X-1317597Y381065D01*
X-1317804Y380528D01*
Y379915D01*
X-1317494Y379225D01*
X-1316977Y378688D01*
X-1316357Y378305D01*
X-1315324Y377998D01*
X-1314394Y377921D01*
X-1313464Y378075D01*
X-1312844Y378305D01*
X-1312224Y378765D01*
X-1311811Y379301D01*
X-1311604Y379838D01*
Y380375D01*
X-1311811Y380911D01*
X-1312121Y381371D01*
X-1312534Y381755D01*
G01X-1316771Y384581D02*
X-1317391Y385041D01*
X-1317701Y385578D01*
X-1317804Y386191D01*
X-1317597Y386958D01*
X-1317081Y387495D01*
X-1316461Y387648D01*
X-1315841Y387571D01*
X-1315324Y387265D01*
X-1314291Y385731D01*
X-1313567Y385041D01*
X-1312534Y384581D01*
X-1311604Y384428D01*
Y387648D01*
G01X-1317804Y392238D02*
X-1317597Y391625D01*
X-1317081Y391165D01*
X-1316461Y390858D01*
X-1315634Y390628D01*
X-1314704Y390551D01*
X-1313774Y390628D01*
X-1312947Y390858D01*
X-1312327Y391165D01*
X-1311811Y391625D01*
X-1311604Y392238D01*
X-1311811Y392851D01*
X-1312327Y393311D01*
X-1312947Y393618D01*
X-1313774Y393848D01*
X-1314704Y393925D01*
X-1315634Y393848D01*
X-1316461Y393618D01*
X-1317081Y393311D01*
X-1317597Y392851D01*
X-1317804Y392238D01*
G01X-1315437Y401938D02*
Y408138D01*
X-1313521D01*
X-1312907Y407828D01*
X-1312524Y407415D01*
X-1312371Y406588D01*
X-1312524Y405761D01*
X-1312984Y405245D01*
X-1313521Y404935D01*
X-1315437D01*
G01X-1313521D02*
X-1312371Y401938D01*
G01X-1309391Y403178D02*
X-1308931Y402455D01*
X-1308317Y402041D01*
X-1307627Y401938D01*
X-1307014Y402041D01*
X-1306401Y402558D01*
X-1306017Y403178D01*
X-1305941Y403798D01*
X-1306094Y404521D01*
X-1306631Y405038D01*
X-1307167Y405245D01*
X-1307857D01*
G01X-1307167D02*
X-1306707Y405555D01*
X-1306324Y406071D01*
X-1306171Y406691D01*
X-1306324Y407311D01*
X-1306707Y407828D01*
X-1307397Y408138D01*
X-1308087Y408035D01*
X-1308777Y407621D01*
G01X-1301504Y401938D02*
X-1300967Y402041D01*
X-1300354Y402351D01*
X-1299971Y402868D01*
X-1299817Y403591D01*
X-1299971Y404315D01*
X-1300431Y404935D01*
X-1301121Y405245D01*
X-1301887D01*
X-1302347Y405451D01*
X-1302731Y405968D01*
X-1302884Y406691D01*
X-1302654Y407415D01*
X-1302117Y407931D01*
X-1301504Y408138D01*
X-1300891Y407931D01*
X-1300354Y407415D01*
X-1300124Y406691D01*
X-1300277Y405968D01*
X-1300661Y405451D01*
X-1301121Y405245D01*
X-1301887D01*
X-1302577Y404935D01*
X-1303037Y404315D01*
X-1303191Y403591D01*
X-1303037Y402868D01*
X-1302654Y402351D01*
X-1302041Y402041D01*
X-1301504Y401938D01*
G01X-1319004Y408705D02*
X-1325204D01*
Y410621D01*
X-1324894Y411235D01*
X-1324481Y411618D01*
X-1323654Y411771D01*
X-1322827Y411618D01*
X-1322311Y411158D01*
X-1322001Y410621D01*
Y408705D01*
G01Y410621D02*
X-1319004Y411771D01*
G01X-1320244Y414751D02*
X-1319521Y415211D01*
X-1319107Y415825D01*
X-1319004Y416515D01*
X-1319107Y417128D01*
X-1319624Y417741D01*
X-1320244Y418125D01*
X-1320864Y418201D01*
X-1321587Y418048D01*
X-1322104Y417511D01*
X-1322311Y416975D01*
Y416285D01*
G01Y416975D02*
X-1322621Y417435D01*
X-1323137Y417818D01*
X-1323757Y417971D01*
X-1324377Y417818D01*
X-1324894Y417435D01*
X-1325204Y416745D01*
X-1325101Y416055D01*
X-1324687Y415365D01*
G01X-1319934Y420951D02*
X-1319417Y421411D01*
X-1319107Y421948D01*
X-1319004Y422638D01*
X-1319211Y423328D01*
X-1319624Y423865D01*
X-1320347Y424248D01*
X-1321174Y424325D01*
X-1322001Y424171D01*
X-1322517Y423788D01*
X-1322931Y423251D01*
X-1323034Y422715D01*
X-1322931Y422178D01*
X-1322517Y421488D01*
X-1325204Y421718D01*
Y423788D01*
G01X-1322594Y437964D02*
Y444164D01*
X-1323514Y442924D01*
G01Y437964D02*
X-1321674D01*
G01X-1318081Y439204D02*
X-1317621Y438481D01*
X-1317007Y438067D01*
X-1316317Y437964D01*
X-1315704Y438067D01*
X-1315091Y438584D01*
X-1314707Y439204D01*
X-1314631Y439824D01*
X-1314784Y440547D01*
X-1315321Y441064D01*
X-1315857Y441271D01*
X-1316547D01*
G01X-1315857D02*
X-1315397Y441581D01*
X-1315014Y442097D01*
X-1314861Y442717D01*
X-1315014Y443337D01*
X-1315397Y443854D01*
X-1316087Y444164D01*
X-1316777Y444061D01*
X-1317467Y443647D01*
G01X-1322594Y461280D02*
Y467480D01*
X-1323514Y466240D01*
G01Y461280D02*
X-1321674D01*
G01X-1316394D02*
X-1315857Y461383D01*
X-1315244Y461693D01*
X-1314861Y462210D01*
X-1314707Y462933D01*
X-1314861Y463657D01*
X-1315321Y464277D01*
X-1316011Y464587D01*
X-1316777D01*
X-1317237Y464793D01*
X-1317621Y465310D01*
X-1317774Y466033D01*
X-1317544Y466757D01*
X-1317007Y467273D01*
X-1316394Y467480D01*
X-1315781Y467273D01*
X-1315244Y466757D01*
X-1315014Y466033D01*
X-1315167Y465310D01*
X-1315551Y464793D01*
X-1316011Y464587D01*
X-1316777D01*
X-1317467Y464277D01*
X-1317927Y463657D01*
X-1318081Y462933D01*
X-1317927Y462210D01*
X-1317544Y461693D01*
X-1316931Y461383D01*
X-1316394Y461280D01*
G01X-1325075Y494440D02*
Y488240D01*
X-1322009D01*
G01X-1317342D02*
X-1316805Y488343D01*
X-1316192Y488653D01*
X-1315809Y489170D01*
X-1315655Y489893D01*
X-1315809Y490617D01*
X-1316269Y491237D01*
X-1316959Y491547D01*
X-1317725D01*
X-1318185Y491753D01*
X-1318569Y492270D01*
X-1318722Y492993D01*
X-1318492Y493717D01*
X-1317955Y494233D01*
X-1317342Y494440D01*
X-1316729Y494233D01*
X-1316192Y493717D01*
X-1315962Y492993D01*
X-1316115Y492270D01*
X-1316499Y491753D01*
X-1316959Y491547D01*
X-1317725D01*
X-1318415Y491237D01*
X-1318875Y490617D01*
X-1319029Y489893D01*
X-1318875Y489170D01*
X-1318492Y488653D01*
X-1317879Y488343D01*
X-1317342Y488240D01*
G01X-1310287Y-35575D02*
X-1310597Y-36035D01*
X-1310804Y-36572D01*
Y-37185D01*
X-1310494Y-37875D01*
X-1309977Y-38412D01*
X-1309357Y-38795D01*
X-1308324Y-39102D01*
X-1307394Y-39179D01*
X-1306464Y-39025D01*
X-1305844Y-38795D01*
X-1305224Y-38335D01*
X-1304811Y-37799D01*
X-1304604Y-37262D01*
Y-36725D01*
X-1304811Y-36189D01*
X-1305121Y-35729D01*
X-1305534Y-35345D01*
G01X-1304604Y-31062D02*
X-1310804D01*
X-1309564Y-31982D01*
G01X-1304604D02*
Y-30142D01*
G01X-1305534Y-26549D02*
X-1305017Y-26089D01*
X-1304707Y-25552D01*
X-1304604Y-24862D01*
X-1304811Y-24172D01*
X-1305224Y-23635D01*
X-1305947Y-23252D01*
X-1306774Y-23175D01*
X-1307601Y-23329D01*
X-1308117Y-23712D01*
X-1308531Y-24249D01*
X-1308634Y-24785D01*
X-1308531Y-25322D01*
X-1308117Y-26012D01*
X-1310804Y-25782D01*
Y-23712D01*
G01X-1305534Y-20349D02*
X-1305017Y-19889D01*
X-1304707Y-19352D01*
X-1304604Y-18662D01*
X-1304811Y-17972D01*
X-1305224Y-17435D01*
X-1305947Y-17052D01*
X-1306774Y-16975D01*
X-1307601Y-17129D01*
X-1308117Y-17512D01*
X-1308531Y-18049D01*
X-1308634Y-18585D01*
X-1308531Y-19122D01*
X-1308117Y-19812D01*
X-1310804Y-19582D01*
Y-17512D01*
G01X-1298287Y-38575D02*
X-1298597Y-39035D01*
X-1298804Y-39572D01*
Y-40185D01*
X-1298494Y-40875D01*
X-1297977Y-41412D01*
X-1297357Y-41795D01*
X-1296324Y-42102D01*
X-1295394Y-42179D01*
X-1294464Y-42025D01*
X-1293844Y-41795D01*
X-1293224Y-41335D01*
X-1292811Y-40799D01*
X-1292604Y-40262D01*
Y-39725D01*
X-1292811Y-39189D01*
X-1293121Y-38729D01*
X-1293534Y-38345D01*
G01X-1292604Y-34062D02*
X-1298804D01*
X-1297564Y-34982D01*
G01X-1292604D02*
Y-33142D01*
G01Y-26942D02*
X-1298804D01*
X-1294361Y-29779D01*
Y-25945D01*
G01X-1292604Y-21662D02*
X-1292707Y-21125D01*
X-1293017Y-20512D01*
X-1293534Y-20129D01*
X-1294257Y-19975D01*
X-1294981Y-20129D01*
X-1295601Y-20589D01*
X-1295911Y-21279D01*
Y-22045D01*
X-1296117Y-22505D01*
X-1296634Y-22889D01*
X-1297357Y-23042D01*
X-1298081Y-22812D01*
X-1298597Y-22275D01*
X-1298804Y-21662D01*
X-1298597Y-21049D01*
X-1298081Y-20512D01*
X-1297357Y-20282D01*
X-1296634Y-20435D01*
X-1296117Y-20819D01*
X-1295911Y-21279D01*
Y-22045D01*
X-1295601Y-22735D01*
X-1294981Y-23195D01*
X-1294257Y-23349D01*
X-1293534Y-23195D01*
X-1293017Y-22812D01*
X-1292707Y-22199D01*
X-1292604Y-21662D01*
G01X-1296804Y-8497D02*
X-1303004D01*
Y-6581D01*
X-1302694Y-5967D01*
X-1302281Y-5584D01*
X-1301454Y-5431D01*
X-1300627Y-5584D01*
X-1300111Y-6044D01*
X-1299801Y-6581D01*
Y-8497D01*
G01Y-6581D02*
X-1296804Y-5431D01*
G01X-1301971Y-2221D02*
X-1302591Y-1761D01*
X-1302901Y-1224D01*
X-1303004Y-611D01*
X-1302797Y156D01*
X-1302281Y693D01*
X-1301661Y846D01*
X-1301041Y769D01*
X-1300524Y463D01*
X-1299491Y-1071D01*
X-1298767Y-1761D01*
X-1297734Y-2221D01*
X-1296804Y-2374D01*
Y846D01*
G01X-1299387Y3979D02*
X-1300111Y4516D01*
X-1300524Y4976D01*
X-1300731Y5589D01*
X-1300524Y6126D01*
X-1300111Y6509D01*
X-1299491Y6816D01*
X-1298767Y6893D01*
X-1298147Y6816D01*
X-1297527Y6509D01*
X-1297011Y6049D01*
X-1296804Y5513D01*
X-1297011Y4899D01*
X-1297630Y4363D01*
X-1298561Y4056D01*
X-1299594Y3979D01*
X-1300937Y4133D01*
X-1301661Y4363D01*
X-1302384Y4746D01*
X-1302901Y5283D01*
X-1303004Y5819D01*
X-1302797Y6356D01*
X-1302281Y6739D01*
G01X-1299387Y10179D02*
X-1300111Y10716D01*
X-1300524Y11176D01*
X-1300731Y11789D01*
X-1300524Y12326D01*
X-1300111Y12709D01*
X-1299491Y13016D01*
X-1298767Y13093D01*
X-1298147Y13016D01*
X-1297527Y12709D01*
X-1297011Y12249D01*
X-1296804Y11713D01*
X-1297011Y11099D01*
X-1297630Y10563D01*
X-1298561Y10256D01*
X-1299594Y10179D01*
X-1300937Y10333D01*
X-1301661Y10563D01*
X-1302384Y10946D01*
X-1302901Y11483D01*
X-1303004Y12019D01*
X-1302797Y12556D01*
X-1302281Y12939D01*
G01X-1305002Y24249D02*
X-1300559D01*
X-1299628Y24556D01*
X-1299009Y25169D01*
X-1298802Y25936D01*
X-1299009Y26703D01*
X-1299628Y27316D01*
X-1300559Y27623D01*
X-1305002D01*
G01X-1298802Y32136D02*
X-1305002D01*
X-1303762Y31216D01*
G01X-1298802D02*
Y33056D01*
G01Y38336D02*
X-1305002D01*
X-1303762Y37416D01*
G01X-1298802D02*
Y39256D01*
G01X-1307236Y43336D02*
X-1306699Y43439D01*
X-1306086Y43749D01*
X-1305703Y44266D01*
X-1305549Y44989D01*
X-1305703Y45713D01*
X-1306163Y46333D01*
X-1306853Y46643D01*
X-1307619D01*
X-1308079Y46849D01*
X-1308463Y47366D01*
X-1308616Y48089D01*
X-1308386Y48813D01*
X-1307849Y49329D01*
X-1307236Y49536D01*
X-1306623Y49329D01*
X-1306086Y48813D01*
X-1305856Y48089D01*
X-1306009Y47366D01*
X-1306393Y46849D01*
X-1306853Y46643D01*
X-1307619D01*
X-1308309Y46333D01*
X-1308769Y45713D01*
X-1308923Y44989D01*
X-1308769Y44266D01*
X-1308386Y43749D01*
X-1307773Y43439D01*
X-1307236Y43336D01*
G01X-1299563Y43510D02*
X-1299410Y44853D01*
X-1299180Y45990D01*
X-1298873Y47023D01*
X-1298490Y48160D01*
X-1297877Y49710D01*
X-1300943D01*
G01X-1312857Y99289D02*
X-1312397Y99909D01*
X-1311860Y100219D01*
X-1311247Y100322D01*
X-1310480Y100115D01*
X-1309943Y99599D01*
X-1309790Y98979D01*
X-1309867Y98359D01*
X-1310173Y97842D01*
X-1311707Y96809D01*
X-1312397Y96085D01*
X-1312857Y95052D01*
X-1313010Y94122D01*
X-1309790D01*
G01X-1305200Y100322D02*
X-1305813Y100115D01*
X-1306273Y99599D01*
X-1306580Y98979D01*
X-1306810Y98152D01*
X-1306887Y97222D01*
X-1306810Y96292D01*
X-1306580Y95465D01*
X-1306273Y94845D01*
X-1305813Y94329D01*
X-1305200Y94122D01*
X-1304587Y94329D01*
X-1304127Y94845D01*
X-1303820Y95465D01*
X-1303590Y96292D01*
X-1303513Y97222D01*
X-1303590Y98152D01*
X-1303820Y98979D01*
X-1304127Y99599D01*
X-1304587Y100115D01*
X-1305200Y100322D01*
G01X-1293604Y117738D02*
X-1296394D01*
X-1299804Y116205D01*
G01Y119271D02*
X-1296394Y117738D01*
G01X-1293604Y123938D02*
X-1299804D01*
X-1298564Y123018D01*
G01X-1293604D02*
Y124858D01*
G01X-1313177Y127353D02*
X-1312717Y127973D01*
X-1312180Y128283D01*
X-1311567Y128386D01*
X-1310800Y128179D01*
X-1310263Y127663D01*
X-1310110Y127043D01*
X-1310187Y126423D01*
X-1310493Y125906D01*
X-1312027Y124873D01*
X-1312717Y124149D01*
X-1313177Y123116D01*
X-1313330Y122186D01*
X-1310110D01*
G01X-1305520D02*
X-1304983Y122289D01*
X-1304370Y122599D01*
X-1303987Y123116D01*
X-1303833Y123839D01*
X-1303987Y124563D01*
X-1304447Y125183D01*
X-1305137Y125493D01*
X-1305903D01*
X-1306363Y125699D01*
X-1306747Y126216D01*
X-1306900Y126939D01*
X-1306670Y127663D01*
X-1306133Y128179D01*
X-1305520Y128386D01*
X-1304907Y128179D01*
X-1304370Y127663D01*
X-1304140Y126939D01*
X-1304293Y126216D01*
X-1304677Y125699D01*
X-1305137Y125493D01*
X-1305903D01*
X-1306593Y125183D01*
X-1307053Y124563D01*
X-1307207Y123839D01*
X-1307053Y123116D01*
X-1306670Y122599D01*
X-1306057Y122289D01*
X-1305520Y122186D01*
G01X-1304087Y148225D02*
X-1304397Y147765D01*
X-1304604Y147228D01*
Y146615D01*
X-1304294Y145925D01*
X-1303777Y145388D01*
X-1303157Y145005D01*
X-1302124Y144698D01*
X-1301194Y144621D01*
X-1300264Y144775D01*
X-1299644Y145005D01*
X-1299024Y145465D01*
X-1298611Y146001D01*
X-1298404Y146538D01*
Y147075D01*
X-1298611Y147611D01*
X-1298921Y148071D01*
X-1299334Y148455D01*
G01X-1303571Y151281D02*
X-1304191Y151741D01*
X-1304501Y152278D01*
X-1304604Y152891D01*
X-1304397Y153658D01*
X-1303881Y154195D01*
X-1303261Y154348D01*
X-1302641Y154271D01*
X-1302124Y153965D01*
X-1301091Y152431D01*
X-1300367Y151741D01*
X-1299334Y151281D01*
X-1298404Y151128D01*
Y154348D01*
G01Y158785D02*
X-1299747Y158938D01*
X-1300884Y159168D01*
X-1301917Y159475D01*
X-1303054Y159858D01*
X-1304604Y160471D01*
Y157405D01*
G01X-1299127Y163835D02*
X-1298611Y164371D01*
X-1298404Y164985D01*
X-1298611Y165598D01*
X-1299230Y166135D01*
X-1300161Y166518D01*
X-1301091Y166671D01*
X-1302227D01*
X-1303157Y166518D01*
X-1303984Y166135D01*
X-1304397Y165675D01*
X-1304604Y165138D01*
X-1304397Y164525D01*
X-1303984Y164065D01*
X-1303364Y163758D01*
X-1302537Y163605D01*
X-1301814Y163758D01*
X-1301091Y164141D01*
X-1300677Y164601D01*
X-1300574Y165138D01*
X-1300781Y165751D01*
X-1301297Y166211D01*
X-1302227Y166671D01*
G01X-1297804Y168738D02*
X-1291604D01*
G01X-1297804Y166975D02*
Y170501D01*
G01X-1291604Y173405D02*
X-1297804D01*
Y175245D01*
X-1297494Y175858D01*
X-1296771Y176318D01*
X-1295944Y176471D01*
X-1295117Y176318D01*
X-1294497Y175935D01*
X-1294187Y175245D01*
Y173405D01*
G01X-1292534Y179451D02*
X-1292017Y179911D01*
X-1291707Y180448D01*
X-1291604Y181138D01*
X-1291811Y181828D01*
X-1292224Y182365D01*
X-1292947Y182748D01*
X-1293774Y182825D01*
X-1294601Y182671D01*
X-1295117Y182288D01*
X-1295531Y181751D01*
X-1295634Y181215D01*
X-1295531Y180678D01*
X-1295117Y179988D01*
X-1297804Y180218D01*
Y182288D01*
G01X-1291604Y187338D02*
X-1291707Y187875D01*
X-1292017Y188488D01*
X-1292534Y188871D01*
X-1293257Y189025D01*
X-1293981Y188871D01*
X-1294601Y188411D01*
X-1294911Y187721D01*
Y186955D01*
X-1295117Y186495D01*
X-1295634Y186111D01*
X-1296357Y185958D01*
X-1297081Y186188D01*
X-1297597Y186725D01*
X-1297804Y187338D01*
X-1297597Y187951D01*
X-1297081Y188488D01*
X-1296357Y188718D01*
X-1295634Y188565D01*
X-1295117Y188181D01*
X-1294911Y187721D01*
Y186955D01*
X-1294601Y186265D01*
X-1293981Y185805D01*
X-1293257Y185651D01*
X-1292534Y185805D01*
X-1292017Y186188D01*
X-1291707Y186801D01*
X-1291604Y187338D01*
G01X-1309837Y412538D02*
Y418738D01*
X-1307921D01*
X-1307307Y418428D01*
X-1306924Y418015D01*
X-1306771Y417188D01*
X-1306924Y416361D01*
X-1307384Y415845D01*
X-1307921Y415535D01*
X-1309837D01*
G01X-1307921D02*
X-1306771Y412538D01*
G01X-1301184D02*
Y418738D01*
X-1304021Y414295D01*
X-1300187D01*
G01X-1295904Y418738D02*
X-1296517Y418531D01*
X-1296977Y418015D01*
X-1297284Y417395D01*
X-1297514Y416568D01*
X-1297591Y415638D01*
X-1297514Y414708D01*
X-1297284Y413881D01*
X-1296977Y413261D01*
X-1296517Y412745D01*
X-1295904Y412538D01*
X-1295291Y412745D01*
X-1294831Y413261D01*
X-1294524Y413881D01*
X-1294294Y414708D01*
X-1294217Y415638D01*
X-1294294Y416568D01*
X-1294524Y417395D01*
X-1294831Y418015D01*
X-1295291Y418531D01*
X-1295904Y418738D01*
G01X-1307617Y430021D02*
X-1308077Y430331D01*
X-1308614Y430538D01*
X-1309227D01*
X-1309917Y430228D01*
X-1310454Y429711D01*
X-1310837Y429091D01*
X-1311144Y428058D01*
X-1311221Y427128D01*
X-1311067Y426198D01*
X-1310837Y425578D01*
X-1310377Y424958D01*
X-1309841Y424545D01*
X-1309304Y424338D01*
X-1308767D01*
X-1308231Y424545D01*
X-1307771Y424855D01*
X-1307387Y425268D01*
G01X-1303104Y424338D02*
Y430538D01*
X-1304024Y429298D01*
G01Y424338D02*
X-1302184D01*
G01X-1298361Y426921D02*
X-1297824Y427645D01*
X-1297364Y428058D01*
X-1296751Y428265D01*
X-1296214Y428058D01*
X-1295831Y427645D01*
X-1295524Y427025D01*
X-1295447Y426301D01*
X-1295524Y425681D01*
X-1295831Y425061D01*
X-1296291Y424545D01*
X-1296827Y424338D01*
X-1297441Y424545D01*
X-1297977Y425164D01*
X-1298284Y426095D01*
X-1298361Y427128D01*
X-1298207Y428471D01*
X-1297977Y429195D01*
X-1297594Y429918D01*
X-1297057Y430435D01*
X-1296521Y430538D01*
X-1295984Y430331D01*
X-1295601Y429815D01*
G01X-1307617Y441021D02*
X-1308077Y441331D01*
X-1308614Y441538D01*
X-1309227D01*
X-1309917Y441228D01*
X-1310454Y440711D01*
X-1310837Y440091D01*
X-1311144Y439058D01*
X-1311221Y438128D01*
X-1311067Y437198D01*
X-1310837Y436578D01*
X-1310377Y435958D01*
X-1309841Y435545D01*
X-1309304Y435338D01*
X-1308767D01*
X-1308231Y435545D01*
X-1307771Y435855D01*
X-1307387Y436268D01*
G01X-1304791D02*
X-1304331Y435751D01*
X-1303794Y435441D01*
X-1303104Y435338D01*
X-1302414Y435545D01*
X-1301877Y435958D01*
X-1301494Y436681D01*
X-1301417Y437508D01*
X-1301571Y438335D01*
X-1301954Y438851D01*
X-1302491Y439265D01*
X-1303027Y439368D01*
X-1303564Y439265D01*
X-1304254Y438851D01*
X-1304024Y441538D01*
X-1301954D01*
G01X-1298591Y436268D02*
X-1298131Y435751D01*
X-1297594Y435441D01*
X-1296904Y435338D01*
X-1296214Y435545D01*
X-1295677Y435958D01*
X-1295294Y436681D01*
X-1295217Y437508D01*
X-1295371Y438335D01*
X-1295754Y438851D01*
X-1296291Y439265D01*
X-1296827Y439368D01*
X-1297364Y439265D01*
X-1298054Y438851D01*
X-1297824Y441538D01*
X-1295754D01*
G01X-1306617Y449021D02*
X-1307077Y449331D01*
X-1307614Y449538D01*
X-1308227D01*
X-1308917Y449228D01*
X-1309454Y448711D01*
X-1309837Y448091D01*
X-1310144Y447058D01*
X-1310221Y446128D01*
X-1310067Y445198D01*
X-1309837Y444578D01*
X-1309377Y443958D01*
X-1308841Y443545D01*
X-1308304Y443338D01*
X-1307767D01*
X-1307231Y443545D01*
X-1306771Y443855D01*
X-1306387Y444268D01*
G01X-1301184Y443338D02*
Y449538D01*
X-1304021Y445095D01*
X-1300187D01*
G01X-1297207Y444061D02*
X-1296671Y443545D01*
X-1296057Y443338D01*
X-1295444Y443545D01*
X-1294907Y444164D01*
X-1294524Y445095D01*
X-1294371Y446025D01*
Y447161D01*
X-1294524Y448091D01*
X-1294907Y448918D01*
X-1295367Y449331D01*
X-1295904Y449538D01*
X-1296517Y449331D01*
X-1296977Y448918D01*
X-1297284Y448298D01*
X-1297437Y447471D01*
X-1297284Y446748D01*
X-1296901Y446025D01*
X-1296441Y445611D01*
X-1295904Y445508D01*
X-1295291Y445715D01*
X-1294831Y446231D01*
X-1294371Y447161D01*
G01X-1309837Y461338D02*
Y467538D01*
X-1307921D01*
X-1307307Y467228D01*
X-1306924Y466815D01*
X-1306771Y465988D01*
X-1306924Y465161D01*
X-1307384Y464645D01*
X-1307921Y464335D01*
X-1309837D01*
G01X-1307921D02*
X-1306771Y461338D01*
G01X-1303791Y462268D02*
X-1303331Y461751D01*
X-1302794Y461441D01*
X-1302104Y461338D01*
X-1301414Y461545D01*
X-1300877Y461958D01*
X-1300494Y462681D01*
X-1300417Y463508D01*
X-1300571Y464335D01*
X-1300954Y464851D01*
X-1301491Y465265D01*
X-1302027Y465368D01*
X-1302564Y465265D01*
X-1303254Y464851D01*
X-1303024Y467538D01*
X-1300954D01*
G01X-1297361Y466505D02*
X-1296901Y467125D01*
X-1296364Y467435D01*
X-1295751Y467538D01*
X-1294984Y467331D01*
X-1294447Y466815D01*
X-1294294Y466195D01*
X-1294371Y465575D01*
X-1294677Y465058D01*
X-1296211Y464025D01*
X-1296901Y463301D01*
X-1297361Y462268D01*
X-1297514Y461338D01*
X-1294294D01*
G01X-1306617Y458021D02*
X-1307077Y458331D01*
X-1307614Y458538D01*
X-1308227D01*
X-1308917Y458228D01*
X-1309454Y457711D01*
X-1309837Y457091D01*
X-1310144Y456058D01*
X-1310221Y455128D01*
X-1310067Y454198D01*
X-1309837Y453578D01*
X-1309377Y452958D01*
X-1308841Y452545D01*
X-1308304Y452338D01*
X-1307767D01*
X-1307231Y452545D01*
X-1306771Y452855D01*
X-1306387Y453268D01*
G01X-1301184Y452338D02*
Y458538D01*
X-1304021Y454095D01*
X-1300187D01*
G01X-1297361Y454921D02*
X-1296824Y455645D01*
X-1296364Y456058D01*
X-1295751Y456265D01*
X-1295214Y456058D01*
X-1294831Y455645D01*
X-1294524Y455025D01*
X-1294447Y454301D01*
X-1294524Y453681D01*
X-1294831Y453061D01*
X-1295291Y452545D01*
X-1295827Y452338D01*
X-1296441Y452545D01*
X-1296977Y453164D01*
X-1297284Y454095D01*
X-1297361Y455128D01*
X-1297207Y456471D01*
X-1296977Y457195D01*
X-1296594Y457918D01*
X-1296057Y458435D01*
X-1295521Y458538D01*
X-1294984Y458331D01*
X-1294601Y457815D01*
G01X-1307817Y475821D02*
X-1308277Y476131D01*
X-1308814Y476338D01*
X-1309427D01*
X-1310117Y476028D01*
X-1310654Y475511D01*
X-1311037Y474891D01*
X-1311344Y473858D01*
X-1311421Y472928D01*
X-1311267Y471998D01*
X-1311037Y471378D01*
X-1310577Y470758D01*
X-1310041Y470345D01*
X-1309504Y470138D01*
X-1308967D01*
X-1308431Y470345D01*
X-1307971Y470655D01*
X-1307587Y471068D01*
G01X-1303457Y470138D02*
X-1303304Y471481D01*
X-1303074Y472618D01*
X-1302767Y473651D01*
X-1302384Y474788D01*
X-1301771Y476338D01*
X-1304837D01*
G01X-1297257Y470138D02*
X-1297104Y471481D01*
X-1296874Y472618D01*
X-1296567Y473651D01*
X-1296184Y474788D01*
X-1295571Y476338D01*
X-1298637D01*
G01X-1300617Y491021D02*
X-1301077Y491331D01*
X-1301614Y491538D01*
X-1302227D01*
X-1302917Y491228D01*
X-1303454Y490711D01*
X-1303837Y490091D01*
X-1304144Y489058D01*
X-1304221Y488128D01*
X-1304067Y487198D01*
X-1303837Y486578D01*
X-1303377Y485958D01*
X-1302841Y485545D01*
X-1302304Y485338D01*
X-1301767D01*
X-1301231Y485545D01*
X-1300771Y485855D01*
X-1300387Y486268D01*
G01X-1296257Y485338D02*
X-1296104Y486681D01*
X-1295874Y487818D01*
X-1295567Y488851D01*
X-1295184Y489988D01*
X-1294571Y491538D01*
X-1297637D01*
G01X-1291361Y487921D02*
X-1290824Y488645D01*
X-1290364Y489058D01*
X-1289751Y489265D01*
X-1289214Y489058D01*
X-1288831Y488645D01*
X-1288524Y488025D01*
X-1288447Y487301D01*
X-1288524Y486681D01*
X-1288831Y486061D01*
X-1289291Y485545D01*
X-1289827Y485338D01*
X-1290441Y485545D01*
X-1290977Y486164D01*
X-1291284Y487095D01*
X-1291361Y488128D01*
X-1291207Y489471D01*
X-1290977Y490195D01*
X-1290594Y490918D01*
X-1290057Y491435D01*
X-1289521Y491538D01*
X-1288984Y491331D01*
X-1288601Y490815D01*
G01X-1289875Y-51960D02*
Y-58160D01*
X-1286809D01*
G01X-1283829Y-56920D02*
X-1283369Y-57643D01*
X-1282755Y-58057D01*
X-1282065Y-58160D01*
X-1281452Y-58057D01*
X-1280839Y-57540D01*
X-1280455Y-56920D01*
X-1280379Y-56300D01*
X-1280532Y-55577D01*
X-1281069Y-55060D01*
X-1281605Y-54853D01*
X-1282295D01*
G01X-1281605D02*
X-1281145Y-54543D01*
X-1280762Y-54027D01*
X-1280609Y-53407D01*
X-1280762Y-52787D01*
X-1281145Y-52270D01*
X-1281835Y-51960D01*
X-1282525Y-52063D01*
X-1283215Y-52477D01*
G01X-1275022Y-58160D02*
Y-51960D01*
X-1277859Y-56403D01*
X-1274025D01*
G01X-1286804Y-8497D02*
X-1293004D01*
Y-6581D01*
X-1292694Y-5967D01*
X-1292281Y-5584D01*
X-1291454Y-5431D01*
X-1290627Y-5584D01*
X-1290111Y-6044D01*
X-1289801Y-6581D01*
Y-8497D01*
G01Y-6581D02*
X-1286804Y-5431D01*
G01Y-764D02*
X-1293004D01*
X-1291764Y-1684D01*
G01X-1286804D02*
Y156D01*
G01X-1293004Y5436D02*
X-1292797Y4823D01*
X-1292281Y4363D01*
X-1291661Y4056D01*
X-1290834Y3826D01*
X-1289904Y3749D01*
X-1288974Y3826D01*
X-1288147Y4056D01*
X-1287527Y4363D01*
X-1287011Y4823D01*
X-1286804Y5436D01*
X-1287011Y6049D01*
X-1287527Y6509D01*
X-1288147Y6816D01*
X-1288974Y7046D01*
X-1289904Y7123D01*
X-1290834Y7046D01*
X-1291661Y6816D01*
X-1292281Y6509D01*
X-1292797Y6049D01*
X-1293004Y5436D01*
G01X-1286804Y12556D02*
X-1293004D01*
X-1288561Y9719D01*
Y13553D01*
G01X-1296161Y22205D02*
X-1295701Y22825D01*
X-1295164Y23135D01*
X-1294551Y23238D01*
X-1293784Y23031D01*
X-1293247Y22515D01*
X-1293094Y21895D01*
X-1293171Y21275D01*
X-1293477Y20758D01*
X-1295011Y19725D01*
X-1295701Y19001D01*
X-1296161Y17968D01*
X-1296314Y17038D01*
X-1293094D01*
G01X-1291391Y27278D02*
X-1290931Y26555D01*
X-1290317Y26141D01*
X-1289627Y26038D01*
X-1289014Y26141D01*
X-1288401Y26658D01*
X-1288017Y27278D01*
X-1287941Y27898D01*
X-1288094Y28621D01*
X-1288631Y29138D01*
X-1289167Y29345D01*
X-1289857D01*
G01X-1289167D02*
X-1288707Y29655D01*
X-1288324Y30171D01*
X-1288171Y30791D01*
X-1288324Y31411D01*
X-1288707Y31928D01*
X-1289397Y32238D01*
X-1290087Y32135D01*
X-1290777Y31721D01*
G01X-1291161Y40621D02*
X-1290624Y41345D01*
X-1290164Y41758D01*
X-1289551Y41965D01*
X-1289014Y41758D01*
X-1288631Y41345D01*
X-1288324Y40725D01*
X-1288247Y40001D01*
X-1288324Y39381D01*
X-1288631Y38761D01*
X-1289091Y38245D01*
X-1289627Y38038D01*
X-1290241Y38245D01*
X-1290777Y38864D01*
X-1291084Y39795D01*
X-1291161Y40828D01*
X-1291007Y42171D01*
X-1290777Y42895D01*
X-1290394Y43618D01*
X-1289857Y44135D01*
X-1289321Y44238D01*
X-1288784Y44031D01*
X-1288401Y43515D01*
G01X-1287875Y95040D02*
Y88840D01*
X-1284809D01*
G01X-1281829Y90080D02*
X-1281369Y89357D01*
X-1280755Y88943D01*
X-1280065Y88840D01*
X-1279452Y88943D01*
X-1278839Y89460D01*
X-1278455Y90080D01*
X-1278379Y90700D01*
X-1278532Y91423D01*
X-1279069Y91940D01*
X-1279605Y92147D01*
X-1280295D01*
G01X-1279605D02*
X-1279145Y92457D01*
X-1278762Y92973D01*
X-1278609Y93593D01*
X-1278762Y94213D01*
X-1279145Y94730D01*
X-1279835Y95040D01*
X-1280525Y94937D01*
X-1281215Y94523D01*
G01X-1275629Y90080D02*
X-1275169Y89357D01*
X-1274555Y88943D01*
X-1273865Y88840D01*
X-1273252Y88943D01*
X-1272639Y89460D01*
X-1272255Y90080D01*
X-1272179Y90700D01*
X-1272332Y91423D01*
X-1272869Y91940D01*
X-1273405Y92147D01*
X-1274095D01*
G01X-1273405D02*
X-1272945Y92457D01*
X-1272562Y92973D01*
X-1272409Y93593D01*
X-1272562Y94213D01*
X-1272945Y94730D01*
X-1273635Y95040D01*
X-1274325Y94937D01*
X-1275015Y94523D01*
G01X-1285941Y111725D02*
X-1286251Y111265D01*
X-1286458Y110728D01*
Y110115D01*
X-1286148Y109425D01*
X-1285631Y108888D01*
X-1285011Y108505D01*
X-1283978Y108198D01*
X-1283048Y108121D01*
X-1282118Y108275D01*
X-1281498Y108505D01*
X-1280878Y108965D01*
X-1280465Y109501D01*
X-1280258Y110038D01*
Y110575D01*
X-1280465Y111111D01*
X-1280775Y111571D01*
X-1281188Y111955D01*
G01X-1280258Y117158D02*
X-1286458D01*
X-1282015Y114321D01*
Y118155D01*
G01X-1280258Y122285D02*
X-1281601Y122438D01*
X-1282738Y122668D01*
X-1283771Y122975D01*
X-1284908Y123358D01*
X-1286458Y123971D01*
Y120905D01*
G01X-1286387Y129525D02*
X-1286697Y129065D01*
X-1286904Y128528D01*
Y127915D01*
X-1286594Y127225D01*
X-1286077Y126688D01*
X-1285457Y126305D01*
X-1284424Y125998D01*
X-1283494Y125921D01*
X-1282564Y126075D01*
X-1281944Y126305D01*
X-1281324Y126765D01*
X-1280911Y127301D01*
X-1280704Y127838D01*
Y128375D01*
X-1280911Y128911D01*
X-1281221Y129371D01*
X-1281634Y129755D01*
G01Y132351D02*
X-1281117Y132811D01*
X-1280807Y133348D01*
X-1280704Y134038D01*
X-1280911Y134728D01*
X-1281324Y135265D01*
X-1282047Y135648D01*
X-1282874Y135725D01*
X-1283701Y135571D01*
X-1284217Y135188D01*
X-1284631Y134651D01*
X-1284734Y134115D01*
X-1284631Y133578D01*
X-1284217Y132888D01*
X-1286904Y133118D01*
Y135188D01*
G01X-1280704Y140238D02*
X-1286904D01*
X-1285664Y139318D01*
G01X-1280704D02*
Y141158D01*
G01X-1284784Y143938D02*
Y150138D01*
X-1287621Y145695D01*
X-1283787D01*
G01X-1282591Y165138D02*
Y160695D01*
X-1282284Y159764D01*
X-1281671Y159145D01*
X-1280904Y158938D01*
X-1280137Y159145D01*
X-1279524Y159764D01*
X-1279217Y160695D01*
Y165138D01*
G01X-1276391Y160178D02*
X-1275931Y159455D01*
X-1275317Y159041D01*
X-1274627Y158938D01*
X-1274014Y159041D01*
X-1273401Y159558D01*
X-1273017Y160178D01*
X-1272941Y160798D01*
X-1273094Y161521D01*
X-1273631Y162038D01*
X-1274167Y162245D01*
X-1274857D01*
G01X-1274167D02*
X-1273707Y162555D01*
X-1273324Y163071D01*
X-1273171Y163691D01*
X-1273324Y164311D01*
X-1273707Y164828D01*
X-1274397Y165138D01*
X-1275087Y165035D01*
X-1275777Y164621D01*
G01X-1267584Y158938D02*
Y165138D01*
X-1270421Y160695D01*
X-1266587D01*
G01X-1285391Y180178D02*
X-1284931Y179455D01*
X-1284317Y179041D01*
X-1283627Y178938D01*
X-1283014Y179041D01*
X-1282401Y179558D01*
X-1282017Y180178D01*
X-1281941Y180798D01*
X-1282094Y181521D01*
X-1282631Y182038D01*
X-1283167Y182245D01*
X-1283857D01*
G01X-1283167D02*
X-1282707Y182555D01*
X-1282324Y183071D01*
X-1282171Y183691D01*
X-1282324Y184311D01*
X-1282707Y184828D01*
X-1283397Y185138D01*
X-1284087Y185035D01*
X-1284777Y184621D01*
G01X-1296887Y197825D02*
X-1297197Y197365D01*
X-1297404Y196828D01*
Y196215D01*
X-1297094Y195525D01*
X-1296577Y194988D01*
X-1295957Y194605D01*
X-1294924Y194298D01*
X-1293994Y194221D01*
X-1293064Y194375D01*
X-1292444Y194605D01*
X-1291824Y195065D01*
X-1291411Y195601D01*
X-1291204Y196138D01*
Y196675D01*
X-1291411Y197211D01*
X-1291721Y197671D01*
X-1292134Y198055D01*
G01X-1291204Y202338D02*
X-1297404D01*
X-1296164Y201418D01*
G01X-1291204D02*
Y203258D01*
G01X-1291927Y207235D02*
X-1291411Y207771D01*
X-1291204Y208385D01*
X-1291411Y208998D01*
X-1292030Y209535D01*
X-1292961Y209918D01*
X-1293891Y210071D01*
X-1295027D01*
X-1295957Y209918D01*
X-1296784Y209535D01*
X-1297197Y209075D01*
X-1297404Y208538D01*
X-1297197Y207925D01*
X-1296784Y207465D01*
X-1296164Y207158D01*
X-1295337Y207005D01*
X-1294614Y207158D01*
X-1293891Y207541D01*
X-1293477Y208001D01*
X-1293374Y208538D01*
X-1293581Y209151D01*
X-1294097Y209611D01*
X-1295027Y210071D01*
G01X-1291204Y214738D02*
X-1291307Y215275D01*
X-1291617Y215888D01*
X-1292134Y216271D01*
X-1292857Y216425D01*
X-1293581Y216271D01*
X-1294201Y215811D01*
X-1294511Y215121D01*
Y214355D01*
X-1294717Y213895D01*
X-1295234Y213511D01*
X-1295957Y213358D01*
X-1296681Y213588D01*
X-1297197Y214125D01*
X-1297404Y214738D01*
X-1297197Y215351D01*
X-1296681Y215888D01*
X-1295957Y216118D01*
X-1295234Y215965D01*
X-1294717Y215581D01*
X-1294511Y215121D01*
Y214355D01*
X-1294201Y213665D01*
X-1293581Y213205D01*
X-1292857Y213051D01*
X-1292134Y213205D01*
X-1291617Y213588D01*
X-1291307Y214201D01*
X-1291204Y214738D01*
G01X-1282804Y198738D02*
X-1276604D01*
G01X-1282804Y196975D02*
Y200501D01*
G01X-1276604Y203405D02*
X-1282804D01*
Y205245D01*
X-1282494Y205858D01*
X-1281771Y206318D01*
X-1280944Y206471D01*
X-1280117Y206318D01*
X-1279497Y205935D01*
X-1279187Y205245D01*
Y203405D01*
G01X-1277534Y209451D02*
X-1277017Y209911D01*
X-1276707Y210448D01*
X-1276604Y211138D01*
X-1276811Y211828D01*
X-1277224Y212365D01*
X-1277947Y212748D01*
X-1278774Y212825D01*
X-1279601Y212671D01*
X-1280117Y212288D01*
X-1280531Y211751D01*
X-1280634Y211215D01*
X-1280531Y210678D01*
X-1280117Y209988D01*
X-1282804Y210218D01*
Y212288D01*
G01X-1277534Y215651D02*
X-1277017Y216111D01*
X-1276707Y216648D01*
X-1276604Y217338D01*
X-1276811Y218028D01*
X-1277224Y218565D01*
X-1277947Y218948D01*
X-1278774Y219025D01*
X-1279601Y218871D01*
X-1280117Y218488D01*
X-1280531Y217951D01*
X-1280634Y217415D01*
X-1280531Y216878D01*
X-1280117Y216188D01*
X-1282804Y216418D01*
Y218488D01*
G01X-1279537Y188970D02*
Y195170D01*
X-1277621D01*
X-1277007Y194860D01*
X-1276624Y194447D01*
X-1276471Y193620D01*
X-1276624Y192793D01*
X-1277084Y192277D01*
X-1277621Y191967D01*
X-1279537D01*
G01X-1277621D02*
X-1276471Y188970D01*
G01X-1271804D02*
Y195170D01*
X-1272724Y193930D01*
G01Y188970D02*
X-1270884D01*
G01X-1267061Y191553D02*
X-1266524Y192277D01*
X-1266064Y192690D01*
X-1265451Y192897D01*
X-1264914Y192690D01*
X-1264531Y192277D01*
X-1264224Y191657D01*
X-1264147Y190933D01*
X-1264224Y190313D01*
X-1264531Y189693D01*
X-1264991Y189177D01*
X-1265527Y188970D01*
X-1266141Y189177D01*
X-1266677Y189796D01*
X-1266984Y190727D01*
X-1267061Y191760D01*
X-1266907Y193103D01*
X-1266677Y193827D01*
X-1266294Y194550D01*
X-1265757Y195067D01*
X-1265221Y195170D01*
X-1264684Y194963D01*
X-1264301Y194447D01*
G01X-1259557Y188970D02*
X-1259404Y190313D01*
X-1259174Y191450D01*
X-1258867Y192483D01*
X-1258484Y193620D01*
X-1257871Y195170D01*
X-1260937D01*
G01X-1296387Y222425D02*
X-1296697Y221965D01*
X-1296904Y221428D01*
Y220815D01*
X-1296594Y220125D01*
X-1296077Y219588D01*
X-1295457Y219205D01*
X-1294424Y218898D01*
X-1293494Y218821D01*
X-1292564Y218975D01*
X-1291944Y219205D01*
X-1291324Y219665D01*
X-1290911Y220201D01*
X-1290704Y220738D01*
Y221275D01*
X-1290911Y221811D01*
X-1291221Y222271D01*
X-1291634Y222655D01*
G01X-1290704Y226938D02*
X-1296904D01*
X-1295664Y226018D01*
G01X-1290704D02*
Y227858D01*
G01X-1291427Y231835D02*
X-1290911Y232371D01*
X-1290704Y232985D01*
X-1290911Y233598D01*
X-1291530Y234135D01*
X-1292461Y234518D01*
X-1293391Y234671D01*
X-1294527D01*
X-1295457Y234518D01*
X-1296284Y234135D01*
X-1296697Y233675D01*
X-1296904Y233138D01*
X-1296697Y232525D01*
X-1296284Y232065D01*
X-1295664Y231758D01*
X-1294837Y231605D01*
X-1294114Y231758D01*
X-1293391Y232141D01*
X-1292977Y232601D01*
X-1292874Y233138D01*
X-1293081Y233751D01*
X-1293597Y234211D01*
X-1294527Y234671D01*
G01X-1291427Y238035D02*
X-1290911Y238571D01*
X-1290704Y239185D01*
X-1290911Y239798D01*
X-1291530Y240335D01*
X-1292461Y240718D01*
X-1293391Y240871D01*
X-1294527D01*
X-1295457Y240718D01*
X-1296284Y240335D01*
X-1296697Y239875D01*
X-1296904Y239338D01*
X-1296697Y238725D01*
X-1296284Y238265D01*
X-1295664Y237958D01*
X-1294837Y237805D01*
X-1294114Y237958D01*
X-1293391Y238341D01*
X-1292977Y238801D01*
X-1292874Y239338D01*
X-1293081Y239951D01*
X-1293597Y240411D01*
X-1294527Y240871D01*
G01X-1280887Y240825D02*
X-1281197Y240365D01*
X-1281404Y239828D01*
Y239215D01*
X-1281094Y238525D01*
X-1280577Y237988D01*
X-1279957Y237605D01*
X-1278924Y237298D01*
X-1277994Y237221D01*
X-1277064Y237375D01*
X-1276444Y237605D01*
X-1275824Y238065D01*
X-1275411Y238601D01*
X-1275204Y239138D01*
Y239675D01*
X-1275411Y240211D01*
X-1275721Y240671D01*
X-1276134Y241055D01*
G01X-1275204Y245338D02*
X-1281404D01*
X-1280164Y244418D01*
G01X-1275204D02*
Y246258D01*
G01Y251538D02*
X-1275307Y252075D01*
X-1275617Y252688D01*
X-1276134Y253071D01*
X-1276857Y253225D01*
X-1277581Y253071D01*
X-1278201Y252611D01*
X-1278511Y251921D01*
Y251155D01*
X-1278717Y250695D01*
X-1279234Y250311D01*
X-1279957Y250158D01*
X-1280681Y250388D01*
X-1281197Y250925D01*
X-1281404Y251538D01*
X-1281197Y252151D01*
X-1280681Y252688D01*
X-1279957Y252918D01*
X-1279234Y252765D01*
X-1278717Y252381D01*
X-1278511Y251921D01*
Y251155D01*
X-1278201Y250465D01*
X-1277581Y250005D01*
X-1276857Y249851D01*
X-1276134Y250005D01*
X-1275617Y250388D01*
X-1275307Y251001D01*
X-1275204Y251538D01*
G01X-1280371Y256281D02*
X-1280991Y256741D01*
X-1281301Y257278D01*
X-1281404Y257891D01*
X-1281197Y258658D01*
X-1280681Y259195D01*
X-1280061Y259348D01*
X-1279441Y259271D01*
X-1278924Y258965D01*
X-1277891Y257431D01*
X-1277167Y256741D01*
X-1276134Y256281D01*
X-1275204Y256128D01*
Y259348D01*
G01X-1282237Y271938D02*
Y265738D01*
X-1279171D01*
G01X-1274504D02*
Y271938D01*
X-1275424Y270698D01*
G01Y265738D02*
X-1273584D01*
G01X-1268304D02*
Y271938D01*
X-1269224Y270698D01*
G01Y265738D02*
X-1267384D01*
G01X-1293591Y314138D02*
Y309695D01*
X-1293284Y308764D01*
X-1292671Y308145D01*
X-1291904Y307938D01*
X-1291137Y308145D01*
X-1290524Y308764D01*
X-1290217Y309695D01*
Y314138D01*
G01X-1287161Y313105D02*
X-1286701Y313725D01*
X-1286164Y314035D01*
X-1285551Y314138D01*
X-1284784Y313931D01*
X-1284247Y313415D01*
X-1284094Y312795D01*
X-1284171Y312175D01*
X-1284477Y311658D01*
X-1286011Y310625D01*
X-1286701Y309901D01*
X-1287161Y308868D01*
X-1287314Y307938D01*
X-1284094D01*
G01X-1281191Y309178D02*
X-1280731Y308455D01*
X-1280117Y308041D01*
X-1279427Y307938D01*
X-1278814Y308041D01*
X-1278201Y308558D01*
X-1277817Y309178D01*
X-1277741Y309798D01*
X-1277894Y310521D01*
X-1278431Y311038D01*
X-1278967Y311245D01*
X-1279657D01*
G01X-1278967D02*
X-1278507Y311555D01*
X-1278124Y312071D01*
X-1277971Y312691D01*
X-1278124Y313311D01*
X-1278507Y313828D01*
X-1279197Y314138D01*
X-1279887Y314035D01*
X-1280577Y313621D01*
G01X-1283004Y412705D02*
X-1289204D01*
Y414621D01*
X-1288894Y415235D01*
X-1288481Y415618D01*
X-1287654Y415771D01*
X-1286827Y415618D01*
X-1286311Y415158D01*
X-1286001Y414621D01*
Y412705D01*
G01Y414621D02*
X-1283004Y415771D01*
G01Y420438D02*
X-1289204D01*
X-1287964Y419518D01*
G01X-1283004D02*
Y421358D01*
G01Y426485D02*
X-1284347Y426638D01*
X-1285484Y426868D01*
X-1286517Y427175D01*
X-1287654Y427558D01*
X-1289204Y428171D01*
Y425105D01*
G01X-1282004Y479138D02*
Y472938D01*
G01X-1283767Y479138D02*
X-1280241D01*
G01X-1277337Y472938D02*
Y479138D01*
X-1275497D01*
X-1274884Y478828D01*
X-1274424Y478105D01*
X-1274271Y477278D01*
X-1274424Y476451D01*
X-1274807Y475831D01*
X-1275497Y475521D01*
X-1277337D01*
G01X-1271291Y473868D02*
X-1270831Y473351D01*
X-1270294Y473041D01*
X-1269604Y472938D01*
X-1268914Y473145D01*
X-1268377Y473558D01*
X-1267994Y474281D01*
X-1267917Y475108D01*
X-1268071Y475935D01*
X-1268454Y476451D01*
X-1268991Y476865D01*
X-1269527Y476968D01*
X-1270064Y476865D01*
X-1270754Y476451D01*
X-1270524Y479138D01*
X-1268454D01*
G01X-1264707Y473661D02*
X-1264171Y473145D01*
X-1263557Y472938D01*
X-1262944Y473145D01*
X-1262407Y473764D01*
X-1262024Y474695D01*
X-1261871Y475625D01*
Y476761D01*
X-1262024Y477691D01*
X-1262407Y478518D01*
X-1262867Y478931D01*
X-1263404Y479138D01*
X-1264017Y478931D01*
X-1264477Y478518D01*
X-1264784Y477898D01*
X-1264937Y477071D01*
X-1264784Y476348D01*
X-1264401Y475625D01*
X-1263941Y475211D01*
X-1263404Y475108D01*
X-1262791Y475315D01*
X-1262331Y475831D01*
X-1261871Y476761D01*
G01X-1272804Y-192262D02*
X-1266604D01*
G01X-1272804Y-194025D02*
Y-190499D01*
G01X-1266604Y-187595D02*
X-1272804D01*
Y-185755D01*
X-1272494Y-185142D01*
X-1271771Y-184682D01*
X-1270944Y-184529D01*
X-1270117Y-184682D01*
X-1269497Y-185065D01*
X-1269187Y-185755D01*
Y-187595D01*
G01X-1267534Y-181549D02*
X-1267017Y-181089D01*
X-1266707Y-180552D01*
X-1266604Y-179862D01*
X-1266811Y-179172D01*
X-1267224Y-178635D01*
X-1267947Y-178252D01*
X-1268774Y-178175D01*
X-1269601Y-178329D01*
X-1270117Y-178712D01*
X-1270531Y-179249D01*
X-1270634Y-179785D01*
X-1270531Y-180322D01*
X-1270117Y-181012D01*
X-1272804Y-180782D01*
Y-178712D01*
G01Y-173662D02*
X-1272597Y-174275D01*
X-1272081Y-174735D01*
X-1271461Y-175042D01*
X-1270634Y-175272D01*
X-1269704Y-175349D01*
X-1268774Y-175272D01*
X-1267947Y-175042D01*
X-1267327Y-174735D01*
X-1266811Y-174275D01*
X-1266604Y-173662D01*
X-1266811Y-173049D01*
X-1267327Y-172589D01*
X-1267947Y-172282D01*
X-1268774Y-172052D01*
X-1269704Y-171975D01*
X-1270634Y-172052D01*
X-1271461Y-172282D01*
X-1272081Y-172589D01*
X-1272597Y-173049D01*
X-1272804Y-173662D01*
G01X-1266317Y-155379D02*
X-1266777Y-155069D01*
X-1267314Y-154862D01*
X-1267927D01*
X-1268617Y-155172D01*
X-1269154Y-155689D01*
X-1269537Y-156309D01*
X-1269844Y-157342D01*
X-1269921Y-158272D01*
X-1269767Y-159202D01*
X-1269537Y-159822D01*
X-1269077Y-160442D01*
X-1268541Y-160855D01*
X-1268004Y-161062D01*
X-1267467D01*
X-1266931Y-160855D01*
X-1266471Y-160545D01*
X-1266087Y-160132D01*
G01X-1263261Y-155895D02*
X-1262801Y-155275D01*
X-1262264Y-154965D01*
X-1261651Y-154862D01*
X-1260884Y-155069D01*
X-1260347Y-155585D01*
X-1260194Y-156205D01*
X-1260271Y-156825D01*
X-1260577Y-157342D01*
X-1262111Y-158375D01*
X-1262801Y-159099D01*
X-1263261Y-160132D01*
X-1263414Y-161062D01*
X-1260194D01*
G01X-1254684D02*
Y-154862D01*
X-1257521Y-159305D01*
X-1253687D01*
G01X-1249557Y-161062D02*
X-1249404Y-159719D01*
X-1249174Y-158582D01*
X-1248867Y-157549D01*
X-1248484Y-156412D01*
X-1247871Y-154862D01*
X-1250937D01*
G01X-1265317Y-136379D02*
X-1265777Y-136069D01*
X-1266314Y-135862D01*
X-1266927D01*
X-1267617Y-136172D01*
X-1268154Y-136689D01*
X-1268537Y-137309D01*
X-1268844Y-138342D01*
X-1268921Y-139272D01*
X-1268767Y-140202D01*
X-1268537Y-140822D01*
X-1268077Y-141442D01*
X-1267541Y-141855D01*
X-1267004Y-142062D01*
X-1266467D01*
X-1265931Y-141855D01*
X-1265471Y-141545D01*
X-1265087Y-141132D01*
G01X-1262261Y-136895D02*
X-1261801Y-136275D01*
X-1261264Y-135965D01*
X-1260651Y-135862D01*
X-1259884Y-136069D01*
X-1259347Y-136585D01*
X-1259194Y-137205D01*
X-1259271Y-137825D01*
X-1259577Y-138342D01*
X-1261111Y-139375D01*
X-1261801Y-140099D01*
X-1262261Y-141132D01*
X-1262414Y-142062D01*
X-1259194D01*
G01X-1255907Y-141339D02*
X-1255371Y-141855D01*
X-1254757Y-142062D01*
X-1254144Y-141855D01*
X-1253607Y-141236D01*
X-1253224Y-140305D01*
X-1253071Y-139375D01*
Y-138239D01*
X-1253224Y-137309D01*
X-1253607Y-136482D01*
X-1254067Y-136069D01*
X-1254604Y-135862D01*
X-1255217Y-136069D01*
X-1255677Y-136482D01*
X-1255984Y-137102D01*
X-1256137Y-137929D01*
X-1255984Y-138652D01*
X-1255601Y-139375D01*
X-1255141Y-139789D01*
X-1254604Y-139892D01*
X-1253991Y-139685D01*
X-1253531Y-139169D01*
X-1253071Y-138239D01*
G01X-1248404Y-142062D02*
Y-135862D01*
X-1249324Y-137102D01*
G01Y-142062D02*
X-1247484D01*
G01X-1272287Y-35575D02*
X-1272597Y-36035D01*
X-1272804Y-36572D01*
Y-37185D01*
X-1272494Y-37875D01*
X-1271977Y-38412D01*
X-1271357Y-38795D01*
X-1270324Y-39102D01*
X-1269394Y-39179D01*
X-1268464Y-39025D01*
X-1267844Y-38795D01*
X-1267224Y-38335D01*
X-1266811Y-37799D01*
X-1266604Y-37262D01*
Y-36725D01*
X-1266811Y-36189D01*
X-1267121Y-35729D01*
X-1267534Y-35345D01*
G01X-1266604Y-31062D02*
X-1272804D01*
X-1271564Y-31982D01*
G01X-1266604D02*
Y-30142D01*
G01X-1267844Y-26549D02*
X-1267121Y-26089D01*
X-1266707Y-25475D01*
X-1266604Y-24785D01*
X-1266707Y-24172D01*
X-1267224Y-23559D01*
X-1267844Y-23175D01*
X-1268464Y-23099D01*
X-1269187Y-23252D01*
X-1269704Y-23789D01*
X-1269911Y-24325D01*
Y-25015D01*
G01Y-24325D02*
X-1270221Y-23865D01*
X-1270737Y-23482D01*
X-1271357Y-23329D01*
X-1271977Y-23482D01*
X-1272494Y-23865D01*
X-1272804Y-24555D01*
X-1272701Y-25245D01*
X-1272287Y-25935D01*
G01X-1266604Y-18815D02*
X-1267947Y-18662D01*
X-1269084Y-18432D01*
X-1270117Y-18125D01*
X-1271254Y-17742D01*
X-1272804Y-17129D01*
Y-20195D01*
G01X-1267804Y738D02*
X-1261604D01*
G01X-1267804Y-1025D02*
Y2501D01*
G01X-1261604Y5405D02*
X-1267804D01*
Y7245D01*
X-1267494Y7858D01*
X-1266771Y8318D01*
X-1265944Y8471D01*
X-1265117Y8318D01*
X-1264497Y7935D01*
X-1264187Y7245D01*
Y5405D01*
G01X-1261604Y14058D02*
X-1267804D01*
X-1263361Y11221D01*
Y15055D01*
G01X-1261604Y19185D02*
X-1262947Y19338D01*
X-1264084Y19568D01*
X-1265117Y19875D01*
X-1266254Y20258D01*
X-1267804Y20871D01*
Y17805D01*
G01X-1256636Y119205D02*
X-1262836D01*
Y121121D01*
X-1262526Y121735D01*
X-1262113Y122118D01*
X-1261286Y122271D01*
X-1260459Y122118D01*
X-1259943Y121658D01*
X-1259633Y121121D01*
Y119205D01*
G01Y121121D02*
X-1256636Y122271D01*
G01Y126938D02*
X-1262836D01*
X-1261596Y126018D01*
G01X-1256636D02*
Y127858D01*
G01X-1259219Y131681D02*
X-1259943Y132218D01*
X-1260356Y132678D01*
X-1260563Y133291D01*
X-1260356Y133828D01*
X-1259943Y134211D01*
X-1259323Y134518D01*
X-1258599Y134595D01*
X-1257979Y134518D01*
X-1257359Y134211D01*
X-1256843Y133751D01*
X-1256636Y133215D01*
X-1256843Y132601D01*
X-1257462Y132065D01*
X-1258393Y131758D01*
X-1259426Y131681D01*
X-1260769Y131835D01*
X-1261493Y132065D01*
X-1262216Y132448D01*
X-1262733Y132985D01*
X-1262836Y133521D01*
X-1262629Y134058D01*
X-1262113Y134441D01*
G01X-1256636Y140258D02*
X-1262836D01*
X-1258393Y137421D01*
Y141255D01*
G01X-1273319Y122425D02*
X-1273629Y121965D01*
X-1273836Y121428D01*
Y120815D01*
X-1273526Y120125D01*
X-1273009Y119588D01*
X-1272389Y119205D01*
X-1271356Y118898D01*
X-1270426Y118821D01*
X-1269496Y118975D01*
X-1268876Y119205D01*
X-1268256Y119665D01*
X-1267843Y120201D01*
X-1267636Y120738D01*
Y121275D01*
X-1267843Y121811D01*
X-1268153Y122271D01*
X-1268566Y122655D01*
G01X-1272803Y125481D02*
X-1273423Y125941D01*
X-1273733Y126478D01*
X-1273836Y127091D01*
X-1273629Y127858D01*
X-1273113Y128395D01*
X-1272493Y128548D01*
X-1271873Y128471D01*
X-1271356Y128165D01*
X-1270323Y126631D01*
X-1269599Y125941D01*
X-1268566Y125481D01*
X-1267636Y125328D01*
Y128548D01*
G01X-1268566Y131451D02*
X-1268049Y131911D01*
X-1267739Y132448D01*
X-1267636Y133138D01*
X-1267843Y133828D01*
X-1268256Y134365D01*
X-1268979Y134748D01*
X-1269806Y134825D01*
X-1270633Y134671D01*
X-1271149Y134288D01*
X-1271563Y133751D01*
X-1271666Y133215D01*
X-1271563Y132678D01*
X-1271149Y131988D01*
X-1273836Y132218D01*
Y134288D01*
G01Y139338D02*
X-1273629Y138725D01*
X-1273113Y138265D01*
X-1272493Y137958D01*
X-1271666Y137728D01*
X-1270736Y137651D01*
X-1269806Y137728D01*
X-1268979Y137958D01*
X-1268359Y138265D01*
X-1267843Y138725D01*
X-1267636Y139338D01*
X-1267843Y139951D01*
X-1268359Y140411D01*
X-1268979Y140718D01*
X-1269806Y140948D01*
X-1270736Y141025D01*
X-1271666Y140948D01*
X-1272493Y140718D01*
X-1273113Y140411D01*
X-1273629Y139951D01*
X-1273836Y139338D01*
G01X-1267487Y208825D02*
X-1267797Y208365D01*
X-1268004Y207828D01*
Y207215D01*
X-1267694Y206525D01*
X-1267177Y205988D01*
X-1266557Y205605D01*
X-1265524Y205298D01*
X-1264594Y205221D01*
X-1263664Y205375D01*
X-1263044Y205605D01*
X-1262424Y206065D01*
X-1262011Y206601D01*
X-1261804Y207138D01*
Y207675D01*
X-1262011Y208211D01*
X-1262321Y208671D01*
X-1262734Y209055D01*
G01X-1261804Y213338D02*
X-1268004D01*
X-1266764Y212418D01*
G01X-1261804D02*
Y214258D01*
G01X-1262527Y218235D02*
X-1262011Y218771D01*
X-1261804Y219385D01*
X-1262011Y219998D01*
X-1262630Y220535D01*
X-1263561Y220918D01*
X-1264491Y221071D01*
X-1265627D01*
X-1266557Y220918D01*
X-1267384Y220535D01*
X-1267797Y220075D01*
X-1268004Y219538D01*
X-1267797Y218925D01*
X-1267384Y218465D01*
X-1266764Y218158D01*
X-1265937Y218005D01*
X-1265214Y218158D01*
X-1264491Y218541D01*
X-1264077Y219001D01*
X-1263974Y219538D01*
X-1264181Y220151D01*
X-1264697Y220611D01*
X-1265627Y221071D01*
G01X-1261804Y226658D02*
X-1268004D01*
X-1263561Y223821D01*
Y227655D01*
G01X-1266887Y238425D02*
X-1267197Y237965D01*
X-1267404Y237428D01*
Y236815D01*
X-1267094Y236125D01*
X-1266577Y235588D01*
X-1265957Y235205D01*
X-1264924Y234898D01*
X-1263994Y234821D01*
X-1263064Y234975D01*
X-1262444Y235205D01*
X-1261824Y235665D01*
X-1261411Y236201D01*
X-1261204Y236738D01*
Y237275D01*
X-1261411Y237811D01*
X-1261721Y238271D01*
X-1262134Y238655D01*
G01X-1261204Y242938D02*
X-1267404D01*
X-1266164Y242018D01*
G01X-1261204D02*
Y243858D01*
G01Y249138D02*
X-1261307Y249675D01*
X-1261617Y250288D01*
X-1262134Y250671D01*
X-1262857Y250825D01*
X-1263581Y250671D01*
X-1264201Y250211D01*
X-1264511Y249521D01*
Y248755D01*
X-1264717Y248295D01*
X-1265234Y247911D01*
X-1265957Y247758D01*
X-1266681Y247988D01*
X-1267197Y248525D01*
X-1267404Y249138D01*
X-1267197Y249751D01*
X-1266681Y250288D01*
X-1265957Y250518D01*
X-1265234Y250365D01*
X-1264717Y249981D01*
X-1264511Y249521D01*
Y248755D01*
X-1264201Y248065D01*
X-1263581Y247605D01*
X-1262857Y247451D01*
X-1262134Y247605D01*
X-1261617Y247988D01*
X-1261307Y248601D01*
X-1261204Y249138D01*
G01X-1262134Y253651D02*
X-1261617Y254111D01*
X-1261307Y254648D01*
X-1261204Y255338D01*
X-1261411Y256028D01*
X-1261824Y256565D01*
X-1262547Y256948D01*
X-1263374Y257025D01*
X-1264201Y256871D01*
X-1264717Y256488D01*
X-1265131Y255951D01*
X-1265234Y255415D01*
X-1265131Y254878D01*
X-1264717Y254188D01*
X-1267404Y254418D01*
Y256488D01*
G01X-1265537Y265038D02*
Y271238D01*
X-1263621D01*
X-1263007Y270928D01*
X-1262624Y270515D01*
X-1262471Y269688D01*
X-1262624Y268861D01*
X-1263084Y268345D01*
X-1263621Y268035D01*
X-1265537D01*
G01X-1263621D02*
X-1262471Y265038D01*
G01X-1257804D02*
Y271238D01*
X-1258724Y269998D01*
G01Y265038D02*
X-1256884D01*
G01X-1250684D02*
Y271238D01*
X-1253521Y266795D01*
X-1249687D01*
G01X-1245404Y271238D02*
X-1246017Y271031D01*
X-1246477Y270515D01*
X-1246784Y269895D01*
X-1247014Y269068D01*
X-1247091Y268138D01*
X-1247014Y267208D01*
X-1246784Y266381D01*
X-1246477Y265761D01*
X-1246017Y265245D01*
X-1245404Y265038D01*
X-1244791Y265245D01*
X-1244331Y265761D01*
X-1244024Y266381D01*
X-1243794Y267208D01*
X-1243717Y268138D01*
X-1243794Y269068D01*
X-1244024Y269895D01*
X-1244331Y270515D01*
X-1244791Y271031D01*
X-1245404Y271238D01*
G01X-1269838Y489220D02*
Y483020D01*
G01X-1271601Y489220D02*
X-1268075D01*
G01X-1265171Y483020D02*
Y489220D01*
X-1263331D01*
X-1262718Y488910D01*
X-1262258Y488187D01*
X-1262105Y487360D01*
X-1262258Y486533D01*
X-1262641Y485913D01*
X-1263331Y485603D01*
X-1265171D01*
G01X-1259125Y484260D02*
X-1258665Y483537D01*
X-1258051Y483123D01*
X-1257361Y483020D01*
X-1256748Y483123D01*
X-1256135Y483640D01*
X-1255751Y484260D01*
X-1255675Y484880D01*
X-1255828Y485603D01*
X-1256365Y486120D01*
X-1256901Y486327D01*
X-1257591D01*
G01X-1256901D02*
X-1256441Y486637D01*
X-1256058Y487153D01*
X-1255905Y487773D01*
X-1256058Y488393D01*
X-1256441Y488910D01*
X-1257131Y489220D01*
X-1257821Y489117D01*
X-1258511Y488703D01*
G01X-1251238Y483020D02*
X-1250701Y483123D01*
X-1250088Y483433D01*
X-1249705Y483950D01*
X-1249551Y484673D01*
X-1249705Y485397D01*
X-1250165Y486017D01*
X-1250855Y486327D01*
X-1251621D01*
X-1252081Y486533D01*
X-1252465Y487050D01*
X-1252618Y487773D01*
X-1252388Y488497D01*
X-1251851Y489013D01*
X-1251238Y489220D01*
X-1250625Y489013D01*
X-1250088Y488497D01*
X-1249858Y487773D01*
X-1250011Y487050D01*
X-1250395Y486533D01*
X-1250855Y486327D01*
X-1251621D01*
X-1252311Y486017D01*
X-1252771Y485397D01*
X-1252925Y484673D01*
X-1252771Y483950D01*
X-1252388Y483433D01*
X-1251775Y483123D01*
X-1251238Y483020D01*
G01X-1254704Y-187795D02*
X-1260904D01*
Y-185879D01*
X-1260594Y-185265D01*
X-1260181Y-184882D01*
X-1259354Y-184729D01*
X-1258527Y-184882D01*
X-1258011Y-185342D01*
X-1257701Y-185879D01*
Y-187795D01*
G01Y-185879D02*
X-1254704Y-184729D01*
G01X-1259871Y-181519D02*
X-1260491Y-181059D01*
X-1260801Y-180522D01*
X-1260904Y-179909D01*
X-1260697Y-179142D01*
X-1260181Y-178605D01*
X-1259561Y-178452D01*
X-1258941Y-178529D01*
X-1258424Y-178835D01*
X-1257391Y-180369D01*
X-1256667Y-181059D01*
X-1255634Y-181519D01*
X-1254704Y-181672D01*
Y-178452D01*
G01X-1255944Y-175549D02*
X-1255221Y-175089D01*
X-1254807Y-174475D01*
X-1254704Y-173785D01*
X-1254807Y-173172D01*
X-1255324Y-172559D01*
X-1255944Y-172175D01*
X-1256564Y-172099D01*
X-1257287Y-172252D01*
X-1257804Y-172789D01*
X-1258011Y-173325D01*
Y-174015D01*
G01Y-173325D02*
X-1258321Y-172865D01*
X-1258837Y-172482D01*
X-1259457Y-172329D01*
X-1260077Y-172482D01*
X-1260594Y-172865D01*
X-1260904Y-173555D01*
X-1260801Y-174245D01*
X-1260387Y-174935D01*
G01X-1257287Y-169119D02*
X-1258011Y-168582D01*
X-1258424Y-168122D01*
X-1258631Y-167509D01*
X-1258424Y-166972D01*
X-1258011Y-166589D01*
X-1257391Y-166282D01*
X-1256667Y-166205D01*
X-1256047Y-166282D01*
X-1255427Y-166589D01*
X-1254911Y-167049D01*
X-1254704Y-167585D01*
X-1254911Y-168199D01*
X-1255530Y-168735D01*
X-1256461Y-169042D01*
X-1257494Y-169119D01*
X-1258837Y-168965D01*
X-1259561Y-168735D01*
X-1260284Y-168352D01*
X-1260801Y-167815D01*
X-1260904Y-167279D01*
X-1260697Y-166742D01*
X-1260181Y-166359D01*
G01X-1248161Y-169379D02*
X-1247624Y-168655D01*
X-1247164Y-168242D01*
X-1246551Y-168035D01*
X-1246014Y-168242D01*
X-1245631Y-168655D01*
X-1245324Y-169275D01*
X-1245247Y-169999D01*
X-1245324Y-170619D01*
X-1245631Y-171239D01*
X-1246091Y-171755D01*
X-1246627Y-171962D01*
X-1247241Y-171755D01*
X-1247777Y-171136D01*
X-1248084Y-170205D01*
X-1248161Y-169172D01*
X-1248007Y-167829D01*
X-1247777Y-167105D01*
X-1247394Y-166382D01*
X-1246857Y-165865D01*
X-1246321Y-165762D01*
X-1245784Y-165969D01*
X-1245401Y-166485D01*
G01X-1242317Y-156379D02*
X-1242777Y-156069D01*
X-1243314Y-155862D01*
X-1243927D01*
X-1244617Y-156172D01*
X-1245154Y-156689D01*
X-1245537Y-157309D01*
X-1245844Y-158342D01*
X-1245921Y-159272D01*
X-1245767Y-160202D01*
X-1245537Y-160822D01*
X-1245077Y-161442D01*
X-1244541Y-161855D01*
X-1244004Y-162062D01*
X-1243467D01*
X-1242931Y-161855D01*
X-1242471Y-161545D01*
X-1242087Y-161132D01*
G01X-1239261Y-156895D02*
X-1238801Y-156275D01*
X-1238264Y-155965D01*
X-1237651Y-155862D01*
X-1236884Y-156069D01*
X-1236347Y-156585D01*
X-1236194Y-157205D01*
X-1236271Y-157825D01*
X-1236577Y-158342D01*
X-1238111Y-159375D01*
X-1238801Y-160099D01*
X-1239261Y-161132D01*
X-1239414Y-162062D01*
X-1236194D01*
G01X-1230684D02*
Y-155862D01*
X-1233521Y-160305D01*
X-1229687D01*
G01X-1226707Y-161339D02*
X-1226171Y-161855D01*
X-1225557Y-162062D01*
X-1224944Y-161855D01*
X-1224407Y-161236D01*
X-1224024Y-160305D01*
X-1223871Y-159375D01*
Y-158239D01*
X-1224024Y-157309D01*
X-1224407Y-156482D01*
X-1224867Y-156069D01*
X-1225404Y-155862D01*
X-1226017Y-156069D01*
X-1226477Y-156482D01*
X-1226784Y-157102D01*
X-1226937Y-157929D01*
X-1226784Y-158652D01*
X-1226401Y-159375D01*
X-1225941Y-159789D01*
X-1225404Y-159892D01*
X-1224791Y-159685D01*
X-1224331Y-159169D01*
X-1223871Y-158239D01*
G01X-1244858Y-82982D02*
X-1251058D01*
X-1249818Y-83902D01*
G01X-1244858D02*
Y-82062D01*
G01X-1253858Y-60062D02*
X-1260058D01*
X-1255615Y-62899D01*
Y-59065D01*
G01X-1259025Y-77439D02*
X-1259645Y-76979D01*
X-1259955Y-76442D01*
X-1260058Y-75829D01*
X-1259851Y-75062D01*
X-1259335Y-74525D01*
X-1258715Y-74372D01*
X-1258095Y-74449D01*
X-1257578Y-74755D01*
X-1256545Y-76289D01*
X-1255821Y-76979D01*
X-1254788Y-77439D01*
X-1253858Y-77592D01*
Y-74372D01*
G01X-1246098Y-68669D02*
X-1245375Y-68209D01*
X-1244961Y-67595D01*
X-1244858Y-66905D01*
X-1244961Y-66292D01*
X-1245478Y-65679D01*
X-1246098Y-65295D01*
X-1246718Y-65219D01*
X-1247441Y-65372D01*
X-1247958Y-65909D01*
X-1248165Y-66445D01*
Y-67135D01*
G01Y-66445D02*
X-1248475Y-65985D01*
X-1248991Y-65602D01*
X-1249611Y-65449D01*
X-1250231Y-65602D01*
X-1250748Y-65985D01*
X-1251058Y-66675D01*
X-1250955Y-67365D01*
X-1250541Y-68055D01*
G01X-1256441Y-45439D02*
X-1257165Y-44902D01*
X-1257578Y-44442D01*
X-1257785Y-43829D01*
X-1257578Y-43292D01*
X-1257165Y-42909D01*
X-1256545Y-42602D01*
X-1255821Y-42525D01*
X-1255201Y-42602D01*
X-1254581Y-42909D01*
X-1254065Y-43369D01*
X-1253858Y-43905D01*
X-1254065Y-44519D01*
X-1254684Y-45055D01*
X-1255615Y-45362D01*
X-1256648Y-45439D01*
X-1257991Y-45285D01*
X-1258715Y-45055D01*
X-1259438Y-44672D01*
X-1259955Y-44135D01*
X-1260058Y-43599D01*
X-1259851Y-43062D01*
X-1259335Y-42679D01*
G01X-1245788Y-52669D02*
X-1245271Y-52209D01*
X-1244961Y-51672D01*
X-1244858Y-50982D01*
X-1245065Y-50292D01*
X-1245478Y-49755D01*
X-1246201Y-49372D01*
X-1247028Y-49295D01*
X-1247855Y-49449D01*
X-1248371Y-49832D01*
X-1248785Y-50369D01*
X-1248888Y-50905D01*
X-1248785Y-51442D01*
X-1248371Y-52132D01*
X-1251058Y-51902D01*
Y-49832D01*
G01X-1253858Y-28982D02*
X-1253961Y-28445D01*
X-1254271Y-27832D01*
X-1254788Y-27449D01*
X-1255511Y-27295D01*
X-1256235Y-27449D01*
X-1256855Y-27909D01*
X-1257165Y-28599D01*
Y-29365D01*
X-1257371Y-29825D01*
X-1257888Y-30209D01*
X-1258611Y-30362D01*
X-1259335Y-30132D01*
X-1259851Y-29595D01*
X-1260058Y-28982D01*
X-1259851Y-28369D01*
X-1259335Y-27832D01*
X-1258611Y-27602D01*
X-1257888Y-27755D01*
X-1257371Y-28139D01*
X-1257165Y-28599D01*
Y-29365D01*
X-1256855Y-30055D01*
X-1256235Y-30515D01*
X-1255511Y-30669D01*
X-1254788Y-30515D01*
X-1254271Y-30132D01*
X-1253961Y-29519D01*
X-1253858Y-28982D01*
G01X-1244858Y-35135D02*
X-1246201Y-34982D01*
X-1247338Y-34752D01*
X-1248371Y-34445D01*
X-1249508Y-34062D01*
X-1251058Y-33449D01*
Y-36515D01*
G01X-1253858Y-18082D02*
X-1260058D01*
X-1258818Y-19002D01*
G01X-1253858D02*
Y-17162D01*
G01X-1260058Y-11882D02*
X-1259851Y-12495D01*
X-1259335Y-12955D01*
X-1258715Y-13262D01*
X-1257888Y-13492D01*
X-1256958Y-13569D01*
X-1256028Y-13492D01*
X-1255201Y-13262D01*
X-1254581Y-12955D01*
X-1254065Y-12495D01*
X-1253858Y-11882D01*
X-1254065Y-11269D01*
X-1254581Y-10809D01*
X-1255201Y-10502D01*
X-1256028Y-10272D01*
X-1256958Y-10195D01*
X-1257888Y-10272D01*
X-1258715Y-10502D01*
X-1259335Y-10809D01*
X-1259851Y-11269D01*
X-1260058Y-11882D01*
G01X-1244858Y-11082D02*
X-1251058D01*
X-1249818Y-12002D01*
G01X-1244858D02*
Y-10162D01*
G01Y-4882D02*
X-1251058D01*
X-1249818Y-5802D01*
G01X-1244858D02*
Y-3962D01*
G01X-1245581Y-21285D02*
X-1245065Y-20749D01*
X-1244858Y-20135D01*
X-1245065Y-19522D01*
X-1245684Y-18985D01*
X-1246615Y-18602D01*
X-1247545Y-18449D01*
X-1248681D01*
X-1249611Y-18602D01*
X-1250438Y-18985D01*
X-1250851Y-19445D01*
X-1251058Y-19982D01*
X-1250851Y-20595D01*
X-1250438Y-21055D01*
X-1249818Y-21362D01*
X-1248991Y-21515D01*
X-1248268Y-21362D01*
X-1247545Y-20979D01*
X-1247131Y-20519D01*
X-1247028Y-19982D01*
X-1247235Y-19369D01*
X-1247751Y-18909D01*
X-1248681Y-18449D01*
G01X-1253858Y-4082D02*
X-1260058D01*
X-1258818Y-5002D01*
G01X-1253858D02*
Y-3162D01*
G01X-1259025Y661D02*
X-1259645Y1121D01*
X-1259955Y1658D01*
X-1260058Y2271D01*
X-1259851Y3038D01*
X-1259335Y3575D01*
X-1258715Y3728D01*
X-1258095Y3651D01*
X-1257578Y3345D01*
X-1256545Y1811D01*
X-1255821Y1121D01*
X-1254788Y661D01*
X-1253858Y508D01*
Y3728D01*
G01X-1244858Y4918D02*
X-1251058D01*
X-1249818Y3998D01*
G01X-1244858D02*
Y5838D01*
G01X-1246098Y9431D02*
X-1245375Y9891D01*
X-1244961Y10505D01*
X-1244858Y11195D01*
X-1244961Y11808D01*
X-1245478Y12421D01*
X-1246098Y12805D01*
X-1246718Y12881D01*
X-1247441Y12728D01*
X-1247958Y12191D01*
X-1248165Y11655D01*
Y10965D01*
G01Y11655D02*
X-1248475Y12115D01*
X-1248991Y12498D01*
X-1249611Y12651D01*
X-1250231Y12498D01*
X-1250748Y12115D01*
X-1251058Y11425D01*
X-1250955Y10735D01*
X-1250541Y10045D01*
G01X-1253858Y11918D02*
X-1260058D01*
X-1258818Y10998D01*
G01X-1253858D02*
Y12838D01*
G01Y19038D02*
X-1260058D01*
X-1255615Y16201D01*
Y20035D01*
G01X-1244858Y20918D02*
X-1251058D01*
X-1249818Y19998D01*
G01X-1244858D02*
Y21838D01*
G01X-1245788Y25431D02*
X-1245271Y25891D01*
X-1244961Y26428D01*
X-1244858Y27118D01*
X-1245065Y27808D01*
X-1245478Y28345D01*
X-1246201Y28728D01*
X-1247028Y28805D01*
X-1247855Y28651D01*
X-1248371Y28268D01*
X-1248785Y27731D01*
X-1248888Y27195D01*
X-1248785Y26658D01*
X-1248371Y25968D01*
X-1251058Y26198D01*
Y28268D01*
G01X-1253858Y27918D02*
X-1260058D01*
X-1258818Y26998D01*
G01X-1253858D02*
Y28838D01*
G01X-1256441Y32661D02*
X-1257165Y33198D01*
X-1257578Y33658D01*
X-1257785Y34271D01*
X-1257578Y34808D01*
X-1257165Y35191D01*
X-1256545Y35498D01*
X-1255821Y35575D01*
X-1255201Y35498D01*
X-1254581Y35191D01*
X-1254065Y34731D01*
X-1253858Y34195D01*
X-1254065Y33581D01*
X-1254684Y33045D01*
X-1255615Y32738D01*
X-1256648Y32661D01*
X-1257991Y32815D01*
X-1258715Y33045D01*
X-1259438Y33428D01*
X-1259955Y33965D01*
X-1260058Y34501D01*
X-1259851Y35038D01*
X-1259335Y35421D01*
G01X-1253858Y42918D02*
X-1260058D01*
X-1258818Y41998D01*
G01X-1253858D02*
Y43838D01*
G01Y49118D02*
X-1253961Y49655D01*
X-1254271Y50268D01*
X-1254788Y50651D01*
X-1255511Y50805D01*
X-1256235Y50651D01*
X-1256855Y50191D01*
X-1257165Y49501D01*
Y48735D01*
X-1257371Y48275D01*
X-1257888Y47891D01*
X-1258611Y47738D01*
X-1259335Y47968D01*
X-1259851Y48505D01*
X-1260058Y49118D01*
X-1259851Y49731D01*
X-1259335Y50268D01*
X-1258611Y50498D01*
X-1257888Y50345D01*
X-1257371Y49961D01*
X-1257165Y49501D01*
Y48735D01*
X-1256855Y48045D01*
X-1256235Y47585D01*
X-1255511Y47431D01*
X-1254788Y47585D01*
X-1254271Y47968D01*
X-1253961Y48581D01*
X-1253858Y49118D01*
G01X-1244858Y36918D02*
X-1251058D01*
X-1249818Y35998D01*
G01X-1244858D02*
Y37838D01*
G01Y42965D02*
X-1246201Y43118D01*
X-1247338Y43348D01*
X-1248371Y43655D01*
X-1249508Y44038D01*
X-1251058Y44651D01*
Y41585D01*
G01X-1259025Y58461D02*
X-1259645Y58921D01*
X-1259955Y59458D01*
X-1260058Y60071D01*
X-1259851Y60838D01*
X-1259335Y61375D01*
X-1258715Y61528D01*
X-1258095Y61451D01*
X-1257578Y61145D01*
X-1256545Y59611D01*
X-1255821Y58921D01*
X-1254788Y58461D01*
X-1253858Y58308D01*
Y61528D01*
G01X-1260058Y66118D02*
X-1259851Y65505D01*
X-1259335Y65045D01*
X-1258715Y64738D01*
X-1257888Y64508D01*
X-1256958Y64431D01*
X-1256028Y64508D01*
X-1255201Y64738D01*
X-1254581Y65045D01*
X-1254065Y65505D01*
X-1253858Y66118D01*
X-1254065Y66731D01*
X-1254581Y67191D01*
X-1255201Y67498D01*
X-1256028Y67728D01*
X-1256958Y67805D01*
X-1257888Y67728D01*
X-1258715Y67498D01*
X-1259335Y67191D01*
X-1259851Y66731D01*
X-1260058Y66118D01*
G01X-1244858Y51918D02*
X-1251058D01*
X-1249818Y50998D01*
G01X-1244858D02*
Y52838D01*
G01X-1245581Y56815D02*
X-1245065Y57351D01*
X-1244858Y57965D01*
X-1245065Y58578D01*
X-1245684Y59115D01*
X-1246615Y59498D01*
X-1247545Y59651D01*
X-1248681D01*
X-1249611Y59498D01*
X-1250438Y59115D01*
X-1250851Y58655D01*
X-1251058Y58118D01*
X-1250851Y57505D01*
X-1250438Y57045D01*
X-1249818Y56738D01*
X-1248991Y56585D01*
X-1248268Y56738D01*
X-1247545Y57121D01*
X-1247131Y57581D01*
X-1247028Y58118D01*
X-1247235Y58731D01*
X-1247751Y59191D01*
X-1248681Y59651D01*
G01X-1259025Y74461D02*
X-1259645Y74921D01*
X-1259955Y75458D01*
X-1260058Y76071D01*
X-1259851Y76838D01*
X-1259335Y77375D01*
X-1258715Y77528D01*
X-1258095Y77451D01*
X-1257578Y77145D01*
X-1256545Y75611D01*
X-1255821Y74921D01*
X-1254788Y74461D01*
X-1253858Y74308D01*
Y77528D01*
G01X-1259025Y80661D02*
X-1259645Y81121D01*
X-1259955Y81658D01*
X-1260058Y82271D01*
X-1259851Y83038D01*
X-1259335Y83575D01*
X-1258715Y83728D01*
X-1258095Y83651D01*
X-1257578Y83345D01*
X-1256545Y81811D01*
X-1255821Y81121D01*
X-1254788Y80661D01*
X-1253858Y80508D01*
Y83728D01*
G01X-1250025Y67461D02*
X-1250645Y67921D01*
X-1250955Y68458D01*
X-1251058Y69071D01*
X-1250851Y69838D01*
X-1250335Y70375D01*
X-1249715Y70528D01*
X-1249095Y70451D01*
X-1248578Y70145D01*
X-1247545Y68611D01*
X-1246821Y67921D01*
X-1245788Y67461D01*
X-1244858Y67308D01*
Y70528D01*
G01Y75118D02*
X-1251058D01*
X-1249818Y74198D01*
G01X-1244858D02*
Y76038D01*
G01X-1260161Y145521D02*
X-1259624Y146245D01*
X-1259164Y146658D01*
X-1258551Y146865D01*
X-1258014Y146658D01*
X-1257631Y146245D01*
X-1257324Y145625D01*
X-1257247Y144901D01*
X-1257324Y144281D01*
X-1257631Y143661D01*
X-1258091Y143145D01*
X-1258627Y142938D01*
X-1259241Y143145D01*
X-1259777Y143764D01*
X-1260084Y144695D01*
X-1260161Y145728D01*
X-1260007Y147071D01*
X-1259777Y147795D01*
X-1259394Y148518D01*
X-1258857Y149035D01*
X-1258321Y149138D01*
X-1257784Y148931D01*
X-1257401Y148415D01*
G01X-1248436Y144405D02*
X-1254636D01*
Y146321D01*
X-1254326Y146935D01*
X-1253913Y147318D01*
X-1253086Y147471D01*
X-1252259Y147318D01*
X-1251743Y146858D01*
X-1251433Y146321D01*
Y144405D01*
G01Y146321D02*
X-1248436Y147471D01*
G01X-1253603Y150681D02*
X-1254223Y151141D01*
X-1254533Y151678D01*
X-1254636Y152291D01*
X-1254429Y153058D01*
X-1253913Y153595D01*
X-1253293Y153748D01*
X-1252673Y153671D01*
X-1252156Y153365D01*
X-1251123Y151831D01*
X-1250399Y151141D01*
X-1249366Y150681D01*
X-1248436Y150528D01*
Y153748D01*
G01Y158338D02*
X-1248539Y158875D01*
X-1248849Y159488D01*
X-1249366Y159871D01*
X-1250089Y160025D01*
X-1250813Y159871D01*
X-1251433Y159411D01*
X-1251743Y158721D01*
Y157955D01*
X-1251949Y157495D01*
X-1252466Y157111D01*
X-1253189Y156958D01*
X-1253913Y157188D01*
X-1254429Y157725D01*
X-1254636Y158338D01*
X-1254429Y158951D01*
X-1253913Y159488D01*
X-1253189Y159718D01*
X-1252466Y159565D01*
X-1251949Y159181D01*
X-1251743Y158721D01*
Y157955D01*
X-1251433Y157265D01*
X-1250813Y156805D01*
X-1250089Y156651D01*
X-1249366Y156805D01*
X-1248849Y157188D01*
X-1248539Y157801D01*
X-1248436Y158338D01*
G01X-1249366Y162851D02*
X-1248849Y163311D01*
X-1248539Y163848D01*
X-1248436Y164538D01*
X-1248643Y165228D01*
X-1249056Y165765D01*
X-1249779Y166148D01*
X-1250606Y166225D01*
X-1251433Y166071D01*
X-1251949Y165688D01*
X-1252363Y165151D01*
X-1252466Y164615D01*
X-1252363Y164078D01*
X-1251949Y163388D01*
X-1254636Y163618D01*
Y165688D01*
G01X-1254137Y182970D02*
Y189170D01*
X-1252221D01*
X-1251607Y188860D01*
X-1251224Y188447D01*
X-1251071Y187620D01*
X-1251224Y186793D01*
X-1251684Y186277D01*
X-1252221Y185967D01*
X-1254137D01*
G01X-1252221D02*
X-1251071Y182970D01*
G01X-1246404D02*
Y189170D01*
X-1247324Y187930D01*
G01Y182970D02*
X-1245484D01*
G01X-1240204D02*
X-1239667Y183073D01*
X-1239054Y183383D01*
X-1238671Y183900D01*
X-1238517Y184623D01*
X-1238671Y185347D01*
X-1239131Y185967D01*
X-1239821Y186277D01*
X-1240587D01*
X-1241047Y186483D01*
X-1241431Y187000D01*
X-1241584Y187723D01*
X-1241354Y188447D01*
X-1240817Y188963D01*
X-1240204Y189170D01*
X-1239591Y188963D01*
X-1239054Y188447D01*
X-1238824Y187723D01*
X-1238977Y187000D01*
X-1239361Y186483D01*
X-1239821Y186277D01*
X-1240587D01*
X-1241277Y185967D01*
X-1241737Y185347D01*
X-1241891Y184623D01*
X-1241737Y183900D01*
X-1241354Y183383D01*
X-1240741Y183073D01*
X-1240204Y182970D01*
G01X-1235461Y185553D02*
X-1234924Y186277D01*
X-1234464Y186690D01*
X-1233851Y186897D01*
X-1233314Y186690D01*
X-1232931Y186277D01*
X-1232624Y185657D01*
X-1232547Y184933D01*
X-1232624Y184313D01*
X-1232931Y183693D01*
X-1233391Y183177D01*
X-1233927Y182970D01*
X-1234541Y183177D01*
X-1235077Y183796D01*
X-1235384Y184727D01*
X-1235461Y185760D01*
X-1235307Y187103D01*
X-1235077Y187827D01*
X-1234694Y188550D01*
X-1234157Y189067D01*
X-1233621Y189170D01*
X-1233084Y188963D01*
X-1232701Y188447D01*
G01X-1254137Y190938D02*
Y197138D01*
X-1252221D01*
X-1251607Y196828D01*
X-1251224Y196415D01*
X-1251071Y195588D01*
X-1251224Y194761D01*
X-1251684Y194245D01*
X-1252221Y193935D01*
X-1254137D01*
G01X-1252221D02*
X-1251071Y190938D01*
G01X-1246404D02*
Y197138D01*
X-1247324Y195898D01*
G01Y190938D02*
X-1245484D01*
G01X-1240204D02*
X-1239667Y191041D01*
X-1239054Y191351D01*
X-1238671Y191868D01*
X-1238517Y192591D01*
X-1238671Y193315D01*
X-1239131Y193935D01*
X-1239821Y194245D01*
X-1240587D01*
X-1241047Y194451D01*
X-1241431Y194968D01*
X-1241584Y195691D01*
X-1241354Y196415D01*
X-1240817Y196931D01*
X-1240204Y197138D01*
X-1239591Y196931D01*
X-1239054Y196415D01*
X-1238824Y195691D01*
X-1238977Y194968D01*
X-1239361Y194451D01*
X-1239821Y194245D01*
X-1240587D01*
X-1241277Y193935D01*
X-1241737Y193315D01*
X-1241891Y192591D01*
X-1241737Y191868D01*
X-1241354Y191351D01*
X-1240741Y191041D01*
X-1240204Y190938D01*
G01X-1235307Y191661D02*
X-1234771Y191145D01*
X-1234157Y190938D01*
X-1233544Y191145D01*
X-1233007Y191764D01*
X-1232624Y192695D01*
X-1232471Y193625D01*
Y194761D01*
X-1232624Y195691D01*
X-1233007Y196518D01*
X-1233467Y196931D01*
X-1234004Y197138D01*
X-1234617Y196931D01*
X-1235077Y196518D01*
X-1235384Y195898D01*
X-1235537Y195071D01*
X-1235384Y194348D01*
X-1235001Y193625D01*
X-1234541Y193211D01*
X-1234004Y193108D01*
X-1233391Y193315D01*
X-1232931Y193831D01*
X-1232471Y194761D01*
G01X-1254137Y200938D02*
Y207138D01*
X-1252221D01*
X-1251607Y206828D01*
X-1251224Y206415D01*
X-1251071Y205588D01*
X-1251224Y204761D01*
X-1251684Y204245D01*
X-1252221Y203935D01*
X-1254137D01*
G01X-1252221D02*
X-1251071Y200938D01*
G01X-1246404D02*
Y207138D01*
X-1247324Y205898D01*
G01Y200938D02*
X-1245484D01*
G01X-1240204D02*
X-1239667Y201041D01*
X-1239054Y201351D01*
X-1238671Y201868D01*
X-1238517Y202591D01*
X-1238671Y203315D01*
X-1239131Y203935D01*
X-1239821Y204245D01*
X-1240587D01*
X-1241047Y204451D01*
X-1241431Y204968D01*
X-1241584Y205691D01*
X-1241354Y206415D01*
X-1240817Y206931D01*
X-1240204Y207138D01*
X-1239591Y206931D01*
X-1239054Y206415D01*
X-1238824Y205691D01*
X-1238977Y204968D01*
X-1239361Y204451D01*
X-1239821Y204245D01*
X-1240587D01*
X-1241277Y203935D01*
X-1241737Y203315D01*
X-1241891Y202591D01*
X-1241737Y201868D01*
X-1241354Y201351D01*
X-1240741Y201041D01*
X-1240204Y200938D01*
G01X-1235691Y201868D02*
X-1235231Y201351D01*
X-1234694Y201041D01*
X-1234004Y200938D01*
X-1233314Y201145D01*
X-1232777Y201558D01*
X-1232394Y202281D01*
X-1232317Y203108D01*
X-1232471Y203935D01*
X-1232854Y204451D01*
X-1233391Y204865D01*
X-1233927Y204968D01*
X-1234464Y204865D01*
X-1235154Y204451D01*
X-1234924Y207138D01*
X-1232854D01*
G01X-1253887Y215425D02*
X-1254197Y214965D01*
X-1254404Y214428D01*
Y213815D01*
X-1254094Y213125D01*
X-1253577Y212588D01*
X-1252957Y212205D01*
X-1251924Y211898D01*
X-1250994Y211821D01*
X-1250064Y211975D01*
X-1249444Y212205D01*
X-1248824Y212665D01*
X-1248411Y213201D01*
X-1248204Y213738D01*
Y214275D01*
X-1248411Y214811D01*
X-1248721Y215271D01*
X-1249134Y215655D01*
G01X-1248204Y219938D02*
X-1254404D01*
X-1253164Y219018D01*
G01X-1248204D02*
Y220858D01*
G01X-1248927Y224835D02*
X-1248411Y225371D01*
X-1248204Y225985D01*
X-1248411Y226598D01*
X-1249030Y227135D01*
X-1249961Y227518D01*
X-1250891Y227671D01*
X-1252027D01*
X-1252957Y227518D01*
X-1253784Y227135D01*
X-1254197Y226675D01*
X-1254404Y226138D01*
X-1254197Y225525D01*
X-1253784Y225065D01*
X-1253164Y224758D01*
X-1252337Y224605D01*
X-1251614Y224758D01*
X-1250891Y225141D01*
X-1250477Y225601D01*
X-1250374Y226138D01*
X-1250581Y226751D01*
X-1251097Y227211D01*
X-1252027Y227671D01*
G01X-1250787Y230881D02*
X-1251511Y231418D01*
X-1251924Y231878D01*
X-1252131Y232491D01*
X-1251924Y233028D01*
X-1251511Y233411D01*
X-1250891Y233718D01*
X-1250167Y233795D01*
X-1249547Y233718D01*
X-1248927Y233411D01*
X-1248411Y232951D01*
X-1248204Y232415D01*
X-1248411Y231801D01*
X-1249030Y231265D01*
X-1249961Y230958D01*
X-1250994Y230881D01*
X-1252337Y231035D01*
X-1253061Y231265D01*
X-1253784Y231648D01*
X-1254301Y232185D01*
X-1254404Y232721D01*
X-1254197Y233258D01*
X-1253681Y233641D01*
G01X-1253887Y239425D02*
X-1254197Y238965D01*
X-1254404Y238428D01*
Y237815D01*
X-1254094Y237125D01*
X-1253577Y236588D01*
X-1252957Y236205D01*
X-1251924Y235898D01*
X-1250994Y235821D01*
X-1250064Y235975D01*
X-1249444Y236205D01*
X-1248824Y236665D01*
X-1248411Y237201D01*
X-1248204Y237738D01*
Y238275D01*
X-1248411Y238811D01*
X-1248721Y239271D01*
X-1249134Y239655D01*
G01X-1248204Y243938D02*
X-1254404D01*
X-1253164Y243018D01*
G01X-1248204D02*
Y244858D01*
G01Y250138D02*
X-1248307Y250675D01*
X-1248617Y251288D01*
X-1249134Y251671D01*
X-1249857Y251825D01*
X-1250581Y251671D01*
X-1251201Y251211D01*
X-1251511Y250521D01*
Y249755D01*
X-1251717Y249295D01*
X-1252234Y248911D01*
X-1252957Y248758D01*
X-1253681Y248988D01*
X-1254197Y249525D01*
X-1254404Y250138D01*
X-1254197Y250751D01*
X-1253681Y251288D01*
X-1252957Y251518D01*
X-1252234Y251365D01*
X-1251717Y250981D01*
X-1251511Y250521D01*
Y249755D01*
X-1251201Y249065D01*
X-1250581Y248605D01*
X-1249857Y248451D01*
X-1249134Y248605D01*
X-1248617Y248988D01*
X-1248307Y249601D01*
X-1248204Y250138D01*
G01Y256338D02*
X-1248307Y256875D01*
X-1248617Y257488D01*
X-1249134Y257871D01*
X-1249857Y258025D01*
X-1250581Y257871D01*
X-1251201Y257411D01*
X-1251511Y256721D01*
Y255955D01*
X-1251717Y255495D01*
X-1252234Y255111D01*
X-1252957Y254958D01*
X-1253681Y255188D01*
X-1254197Y255725D01*
X-1254404Y256338D01*
X-1254197Y256951D01*
X-1253681Y257488D01*
X-1252957Y257718D01*
X-1252234Y257565D01*
X-1251717Y257181D01*
X-1251511Y256721D01*
Y255955D01*
X-1251201Y255265D01*
X-1250581Y254805D01*
X-1249857Y254651D01*
X-1249134Y254805D01*
X-1248617Y255188D01*
X-1248307Y255801D01*
X-1248204Y256338D01*
G01X-1257584Y326438D02*
Y332638D01*
X-1260421Y328195D01*
X-1256587D01*
G01X-1252537Y397938D02*
Y404138D01*
X-1250621D01*
X-1250007Y403828D01*
X-1249624Y403415D01*
X-1249471Y402588D01*
X-1249624Y401761D01*
X-1250084Y401245D01*
X-1250621Y400935D01*
X-1252537D01*
G01X-1250621D02*
X-1249471Y397938D01*
G01X-1243884D02*
Y404138D01*
X-1246721Y399695D01*
X-1242887D01*
G01X-1237684Y397938D02*
Y404138D01*
X-1240521Y399695D01*
X-1236687D01*
G01X-1233707Y398661D02*
X-1233171Y398145D01*
X-1232557Y397938D01*
X-1231944Y398145D01*
X-1231407Y398764D01*
X-1231024Y399695D01*
X-1230871Y400625D01*
Y401761D01*
X-1231024Y402691D01*
X-1231407Y403518D01*
X-1231867Y403931D01*
X-1232404Y404138D01*
X-1233017Y403931D01*
X-1233477Y403518D01*
X-1233784Y402898D01*
X-1233937Y402071D01*
X-1233784Y401348D01*
X-1233401Y400625D01*
X-1232941Y400211D01*
X-1232404Y400108D01*
X-1231791Y400315D01*
X-1231331Y400831D01*
X-1230871Y401761D01*
G01X-1252537Y408938D02*
Y415138D01*
X-1250621D01*
X-1250007Y414828D01*
X-1249624Y414415D01*
X-1249471Y413588D01*
X-1249624Y412761D01*
X-1250084Y412245D01*
X-1250621Y411935D01*
X-1252537D01*
G01X-1250621D02*
X-1249471Y408938D01*
G01X-1243884D02*
Y415138D01*
X-1246721Y410695D01*
X-1242887D01*
G01X-1237684Y408938D02*
Y415138D01*
X-1240521Y410695D01*
X-1236687D01*
G01X-1232404Y408938D02*
X-1231867Y409041D01*
X-1231254Y409351D01*
X-1230871Y409868D01*
X-1230717Y410591D01*
X-1230871Y411315D01*
X-1231331Y411935D01*
X-1232021Y412245D01*
X-1232787D01*
X-1233247Y412451D01*
X-1233631Y412968D01*
X-1233784Y413691D01*
X-1233554Y414415D01*
X-1233017Y414931D01*
X-1232404Y415138D01*
X-1231791Y414931D01*
X-1231254Y414415D01*
X-1231024Y413691D01*
X-1231177Y412968D01*
X-1231561Y412451D01*
X-1232021Y412245D01*
X-1232787D01*
X-1233477Y411935D01*
X-1233937Y411315D01*
X-1234091Y410591D01*
X-1233937Y409868D01*
X-1233554Y409351D01*
X-1232941Y409041D01*
X-1232404Y408938D01*
G01X-1235270Y-214368D02*
Y-208168D01*
X-1236190Y-209408D01*
G01Y-214368D02*
X-1234350D01*
G01X-1228638Y-101379D02*
X-1234838Y-99462D01*
X-1228638Y-97545D01*
G01X-1230808Y-98235D02*
Y-100689D01*
G01X-1223804Y144405D02*
X-1230004D01*
Y146321D01*
X-1229694Y146935D01*
X-1229281Y147318D01*
X-1228454Y147471D01*
X-1227627Y147318D01*
X-1227111Y146858D01*
X-1226801Y146321D01*
Y144405D01*
G01Y146321D02*
X-1223804Y147471D01*
G01Y152138D02*
X-1230004D01*
X-1228764Y151218D01*
G01X-1223804D02*
Y153058D01*
G01Y158185D02*
X-1225147Y158338D01*
X-1226284Y158568D01*
X-1227317Y158875D01*
X-1228454Y159258D01*
X-1230004Y159871D01*
Y156805D01*
G01X-1228971Y163081D02*
X-1229591Y163541D01*
X-1229901Y164078D01*
X-1230004Y164691D01*
X-1229797Y165458D01*
X-1229281Y165995D01*
X-1228661Y166148D01*
X-1228041Y166071D01*
X-1227524Y165765D01*
X-1226491Y164231D01*
X-1225767Y163541D01*
X-1224734Y163081D01*
X-1223804Y162928D01*
Y166148D01*
G01X-1236636Y144405D02*
X-1242836D01*
Y146321D01*
X-1242526Y146935D01*
X-1242113Y147318D01*
X-1241286Y147471D01*
X-1240459Y147318D01*
X-1239943Y146858D01*
X-1239633Y146321D01*
Y144405D01*
G01Y146321D02*
X-1236636Y147471D01*
G01X-1241803Y150681D02*
X-1242423Y151141D01*
X-1242733Y151678D01*
X-1242836Y152291D01*
X-1242629Y153058D01*
X-1242113Y153595D01*
X-1241493Y153748D01*
X-1240873Y153671D01*
X-1240356Y153365D01*
X-1239323Y151831D01*
X-1238599Y151141D01*
X-1237566Y150681D01*
X-1236636Y150528D01*
Y153748D01*
G01Y158338D02*
X-1236739Y158875D01*
X-1237049Y159488D01*
X-1237566Y159871D01*
X-1238289Y160025D01*
X-1239013Y159871D01*
X-1239633Y159411D01*
X-1239943Y158721D01*
Y157955D01*
X-1240149Y157495D01*
X-1240666Y157111D01*
X-1241389Y156958D01*
X-1242113Y157188D01*
X-1242629Y157725D01*
X-1242836Y158338D01*
X-1242629Y158951D01*
X-1242113Y159488D01*
X-1241389Y159718D01*
X-1240666Y159565D01*
X-1240149Y159181D01*
X-1239943Y158721D01*
Y157955D01*
X-1239633Y157265D01*
X-1239013Y156805D01*
X-1238289Y156651D01*
X-1237566Y156805D01*
X-1237049Y157188D01*
X-1236739Y157801D01*
X-1236636Y158338D01*
G01X-1237876Y162851D02*
X-1237153Y163311D01*
X-1236739Y163925D01*
X-1236636Y164615D01*
X-1236739Y165228D01*
X-1237256Y165841D01*
X-1237876Y166225D01*
X-1238496Y166301D01*
X-1239219Y166148D01*
X-1239736Y165611D01*
X-1239943Y165075D01*
Y164385D01*
G01Y165075D02*
X-1240253Y165535D01*
X-1240769Y165918D01*
X-1241389Y166071D01*
X-1242009Y165918D01*
X-1242526Y165535D01*
X-1242836Y164845D01*
X-1242733Y164155D01*
X-1242319Y163465D01*
G01X-1227137Y182938D02*
Y189138D01*
X-1225221D01*
X-1224607Y188828D01*
X-1224224Y188415D01*
X-1224071Y187588D01*
X-1224224Y186761D01*
X-1224684Y186245D01*
X-1225221Y185935D01*
X-1227137D01*
G01X-1225221D02*
X-1224071Y182938D01*
G01X-1219404D02*
Y189138D01*
X-1220324Y187898D01*
G01Y182938D02*
X-1218484D01*
G01X-1213357D02*
X-1213204Y184281D01*
X-1212974Y185418D01*
X-1212667Y186451D01*
X-1212284Y187588D01*
X-1211671Y189138D01*
X-1214737D01*
G01X-1207004Y182938D02*
X-1206467Y183041D01*
X-1205854Y183351D01*
X-1205471Y183868D01*
X-1205317Y184591D01*
X-1205471Y185315D01*
X-1205931Y185935D01*
X-1206621Y186245D01*
X-1207387D01*
X-1207847Y186451D01*
X-1208231Y186968D01*
X-1208384Y187691D01*
X-1208154Y188415D01*
X-1207617Y188931D01*
X-1207004Y189138D01*
X-1206391Y188931D01*
X-1205854Y188415D01*
X-1205624Y187691D01*
X-1205777Y186968D01*
X-1206161Y186451D01*
X-1206621Y186245D01*
X-1207387D01*
X-1208077Y185935D01*
X-1208537Y185315D01*
X-1208691Y184591D01*
X-1208537Y183868D01*
X-1208154Y183351D01*
X-1207541Y183041D01*
X-1207004Y182938D01*
G01X-1227137Y191938D02*
Y198138D01*
X-1225221D01*
X-1224607Y197828D01*
X-1224224Y197415D01*
X-1224071Y196588D01*
X-1224224Y195761D01*
X-1224684Y195245D01*
X-1225221Y194935D01*
X-1227137D01*
G01X-1225221D02*
X-1224071Y191938D01*
G01X-1219404D02*
Y198138D01*
X-1220324Y196898D01*
G01Y191938D02*
X-1218484D01*
G01X-1213204D02*
X-1212667Y192041D01*
X-1212054Y192351D01*
X-1211671Y192868D01*
X-1211517Y193591D01*
X-1211671Y194315D01*
X-1212131Y194935D01*
X-1212821Y195245D01*
X-1213587D01*
X-1214047Y195451D01*
X-1214431Y195968D01*
X-1214584Y196691D01*
X-1214354Y197415D01*
X-1213817Y197931D01*
X-1213204Y198138D01*
X-1212591Y197931D01*
X-1212054Y197415D01*
X-1211824Y196691D01*
X-1211977Y195968D01*
X-1212361Y195451D01*
X-1212821Y195245D01*
X-1213587D01*
X-1214277Y194935D01*
X-1214737Y194315D01*
X-1214891Y193591D01*
X-1214737Y192868D01*
X-1214354Y192351D01*
X-1213741Y192041D01*
X-1213204Y191938D01*
G01X-1207004D02*
Y198138D01*
X-1207924Y196898D01*
G01Y191938D02*
X-1206084D01*
G01X-1231404Y230151D02*
X-1226961D01*
X-1226030Y230458D01*
X-1225411Y231071D01*
X-1225204Y231838D01*
X-1225411Y232605D01*
X-1226030Y233218D01*
X-1226961Y233525D01*
X-1231404D01*
G01X-1230371Y236581D02*
X-1230991Y237041D01*
X-1231301Y237578D01*
X-1231404Y238191D01*
X-1231197Y238958D01*
X-1230681Y239495D01*
X-1230061Y239648D01*
X-1229441Y239571D01*
X-1228924Y239265D01*
X-1227891Y237731D01*
X-1227167Y237041D01*
X-1226134Y236581D01*
X-1225204Y236428D01*
Y239648D01*
G01X-1231404Y244238D02*
X-1231197Y243625D01*
X-1230681Y243165D01*
X-1230061Y242858D01*
X-1229234Y242628D01*
X-1228304Y242551D01*
X-1227374Y242628D01*
X-1226547Y242858D01*
X-1225927Y243165D01*
X-1225411Y243625D01*
X-1225204Y244238D01*
X-1225411Y244851D01*
X-1225927Y245311D01*
X-1226547Y245618D01*
X-1227374Y245848D01*
X-1228304Y245925D01*
X-1229234Y245848D01*
X-1230061Y245618D01*
X-1230681Y245311D01*
X-1231197Y244851D01*
X-1231404Y244238D01*
G01X-1241804Y254038D02*
Y260238D01*
X-1242724Y258998D01*
G01Y254038D02*
X-1240884D01*
G01X-1235604Y260238D02*
X-1236217Y260031D01*
X-1236677Y259515D01*
X-1236984Y258895D01*
X-1237214Y258068D01*
X-1237291Y257138D01*
X-1237214Y256208D01*
X-1236984Y255381D01*
X-1236677Y254761D01*
X-1236217Y254245D01*
X-1235604Y254038D01*
X-1234991Y254245D01*
X-1234531Y254761D01*
X-1234224Y255381D01*
X-1233994Y256208D01*
X-1233917Y257138D01*
X-1233994Y258068D01*
X-1234224Y258895D01*
X-1234531Y259515D01*
X-1234991Y260031D01*
X-1235604Y260238D01*
G01X-1237317Y270721D02*
X-1237777Y271031D01*
X-1238314Y271238D01*
X-1238927D01*
X-1239617Y270928D01*
X-1240154Y270411D01*
X-1240537Y269791D01*
X-1240844Y268758D01*
X-1240921Y267828D01*
X-1240767Y266898D01*
X-1240537Y266278D01*
X-1240077Y265658D01*
X-1239541Y265245D01*
X-1239004Y265038D01*
X-1238467D01*
X-1237931Y265245D01*
X-1237471Y265555D01*
X-1237087Y265968D01*
G01X-1232804Y265038D02*
Y271238D01*
X-1233724Y269998D01*
G01Y265038D02*
X-1231884D01*
G01X-1226604D02*
X-1226067Y265141D01*
X-1225454Y265451D01*
X-1225071Y265968D01*
X-1224917Y266691D01*
X-1225071Y267415D01*
X-1225531Y268035D01*
X-1226221Y268345D01*
X-1226987D01*
X-1227447Y268551D01*
X-1227831Y269068D01*
X-1227984Y269791D01*
X-1227754Y270515D01*
X-1227217Y271031D01*
X-1226604Y271238D01*
X-1225991Y271031D01*
X-1225454Y270515D01*
X-1225224Y269791D01*
X-1225377Y269068D01*
X-1225761Y268551D01*
X-1226221Y268345D01*
X-1226987D01*
X-1227677Y268035D01*
X-1228137Y267415D01*
X-1228291Y266691D01*
X-1228137Y265968D01*
X-1227754Y265451D01*
X-1227141Y265141D01*
X-1226604Y265038D01*
G01X-1219484D02*
Y271238D01*
X-1222321Y266795D01*
X-1218487D01*
G01X-1234636Y327205D02*
X-1240836D01*
Y329121D01*
X-1240526Y329735D01*
X-1240113Y330118D01*
X-1239286Y330271D01*
X-1238459Y330118D01*
X-1237943Y329658D01*
X-1237633Y329121D01*
Y327205D01*
G01Y329121D02*
X-1234636Y330271D01*
G01Y335858D02*
X-1240836D01*
X-1236393Y333021D01*
Y336855D01*
G01X-1237219Y339681D02*
X-1237943Y340218D01*
X-1238356Y340678D01*
X-1238563Y341291D01*
X-1238356Y341828D01*
X-1237943Y342211D01*
X-1237323Y342518D01*
X-1236599Y342595D01*
X-1235979Y342518D01*
X-1235359Y342211D01*
X-1234843Y341751D01*
X-1234636Y341215D01*
X-1234843Y340601D01*
X-1235462Y340065D01*
X-1236393Y339758D01*
X-1237426Y339681D01*
X-1238769Y339835D01*
X-1239493Y340065D01*
X-1240216Y340448D01*
X-1240733Y340985D01*
X-1240836Y341521D01*
X-1240629Y342058D01*
X-1240113Y342441D01*
G01X-1234636Y348258D02*
X-1240836D01*
X-1236393Y345421D01*
Y349255D01*
G01X-1211604Y-189062D02*
X-1214394D01*
X-1217804Y-190595D01*
G01Y-187529D02*
X-1214394Y-189062D01*
G01X-1211604Y-181942D02*
X-1217804D01*
X-1213361Y-184779D01*
Y-180945D01*
G01X-1222537Y-161962D02*
Y-155762D01*
X-1220621D01*
X-1220007Y-156072D01*
X-1219624Y-156485D01*
X-1219471Y-157312D01*
X-1219624Y-158139D01*
X-1220084Y-158655D01*
X-1220621Y-158965D01*
X-1222537D01*
G01X-1220621D02*
X-1219471Y-161962D01*
G01X-1216261Y-156795D02*
X-1215801Y-156175D01*
X-1215264Y-155865D01*
X-1214651Y-155762D01*
X-1213884Y-155969D01*
X-1213347Y-156485D01*
X-1213194Y-157105D01*
X-1213271Y-157725D01*
X-1213577Y-158242D01*
X-1215111Y-159275D01*
X-1215801Y-159999D01*
X-1216261Y-161032D01*
X-1216414Y-161962D01*
X-1213194D01*
G01X-1207684D02*
Y-155762D01*
X-1210521Y-160205D01*
X-1206687D01*
G01X-1202404Y-155762D02*
X-1203017Y-155969D01*
X-1203477Y-156485D01*
X-1203784Y-157105D01*
X-1204014Y-157932D01*
X-1204091Y-158862D01*
X-1204014Y-159792D01*
X-1203784Y-160619D01*
X-1203477Y-161239D01*
X-1203017Y-161755D01*
X-1202404Y-161962D01*
X-1201791Y-161755D01*
X-1201331Y-161239D01*
X-1201024Y-160619D01*
X-1200794Y-159792D01*
X-1200717Y-158862D01*
X-1200794Y-157932D01*
X-1201024Y-157105D01*
X-1201331Y-156485D01*
X-1201791Y-155969D01*
X-1202404Y-155762D01*
G01X-1211287Y-149575D02*
X-1211597Y-150035D01*
X-1211804Y-150572D01*
Y-151185D01*
X-1211494Y-151875D01*
X-1210977Y-152412D01*
X-1210357Y-152795D01*
X-1209324Y-153102D01*
X-1208394Y-153179D01*
X-1207464Y-153025D01*
X-1206844Y-152795D01*
X-1206224Y-152335D01*
X-1205811Y-151799D01*
X-1205604Y-151262D01*
Y-150725D01*
X-1205811Y-150189D01*
X-1206121Y-149729D01*
X-1206534Y-149345D01*
G01X-1210771Y-146519D02*
X-1211391Y-146059D01*
X-1211701Y-145522D01*
X-1211804Y-144909D01*
X-1211597Y-144142D01*
X-1211081Y-143605D01*
X-1210461Y-143452D01*
X-1209841Y-143529D01*
X-1209324Y-143835D01*
X-1208291Y-145369D01*
X-1207567Y-146059D01*
X-1206534Y-146519D01*
X-1205604Y-146672D01*
Y-143452D01*
G01X-1206534Y-140549D02*
X-1206017Y-140089D01*
X-1205707Y-139552D01*
X-1205604Y-138862D01*
X-1205811Y-138172D01*
X-1206224Y-137635D01*
X-1206947Y-137252D01*
X-1207774Y-137175D01*
X-1208601Y-137329D01*
X-1209117Y-137712D01*
X-1209531Y-138249D01*
X-1209634Y-138785D01*
X-1209531Y-139322D01*
X-1209117Y-140012D01*
X-1211804Y-139782D01*
Y-137712D01*
G01X-1205604Y-131742D02*
X-1211804D01*
X-1207361Y-134579D01*
Y-130745D01*
G01X-1223945Y-104849D02*
X-1224255Y-104542D01*
X-1224771Y-104312D01*
X-1225495Y-104159D01*
X-1226115Y-104312D01*
X-1226528Y-104619D01*
X-1226838Y-105155D01*
Y-107225D01*
X-1220638D01*
Y-104695D01*
X-1221051Y-104159D01*
X-1221671Y-103852D01*
X-1222395Y-103699D01*
X-1223118Y-103852D01*
X-1223738Y-104312D01*
X-1223945Y-104849D01*
Y-107225D01*
G01X-1216321Y-97775D02*
X-1216631Y-98235D01*
X-1216838Y-98772D01*
Y-99385D01*
X-1216528Y-100075D01*
X-1216011Y-100612D01*
X-1215391Y-100995D01*
X-1214358Y-101302D01*
X-1213428Y-101379D01*
X-1212498Y-101225D01*
X-1211878Y-100995D01*
X-1211258Y-100535D01*
X-1210845Y-99999D01*
X-1210638Y-99462D01*
Y-98925D01*
X-1210845Y-98389D01*
X-1211155Y-97929D01*
X-1211568Y-97545D01*
G01X-1214068Y144405D02*
X-1220268D01*
Y146321D01*
X-1219958Y146935D01*
X-1219545Y147318D01*
X-1218718Y147471D01*
X-1217891Y147318D01*
X-1217375Y146858D01*
X-1217065Y146321D01*
Y144405D01*
G01Y146321D02*
X-1214068Y147471D01*
G01Y152138D02*
X-1220268D01*
X-1219028Y151218D01*
G01X-1214068D02*
Y153058D01*
G01Y158185D02*
X-1215411Y158338D01*
X-1216548Y158568D01*
X-1217581Y158875D01*
X-1218718Y159258D01*
X-1220268Y159871D01*
Y156805D01*
G01Y164538D02*
X-1220061Y163925D01*
X-1219545Y163465D01*
X-1218925Y163158D01*
X-1218098Y162928D01*
X-1217168Y162851D01*
X-1216238Y162928D01*
X-1215411Y163158D01*
X-1214791Y163465D01*
X-1214275Y163925D01*
X-1214068Y164538D01*
X-1214275Y165151D01*
X-1214791Y165611D01*
X-1215411Y165918D01*
X-1216238Y166148D01*
X-1217168Y166225D01*
X-1218098Y166148D01*
X-1218925Y165918D01*
X-1219545Y165611D01*
X-1220061Y165151D01*
X-1220268Y164538D01*
G01X-1222917Y207421D02*
X-1223377Y207731D01*
X-1223914Y207938D01*
X-1224527D01*
X-1225217Y207628D01*
X-1225754Y207111D01*
X-1226137Y206491D01*
X-1226444Y205458D01*
X-1226521Y204528D01*
X-1226367Y203598D01*
X-1226137Y202978D01*
X-1225677Y202358D01*
X-1225141Y201945D01*
X-1224604Y201738D01*
X-1224067D01*
X-1223531Y201945D01*
X-1223071Y202255D01*
X-1222687Y202668D01*
G01X-1218404Y201738D02*
Y207938D01*
X-1219324Y206698D01*
G01Y201738D02*
X-1217484D01*
G01X-1213507Y202461D02*
X-1212971Y201945D01*
X-1212357Y201738D01*
X-1211744Y201945D01*
X-1211207Y202564D01*
X-1210824Y203495D01*
X-1210671Y204425D01*
Y205561D01*
X-1210824Y206491D01*
X-1211207Y207318D01*
X-1211667Y207731D01*
X-1212204Y207938D01*
X-1212817Y207731D01*
X-1213277Y207318D01*
X-1213584Y206698D01*
X-1213737Y205871D01*
X-1213584Y205148D01*
X-1213201Y204425D01*
X-1212741Y204011D01*
X-1212204Y203908D01*
X-1211591Y204115D01*
X-1211131Y204631D01*
X-1210671Y205561D01*
G01X-1207461Y206905D02*
X-1207001Y207525D01*
X-1206464Y207835D01*
X-1205851Y207938D01*
X-1205084Y207731D01*
X-1204547Y207215D01*
X-1204394Y206595D01*
X-1204471Y205975D01*
X-1204777Y205458D01*
X-1206311Y204425D01*
X-1207001Y203701D01*
X-1207461Y202668D01*
X-1207614Y201738D01*
X-1204394D01*
G01X-1214391Y222968D02*
X-1213931Y222451D01*
X-1213394Y222141D01*
X-1212704Y222038D01*
X-1212014Y222245D01*
X-1211477Y222658D01*
X-1211094Y223381D01*
X-1211017Y224208D01*
X-1211171Y225035D01*
X-1211554Y225551D01*
X-1212091Y225965D01*
X-1212627Y226068D01*
X-1213164Y225965D01*
X-1213854Y225551D01*
X-1213624Y228238D01*
X-1211554D01*
G01X-1223161Y256621D02*
X-1222624Y257345D01*
X-1222164Y257758D01*
X-1221551Y257965D01*
X-1221014Y257758D01*
X-1220631Y257345D01*
X-1220324Y256725D01*
X-1220247Y256001D01*
X-1220324Y255381D01*
X-1220631Y254761D01*
X-1221091Y254245D01*
X-1221627Y254038D01*
X-1222241Y254245D01*
X-1222777Y254864D01*
X-1223084Y255795D01*
X-1223161Y256828D01*
X-1223007Y258171D01*
X-1222777Y258895D01*
X-1222394Y259618D01*
X-1221857Y260135D01*
X-1221321Y260238D01*
X-1220784Y260031D01*
X-1220401Y259515D01*
G01X-1216887Y259425D02*
X-1217197Y258965D01*
X-1217404Y258428D01*
Y257815D01*
X-1217094Y257125D01*
X-1216577Y256588D01*
X-1215957Y256205D01*
X-1214924Y255898D01*
X-1213994Y255821D01*
X-1213064Y255975D01*
X-1212444Y256205D01*
X-1211824Y256665D01*
X-1211411Y257201D01*
X-1211204Y257738D01*
Y258275D01*
X-1211411Y258811D01*
X-1211721Y259271D01*
X-1212134Y259655D01*
G01X-1211204Y263938D02*
X-1217404D01*
X-1216164Y263018D01*
G01X-1211204D02*
Y264858D01*
G01X-1211927Y268835D02*
X-1211411Y269371D01*
X-1211204Y269985D01*
X-1211411Y270598D01*
X-1212030Y271135D01*
X-1212961Y271518D01*
X-1213891Y271671D01*
X-1215027D01*
X-1215957Y271518D01*
X-1216784Y271135D01*
X-1217197Y270675D01*
X-1217404Y270138D01*
X-1217197Y269525D01*
X-1216784Y269065D01*
X-1216164Y268758D01*
X-1215337Y268605D01*
X-1214614Y268758D01*
X-1213891Y269141D01*
X-1213477Y269601D01*
X-1213374Y270138D01*
X-1213581Y270751D01*
X-1214097Y271211D01*
X-1215027Y271671D01*
G01X-1217404Y276338D02*
X-1217197Y275725D01*
X-1216681Y275265D01*
X-1216061Y274958D01*
X-1215234Y274728D01*
X-1214304Y274651D01*
X-1213374Y274728D01*
X-1212547Y274958D01*
X-1211927Y275265D01*
X-1211411Y275725D01*
X-1211204Y276338D01*
X-1211411Y276951D01*
X-1211927Y277411D01*
X-1212547Y277718D01*
X-1213374Y277948D01*
X-1214304Y278025D01*
X-1215234Y277948D01*
X-1216061Y277718D01*
X-1216681Y277411D01*
X-1217197Y276951D01*
X-1217404Y276338D01*
G01X-1222737Y294770D02*
Y300970D01*
X-1220821D01*
X-1220207Y300660D01*
X-1219824Y300247D01*
X-1219671Y299420D01*
X-1219824Y298593D01*
X-1220284Y298077D01*
X-1220821Y297767D01*
X-1222737D01*
G01X-1220821D02*
X-1219671Y294770D01*
G01X-1214084D02*
Y300970D01*
X-1216921Y296527D01*
X-1213087D01*
G01X-1210261Y297353D02*
X-1209724Y298077D01*
X-1209264Y298490D01*
X-1208651Y298697D01*
X-1208114Y298490D01*
X-1207731Y298077D01*
X-1207424Y297457D01*
X-1207347Y296733D01*
X-1207424Y296113D01*
X-1207731Y295493D01*
X-1208191Y294977D01*
X-1208727Y294770D01*
X-1209341Y294977D01*
X-1209877Y295596D01*
X-1210184Y296527D01*
X-1210261Y297560D01*
X-1210107Y298903D01*
X-1209877Y299627D01*
X-1209494Y300350D01*
X-1208957Y300867D01*
X-1208421Y300970D01*
X-1207884Y300763D01*
X-1207501Y300247D01*
G01X-1204061Y299937D02*
X-1203601Y300557D01*
X-1203064Y300867D01*
X-1202451Y300970D01*
X-1201684Y300763D01*
X-1201147Y300247D01*
X-1200994Y299627D01*
X-1201071Y299007D01*
X-1201377Y298490D01*
X-1202911Y297457D01*
X-1203601Y296733D01*
X-1204061Y295700D01*
X-1204214Y294770D01*
X-1200994D01*
G01X-1222737Y305170D02*
Y311370D01*
X-1220821D01*
X-1220207Y311060D01*
X-1219824Y310647D01*
X-1219671Y309820D01*
X-1219824Y308993D01*
X-1220284Y308477D01*
X-1220821Y308167D01*
X-1222737D01*
G01X-1220821D02*
X-1219671Y305170D01*
G01X-1214084D02*
Y311370D01*
X-1216921Y306927D01*
X-1213087D01*
G01X-1210261Y307753D02*
X-1209724Y308477D01*
X-1209264Y308890D01*
X-1208651Y309097D01*
X-1208114Y308890D01*
X-1207731Y308477D01*
X-1207424Y307857D01*
X-1207347Y307133D01*
X-1207424Y306513D01*
X-1207731Y305893D01*
X-1208191Y305377D01*
X-1208727Y305170D01*
X-1209341Y305377D01*
X-1209877Y305996D01*
X-1210184Y306927D01*
X-1210261Y307960D01*
X-1210107Y309303D01*
X-1209877Y310027D01*
X-1209494Y310750D01*
X-1208957Y311267D01*
X-1208421Y311370D01*
X-1207884Y311163D01*
X-1207501Y310647D01*
G01X-1202604Y305170D02*
Y311370D01*
X-1203524Y310130D01*
G01Y305170D02*
X-1201684D01*
G01X-1219192Y322534D02*
X-1225392D01*
X-1220949Y319697D01*
Y323531D01*
G01X-1208735Y320661D02*
X-1209459Y321198D01*
X-1209872Y321658D01*
X-1210079Y322271D01*
X-1209872Y322808D01*
X-1209459Y323191D01*
X-1208839Y323498D01*
X-1208115Y323575D01*
X-1207495Y323498D01*
X-1206875Y323191D01*
X-1206359Y322731D01*
X-1206152Y322195D01*
X-1206359Y321581D01*
X-1206978Y321045D01*
X-1207909Y320738D01*
X-1208942Y320661D01*
X-1210285Y320815D01*
X-1211009Y321045D01*
X-1211732Y321428D01*
X-1212249Y321965D01*
X-1212352Y322501D01*
X-1212145Y323038D01*
X-1211629Y323421D01*
G01X-1216768Y329751D02*
X-1212325D01*
X-1211394Y330058D01*
X-1210775Y330671D01*
X-1210568Y331438D01*
X-1210775Y332205D01*
X-1211394Y332818D01*
X-1212325Y333125D01*
X-1216768D01*
G01X-1211808Y335951D02*
X-1211085Y336411D01*
X-1210671Y337025D01*
X-1210568Y337715D01*
X-1210671Y338328D01*
X-1211188Y338941D01*
X-1211808Y339325D01*
X-1212428Y339401D01*
X-1213151Y339248D01*
X-1213668Y338711D01*
X-1213875Y338175D01*
Y337485D01*
G01Y338175D02*
X-1214185Y338635D01*
X-1214701Y339018D01*
X-1215321Y339171D01*
X-1215941Y339018D01*
X-1216458Y338635D01*
X-1216768Y337945D01*
X-1216665Y337255D01*
X-1216251Y336565D01*
G01X-1211291Y342535D02*
X-1210775Y343071D01*
X-1210568Y343685D01*
X-1210775Y344298D01*
X-1211394Y344835D01*
X-1212325Y345218D01*
X-1213255Y345371D01*
X-1214391D01*
X-1215321Y345218D01*
X-1216148Y344835D01*
X-1216561Y344375D01*
X-1216768Y343838D01*
X-1216561Y343225D01*
X-1216148Y342765D01*
X-1215528Y342458D01*
X-1214701Y342305D01*
X-1213978Y342458D01*
X-1213255Y342841D01*
X-1212841Y343301D01*
X-1212738Y343838D01*
X-1212945Y344451D01*
X-1213461Y344911D01*
X-1214391Y345371D01*
G01X-1220344Y351665D02*
X-1219621Y352125D01*
X-1219207Y352739D01*
X-1219104Y353429D01*
X-1219207Y354042D01*
X-1219724Y354655D01*
X-1220344Y355039D01*
X-1220964Y355115D01*
X-1221687Y354962D01*
X-1222204Y354425D01*
X-1222411Y353889D01*
Y353199D01*
G01Y353889D02*
X-1222721Y354349D01*
X-1223237Y354732D01*
X-1223857Y354885D01*
X-1224477Y354732D01*
X-1224994Y354349D01*
X-1225304Y353659D01*
X-1225201Y352969D01*
X-1224787Y352279D01*
G01X-1215704Y364038D02*
X-1215167Y364141D01*
X-1214554Y364451D01*
X-1214171Y364968D01*
X-1214017Y365691D01*
X-1214171Y366415D01*
X-1214631Y367035D01*
X-1215321Y367345D01*
X-1216087D01*
X-1216547Y367551D01*
X-1216931Y368068D01*
X-1217084Y368791D01*
X-1216854Y369515D01*
X-1216317Y370031D01*
X-1215704Y370238D01*
X-1215091Y370031D01*
X-1214554Y369515D01*
X-1214324Y368791D01*
X-1214477Y368068D01*
X-1214861Y367551D01*
X-1215321Y367345D01*
X-1216087D01*
X-1216777Y367035D01*
X-1217237Y366415D01*
X-1217391Y365691D01*
X-1217237Y364968D01*
X-1216854Y364451D01*
X-1216241Y364141D01*
X-1215704Y364038D01*
G01X-1225004Y416138D02*
Y409938D01*
G01X-1226767Y416138D02*
X-1223241D01*
G01X-1220337Y409938D02*
Y416138D01*
X-1218497D01*
X-1217884Y415828D01*
X-1217424Y415105D01*
X-1217271Y414278D01*
X-1217424Y413451D01*
X-1217807Y412831D01*
X-1218497Y412521D01*
X-1220337D01*
G01X-1212604Y409938D02*
Y416138D01*
X-1213524Y414898D01*
G01Y409938D02*
X-1211684D01*
G01X-1205484D02*
Y416138D01*
X-1208321Y411695D01*
X-1204487D01*
G01X-1219581Y439657D02*
X-1219121Y440277D01*
X-1218584Y440587D01*
X-1217971Y440690D01*
X-1217204Y440483D01*
X-1216667Y439967D01*
X-1216514Y439347D01*
X-1216591Y438727D01*
X-1216897Y438210D01*
X-1218431Y437177D01*
X-1219121Y436453D01*
X-1219581Y435420D01*
X-1219734Y434490D01*
X-1216514D01*
G01X-1211924D02*
Y440690D01*
X-1212844Y439450D01*
G01Y434490D02*
X-1211004D01*
G01X-1218124Y458114D02*
Y464314D01*
X-1219044Y463074D01*
G01Y458114D02*
X-1217204D01*
G01X-1213611Y459044D02*
X-1213151Y458527D01*
X-1212614Y458217D01*
X-1211924Y458114D01*
X-1211234Y458321D01*
X-1210697Y458734D01*
X-1210314Y459457D01*
X-1210237Y460284D01*
X-1210391Y461111D01*
X-1210774Y461627D01*
X-1211311Y462041D01*
X-1211847Y462144D01*
X-1212384Y462041D01*
X-1213074Y461627D01*
X-1212844Y464314D01*
X-1210774D01*
G01X-1196291Y-213944D02*
X-1195831Y-214667D01*
X-1195217Y-215081D01*
X-1194527Y-215184D01*
X-1193914Y-215081D01*
X-1193301Y-214564D01*
X-1192917Y-213944D01*
X-1192841Y-213324D01*
X-1192994Y-212601D01*
X-1193531Y-212084D01*
X-1194067Y-211877D01*
X-1194757D01*
G01X-1194067D02*
X-1193607Y-211567D01*
X-1193224Y-211051D01*
X-1193071Y-210431D01*
X-1193224Y-209811D01*
X-1193607Y-209294D01*
X-1194297Y-208984D01*
X-1194987Y-209087D01*
X-1195677Y-209501D01*
G01X-1198537Y-161962D02*
Y-155762D01*
X-1196621D01*
X-1196007Y-156072D01*
X-1195624Y-156485D01*
X-1195471Y-157312D01*
X-1195624Y-158139D01*
X-1196084Y-158655D01*
X-1196621Y-158965D01*
X-1198537D01*
G01X-1196621D02*
X-1195471Y-161962D01*
G01X-1192261Y-156795D02*
X-1191801Y-156175D01*
X-1191264Y-155865D01*
X-1190651Y-155762D01*
X-1189884Y-155969D01*
X-1189347Y-156485D01*
X-1189194Y-157105D01*
X-1189271Y-157725D01*
X-1189577Y-158242D01*
X-1191111Y-159275D01*
X-1191801Y-159999D01*
X-1192261Y-161032D01*
X-1192414Y-161962D01*
X-1189194D01*
G01X-1183684D02*
Y-155762D01*
X-1186521Y-160205D01*
X-1182687D01*
G01X-1179861Y-156795D02*
X-1179401Y-156175D01*
X-1178864Y-155865D01*
X-1178251Y-155762D01*
X-1177484Y-155969D01*
X-1176947Y-156485D01*
X-1176794Y-157105D01*
X-1176871Y-157725D01*
X-1177177Y-158242D01*
X-1178711Y-159275D01*
X-1179401Y-159999D01*
X-1179861Y-161032D01*
X-1180014Y-161962D01*
X-1176794D01*
G01X-1202287Y-149575D02*
X-1202597Y-150035D01*
X-1202804Y-150572D01*
Y-151185D01*
X-1202494Y-151875D01*
X-1201977Y-152412D01*
X-1201357Y-152795D01*
X-1200324Y-153102D01*
X-1199394Y-153179D01*
X-1198464Y-153025D01*
X-1197844Y-152795D01*
X-1197224Y-152335D01*
X-1196811Y-151799D01*
X-1196604Y-151262D01*
Y-150725D01*
X-1196811Y-150189D01*
X-1197121Y-149729D01*
X-1197534Y-149345D01*
G01X-1201771Y-146519D02*
X-1202391Y-146059D01*
X-1202701Y-145522D01*
X-1202804Y-144909D01*
X-1202597Y-144142D01*
X-1202081Y-143605D01*
X-1201461Y-143452D01*
X-1200841Y-143529D01*
X-1200324Y-143835D01*
X-1199291Y-145369D01*
X-1198567Y-146059D01*
X-1197534Y-146519D01*
X-1196604Y-146672D01*
Y-143452D01*
G01X-1197534Y-140549D02*
X-1197017Y-140089D01*
X-1196707Y-139552D01*
X-1196604Y-138862D01*
X-1196811Y-138172D01*
X-1197224Y-137635D01*
X-1197947Y-137252D01*
X-1198774Y-137175D01*
X-1199601Y-137329D01*
X-1200117Y-137712D01*
X-1200531Y-138249D01*
X-1200634Y-138785D01*
X-1200531Y-139322D01*
X-1200117Y-140012D01*
X-1202804Y-139782D01*
Y-137712D01*
G01X-1197844Y-134349D02*
X-1197121Y-133889D01*
X-1196707Y-133275D01*
X-1196604Y-132585D01*
X-1196707Y-131972D01*
X-1197224Y-131359D01*
X-1197844Y-130975D01*
X-1198464Y-130899D01*
X-1199187Y-131052D01*
X-1199704Y-131589D01*
X-1199911Y-132125D01*
Y-132815D01*
G01Y-132125D02*
X-1200221Y-131665D01*
X-1200737Y-131282D01*
X-1201357Y-131129D01*
X-1201977Y-131282D01*
X-1202494Y-131665D01*
X-1202804Y-132355D01*
X-1202701Y-133045D01*
X-1202287Y-133735D01*
G01X-1191638Y-97929D02*
Y-100995D01*
X-1197838D01*
Y-97929D01*
G01X-1194841Y-99155D02*
Y-100995D01*
G01X-1200638Y-107149D02*
X-1206838D01*
Y-105615D01*
X-1206528Y-105002D01*
X-1206115Y-104542D01*
X-1205495Y-104159D01*
X-1204771Y-103852D01*
X-1203738Y-103775D01*
X-1202705Y-103852D01*
X-1201981Y-104159D01*
X-1201361Y-104542D01*
X-1200948Y-105002D01*
X-1200638Y-105615D01*
Y-107149D01*
G01X-1202268Y144405D02*
X-1208468D01*
Y146321D01*
X-1208158Y146935D01*
X-1207745Y147318D01*
X-1206918Y147471D01*
X-1206091Y147318D01*
X-1205575Y146858D01*
X-1205265Y146321D01*
Y144405D01*
G01Y146321D02*
X-1202268Y147471D01*
G01X-1207435Y150681D02*
X-1208055Y151141D01*
X-1208365Y151678D01*
X-1208468Y152291D01*
X-1208261Y153058D01*
X-1207745Y153595D01*
X-1207125Y153748D01*
X-1206505Y153671D01*
X-1205988Y153365D01*
X-1204955Y151831D01*
X-1204231Y151141D01*
X-1203198Y150681D01*
X-1202268Y150528D01*
Y153748D01*
G01X-1202991Y157035D02*
X-1202475Y157571D01*
X-1202268Y158185D01*
X-1202475Y158798D01*
X-1203094Y159335D01*
X-1204025Y159718D01*
X-1204955Y159871D01*
X-1206091D01*
X-1207021Y159718D01*
X-1207848Y159335D01*
X-1208261Y158875D01*
X-1208468Y158338D01*
X-1208261Y157725D01*
X-1207848Y157265D01*
X-1207228Y156958D01*
X-1206401Y156805D01*
X-1205678Y156958D01*
X-1204955Y157341D01*
X-1204541Y157801D01*
X-1204438Y158338D01*
X-1204645Y158951D01*
X-1205161Y159411D01*
X-1206091Y159871D01*
G01X-1207435Y163081D02*
X-1208055Y163541D01*
X-1208365Y164078D01*
X-1208468Y164691D01*
X-1208261Y165458D01*
X-1207745Y165995D01*
X-1207125Y166148D01*
X-1206505Y166071D01*
X-1205988Y165765D01*
X-1204955Y164231D01*
X-1204231Y163541D01*
X-1203198Y163081D01*
X-1202268Y162928D01*
Y166148D01*
G01X-1190036Y144405D02*
X-1196236D01*
Y146321D01*
X-1195926Y146935D01*
X-1195513Y147318D01*
X-1194686Y147471D01*
X-1193859Y147318D01*
X-1193343Y146858D01*
X-1193033Y146321D01*
Y144405D01*
G01Y146321D02*
X-1190036Y147471D01*
G01X-1191276Y150451D02*
X-1190553Y150911D01*
X-1190139Y151525D01*
X-1190036Y152215D01*
X-1190139Y152828D01*
X-1190656Y153441D01*
X-1191276Y153825D01*
X-1191896Y153901D01*
X-1192619Y153748D01*
X-1193136Y153211D01*
X-1193343Y152675D01*
Y151985D01*
G01Y152675D02*
X-1193653Y153135D01*
X-1194169Y153518D01*
X-1194789Y153671D01*
X-1195409Y153518D01*
X-1195926Y153135D01*
X-1196236Y152445D01*
X-1196133Y151755D01*
X-1195719Y151065D01*
G01X-1196236Y158338D02*
X-1196029Y157725D01*
X-1195513Y157265D01*
X-1194893Y156958D01*
X-1194066Y156728D01*
X-1193136Y156651D01*
X-1192206Y156728D01*
X-1191379Y156958D01*
X-1190759Y157265D01*
X-1190243Y157725D01*
X-1190036Y158338D01*
X-1190243Y158951D01*
X-1190759Y159411D01*
X-1191379Y159718D01*
X-1192206Y159948D01*
X-1193136Y160025D01*
X-1194066Y159948D01*
X-1194893Y159718D01*
X-1195513Y159411D01*
X-1196029Y158951D01*
X-1196236Y158338D01*
G01X-1190036Y164538D02*
X-1190139Y165075D01*
X-1190449Y165688D01*
X-1190966Y166071D01*
X-1191689Y166225D01*
X-1192413Y166071D01*
X-1193033Y165611D01*
X-1193343Y164921D01*
Y164155D01*
X-1193549Y163695D01*
X-1194066Y163311D01*
X-1194789Y163158D01*
X-1195513Y163388D01*
X-1196029Y163925D01*
X-1196236Y164538D01*
X-1196029Y165151D01*
X-1195513Y165688D01*
X-1194789Y165918D01*
X-1194066Y165765D01*
X-1193549Y165381D01*
X-1193343Y164921D01*
Y164155D01*
X-1193033Y163465D01*
X-1192413Y163005D01*
X-1191689Y162851D01*
X-1190966Y163005D01*
X-1190449Y163388D01*
X-1190139Y164001D01*
X-1190036Y164538D01*
G01X-1196804Y293738D02*
X-1190604D01*
G01X-1196804Y291975D02*
Y295501D01*
G01X-1190604Y298405D02*
X-1196804D01*
Y300245D01*
X-1196494Y300858D01*
X-1195771Y301318D01*
X-1194944Y301471D01*
X-1194117Y301318D01*
X-1193497Y300935D01*
X-1193187Y300245D01*
Y298405D01*
G01X-1190604Y306138D02*
X-1196804D01*
X-1195564Y305218D01*
G01X-1190604D02*
Y307058D01*
G01X-1191844Y310651D02*
X-1191121Y311111D01*
X-1190707Y311725D01*
X-1190604Y312415D01*
X-1190707Y313028D01*
X-1191224Y313641D01*
X-1191844Y314025D01*
X-1192464Y314101D01*
X-1193187Y313948D01*
X-1193704Y313411D01*
X-1193911Y312875D01*
Y312185D01*
G01Y312875D02*
X-1194221Y313335D01*
X-1194737Y313718D01*
X-1195357Y313871D01*
X-1195977Y313718D01*
X-1196494Y313335D01*
X-1196804Y312645D01*
X-1196701Y311955D01*
X-1196287Y311265D01*
G01X-1192636Y328205D02*
X-1198836D01*
Y330121D01*
X-1198526Y330735D01*
X-1198113Y331118D01*
X-1197286Y331271D01*
X-1196459Y331118D01*
X-1195943Y330658D01*
X-1195633Y330121D01*
Y328205D01*
G01Y330121D02*
X-1192636Y331271D01*
G01Y336858D02*
X-1198836D01*
X-1194393Y334021D01*
Y337855D01*
G01X-1195219Y340681D02*
X-1195943Y341218D01*
X-1196356Y341678D01*
X-1196563Y342291D01*
X-1196356Y342828D01*
X-1195943Y343211D01*
X-1195323Y343518D01*
X-1194599Y343595D01*
X-1193979Y343518D01*
X-1193359Y343211D01*
X-1192843Y342751D01*
X-1192636Y342215D01*
X-1192843Y341601D01*
X-1193462Y341065D01*
X-1194393Y340758D01*
X-1195426Y340681D01*
X-1196769Y340835D01*
X-1197493Y341065D01*
X-1198216Y341448D01*
X-1198733Y341985D01*
X-1198836Y342521D01*
X-1198629Y343058D01*
X-1198113Y343441D01*
G01X-1193566Y346651D02*
X-1193049Y347111D01*
X-1192739Y347648D01*
X-1192636Y348338D01*
X-1192843Y349028D01*
X-1193256Y349565D01*
X-1193979Y349948D01*
X-1194806Y350025D01*
X-1195633Y349871D01*
X-1196149Y349488D01*
X-1196563Y348951D01*
X-1196666Y348415D01*
X-1196563Y347878D01*
X-1196149Y347188D01*
X-1198836Y347418D01*
Y349488D01*
G01X-1198273Y419949D02*
X-1197813Y420569D01*
X-1197276Y420879D01*
X-1196663Y420982D01*
X-1195896Y420775D01*
X-1195359Y420259D01*
X-1195206Y419639D01*
X-1195283Y419019D01*
X-1195589Y418502D01*
X-1197123Y417469D01*
X-1197813Y416745D01*
X-1198273Y415712D01*
X-1198426Y414782D01*
X-1195206D01*
G01X-1192073Y419949D02*
X-1191613Y420569D01*
X-1191076Y420879D01*
X-1190463Y420982D01*
X-1189696Y420775D01*
X-1189159Y420259D01*
X-1189006Y419639D01*
X-1189083Y419019D01*
X-1189389Y418502D01*
X-1190923Y417469D01*
X-1191613Y416745D01*
X-1192073Y415712D01*
X-1192226Y414782D01*
X-1189006D01*
G01X-1192691Y452602D02*
Y448159D01*
X-1192384Y447228D01*
X-1191771Y446609D01*
X-1191004Y446402D01*
X-1190237Y446609D01*
X-1189624Y447228D01*
X-1189317Y448159D01*
Y452602D01*
G01X-1186491Y447642D02*
X-1186031Y446919D01*
X-1185417Y446505D01*
X-1184727Y446402D01*
X-1184114Y446505D01*
X-1183501Y447022D01*
X-1183117Y447642D01*
X-1183041Y448262D01*
X-1183194Y448985D01*
X-1183731Y449502D01*
X-1184267Y449709D01*
X-1184957D01*
G01X-1184267D02*
X-1183807Y450019D01*
X-1183424Y450535D01*
X-1183271Y451155D01*
X-1183424Y451775D01*
X-1183807Y452292D01*
X-1184497Y452602D01*
X-1185187Y452499D01*
X-1185877Y452085D01*
G01X-1180291Y447642D02*
X-1179831Y446919D01*
X-1179217Y446505D01*
X-1178527Y446402D01*
X-1177914Y446505D01*
X-1177301Y447022D01*
X-1176917Y447642D01*
X-1176841Y448262D01*
X-1176994Y448985D01*
X-1177531Y449502D01*
X-1178067Y449709D01*
X-1178757D01*
G01X-1178067D02*
X-1177607Y450019D01*
X-1177224Y450535D01*
X-1177071Y451155D01*
X-1177224Y451775D01*
X-1177607Y452292D01*
X-1178297Y452602D01*
X-1178987Y452499D01*
X-1179677Y452085D01*
G01X-1196816Y478026D02*
Y484226D01*
X-1197736Y482986D01*
G01Y478026D02*
X-1195896D01*
G01X-1189696D02*
Y484226D01*
X-1192533Y479783D01*
X-1188699D01*
G01X-1182784Y-173962D02*
Y-167762D01*
X-1185621Y-172205D01*
X-1181787D01*
G01X-1183638Y-106919D02*
X-1189838D01*
Y-104005D01*
G01X-1186841Y-105079D02*
Y-106919D01*
G01X-1178738Y-99002D02*
Y-97469D01*
X-1176878D01*
X-1176258Y-97929D01*
X-1175845Y-98465D01*
X-1175638Y-99232D01*
X-1175845Y-99999D01*
X-1176258Y-100535D01*
X-1176878Y-100995D01*
X-1177601Y-101302D01*
X-1178428Y-101455D01*
X-1179151D01*
X-1179771Y-101302D01*
X-1180495Y-100995D01*
X-1181115Y-100535D01*
X-1181528Y-100075D01*
X-1181838Y-99462D01*
Y-98925D01*
X-1181631Y-98312D01*
X-1181218Y-97852D01*
G01X-1178636Y144405D02*
X-1184836D01*
Y146321D01*
X-1184526Y146935D01*
X-1184113Y147318D01*
X-1183286Y147471D01*
X-1182459Y147318D01*
X-1181943Y146858D01*
X-1181633Y146321D01*
Y144405D01*
G01Y146321D02*
X-1178636Y147471D01*
G01X-1179876Y150451D02*
X-1179153Y150911D01*
X-1178739Y151525D01*
X-1178636Y152215D01*
X-1178739Y152828D01*
X-1179256Y153441D01*
X-1179876Y153825D01*
X-1180496Y153901D01*
X-1181219Y153748D01*
X-1181736Y153211D01*
X-1181943Y152675D01*
Y151985D01*
G01Y152675D02*
X-1182253Y153135D01*
X-1182769Y153518D01*
X-1183389Y153671D01*
X-1184009Y153518D01*
X-1184526Y153135D01*
X-1184836Y152445D01*
X-1184733Y151755D01*
X-1184319Y151065D01*
G01X-1183803Y156881D02*
X-1184423Y157341D01*
X-1184733Y157878D01*
X-1184836Y158491D01*
X-1184629Y159258D01*
X-1184113Y159795D01*
X-1183493Y159948D01*
X-1182873Y159871D01*
X-1182356Y159565D01*
X-1181323Y158031D01*
X-1180599Y157341D01*
X-1179566Y156881D01*
X-1178636Y156728D01*
Y159948D01*
G01Y164385D02*
X-1179979Y164538D01*
X-1181116Y164768D01*
X-1182149Y165075D01*
X-1183286Y165458D01*
X-1184836Y166071D01*
Y163005D01*
G01X-1184917Y222621D02*
X-1185377Y222931D01*
X-1185914Y223138D01*
X-1186527D01*
X-1187217Y222828D01*
X-1187754Y222311D01*
X-1188137Y221691D01*
X-1188444Y220658D01*
X-1188521Y219728D01*
X-1188367Y218798D01*
X-1188137Y218178D01*
X-1187677Y217558D01*
X-1187141Y217145D01*
X-1186604Y216938D01*
X-1186067D01*
X-1185531Y217145D01*
X-1185071Y217455D01*
X-1184687Y217868D01*
G01X-1181861Y222105D02*
X-1181401Y222725D01*
X-1180864Y223035D01*
X-1180251Y223138D01*
X-1179484Y222931D01*
X-1178947Y222415D01*
X-1178794Y221795D01*
X-1178871Y221175D01*
X-1179177Y220658D01*
X-1180711Y219625D01*
X-1181401Y218901D01*
X-1181861Y217868D01*
X-1182014Y216938D01*
X-1178794D01*
G01X-1173284D02*
Y223138D01*
X-1176121Y218695D01*
X-1172287D01*
G01X-1168004Y223138D02*
X-1168617Y222931D01*
X-1169077Y222415D01*
X-1169384Y221795D01*
X-1169614Y220968D01*
X-1169691Y220038D01*
X-1169614Y219108D01*
X-1169384Y218281D01*
X-1169077Y217661D01*
X-1168617Y217145D01*
X-1168004Y216938D01*
X-1167391Y217145D01*
X-1166931Y217661D01*
X-1166624Y218281D01*
X-1166394Y219108D01*
X-1166317Y220038D01*
X-1166394Y220968D01*
X-1166624Y221795D01*
X-1166931Y222415D01*
X-1167391Y222931D01*
X-1168004Y223138D01*
G01X-1185117Y210021D02*
X-1185577Y210331D01*
X-1186114Y210538D01*
X-1186727D01*
X-1187417Y210228D01*
X-1187954Y209711D01*
X-1188337Y209091D01*
X-1188644Y208058D01*
X-1188721Y207128D01*
X-1188567Y206198D01*
X-1188337Y205578D01*
X-1187877Y204958D01*
X-1187341Y204545D01*
X-1186804Y204338D01*
X-1186267D01*
X-1185731Y204545D01*
X-1185271Y204855D01*
X-1184887Y205268D01*
G01X-1182061Y209505D02*
X-1181601Y210125D01*
X-1181064Y210435D01*
X-1180451Y210538D01*
X-1179684Y210331D01*
X-1179147Y209815D01*
X-1178994Y209195D01*
X-1179071Y208575D01*
X-1179377Y208058D01*
X-1180911Y207025D01*
X-1181601Y206301D01*
X-1182061Y205268D01*
X-1182214Y204338D01*
X-1178994D01*
G01X-1176091Y205578D02*
X-1175631Y204855D01*
X-1175017Y204441D01*
X-1174327Y204338D01*
X-1173714Y204441D01*
X-1173101Y204958D01*
X-1172717Y205578D01*
X-1172641Y206198D01*
X-1172794Y206921D01*
X-1173331Y207438D01*
X-1173867Y207645D01*
X-1174557D01*
G01X-1173867D02*
X-1173407Y207955D01*
X-1173024Y208471D01*
X-1172871Y209091D01*
X-1173024Y209711D01*
X-1173407Y210228D01*
X-1174097Y210538D01*
X-1174787Y210435D01*
X-1175477Y210021D01*
G01X-1168357Y204338D02*
X-1168204Y205681D01*
X-1167974Y206818D01*
X-1167667Y207851D01*
X-1167284Y208988D01*
X-1166671Y210538D01*
X-1169737D01*
G01X-1184917Y238821D02*
X-1185377Y239131D01*
X-1185914Y239338D01*
X-1186527D01*
X-1187217Y239028D01*
X-1187754Y238511D01*
X-1188137Y237891D01*
X-1188444Y236858D01*
X-1188521Y235928D01*
X-1188367Y234998D01*
X-1188137Y234378D01*
X-1187677Y233758D01*
X-1187141Y233345D01*
X-1186604Y233138D01*
X-1186067D01*
X-1185531Y233345D01*
X-1185071Y233655D01*
X-1184687Y234068D01*
G01X-1181861Y238305D02*
X-1181401Y238925D01*
X-1180864Y239235D01*
X-1180251Y239338D01*
X-1179484Y239131D01*
X-1178947Y238615D01*
X-1178794Y237995D01*
X-1178871Y237375D01*
X-1179177Y236858D01*
X-1180711Y235825D01*
X-1181401Y235101D01*
X-1181861Y234068D01*
X-1182014Y233138D01*
X-1178794D01*
G01X-1175891Y234378D02*
X-1175431Y233655D01*
X-1174817Y233241D01*
X-1174127Y233138D01*
X-1173514Y233241D01*
X-1172901Y233758D01*
X-1172517Y234378D01*
X-1172441Y234998D01*
X-1172594Y235721D01*
X-1173131Y236238D01*
X-1173667Y236445D01*
X-1174357D01*
G01X-1173667D02*
X-1173207Y236755D01*
X-1172824Y237271D01*
X-1172671Y237891D01*
X-1172824Y238511D01*
X-1173207Y239028D01*
X-1173897Y239338D01*
X-1174587Y239235D01*
X-1175277Y238821D01*
G01X-1168004Y233138D02*
X-1167467Y233241D01*
X-1166854Y233551D01*
X-1166471Y234068D01*
X-1166317Y234791D01*
X-1166471Y235515D01*
X-1166931Y236135D01*
X-1167621Y236445D01*
X-1168387D01*
X-1168847Y236651D01*
X-1169231Y237168D01*
X-1169384Y237891D01*
X-1169154Y238615D01*
X-1168617Y239131D01*
X-1168004Y239338D01*
X-1167391Y239131D01*
X-1166854Y238615D01*
X-1166624Y237891D01*
X-1166777Y237168D01*
X-1167161Y236651D01*
X-1167621Y236445D01*
X-1168387D01*
X-1169077Y236135D01*
X-1169537Y235515D01*
X-1169691Y234791D01*
X-1169537Y234068D01*
X-1169154Y233551D01*
X-1168541Y233241D01*
X-1168004Y233138D01*
G01X-1188904Y260238D02*
X-1188367Y260341D01*
X-1187754Y260651D01*
X-1187371Y261168D01*
X-1187217Y261891D01*
X-1187371Y262615D01*
X-1187831Y263235D01*
X-1188521Y263545D01*
X-1189287D01*
X-1189747Y263751D01*
X-1190131Y264268D01*
X-1190284Y264991D01*
X-1190054Y265715D01*
X-1189517Y266231D01*
X-1188904Y266438D01*
X-1188291Y266231D01*
X-1187754Y265715D01*
X-1187524Y264991D01*
X-1187677Y264268D01*
X-1188061Y263751D01*
X-1188521Y263545D01*
X-1189287D01*
X-1189977Y263235D01*
X-1190437Y262615D01*
X-1190591Y261891D01*
X-1190437Y261168D01*
X-1190054Y260651D01*
X-1189441Y260341D01*
X-1188904Y260238D01*
G01X-1180192Y322934D02*
X-1186392D01*
X-1181949Y320097D01*
Y323931D01*
G01X-1177768Y330151D02*
X-1173325D01*
X-1172394Y330458D01*
X-1171775Y331071D01*
X-1171568Y331838D01*
X-1171775Y332605D01*
X-1172394Y333218D01*
X-1173325Y333525D01*
X-1177768D01*
G01X-1171568Y338958D02*
X-1177768D01*
X-1173325Y336121D01*
Y339955D01*
G01X-1177768Y344238D02*
X-1177561Y343625D01*
X-1177045Y343165D01*
X-1176425Y342858D01*
X-1175598Y342628D01*
X-1174668Y342551D01*
X-1173738Y342628D01*
X-1172911Y342858D01*
X-1172291Y343165D01*
X-1171775Y343625D01*
X-1171568Y344238D01*
X-1171775Y344851D01*
X-1172291Y345311D01*
X-1172911Y345618D01*
X-1173738Y345848D01*
X-1174668Y345925D01*
X-1175598Y345848D01*
X-1176425Y345618D01*
X-1177045Y345311D01*
X-1177561Y344851D01*
X-1177768Y344238D01*
G01X-1181344Y352065D02*
X-1180621Y352525D01*
X-1180207Y353139D01*
X-1180104Y353829D01*
X-1180207Y354442D01*
X-1180724Y355055D01*
X-1181344Y355439D01*
X-1181964Y355515D01*
X-1182687Y355362D01*
X-1183204Y354825D01*
X-1183411Y354289D01*
Y353599D01*
G01Y354289D02*
X-1183721Y354749D01*
X-1184237Y355132D01*
X-1184857Y355285D01*
X-1185477Y355132D01*
X-1185994Y354749D01*
X-1186304Y354059D01*
X-1186201Y353369D01*
X-1185787Y352679D01*
G01X-1187591Y388170D02*
Y383727D01*
X-1187284Y382796D01*
X-1186671Y382177D01*
X-1185904Y381970D01*
X-1185137Y382177D01*
X-1184524Y382796D01*
X-1184217Y383727D01*
Y388170D01*
G01X-1181391Y383210D02*
X-1180931Y382487D01*
X-1180317Y382073D01*
X-1179627Y381970D01*
X-1179014Y382073D01*
X-1178401Y382590D01*
X-1178017Y383210D01*
X-1177941Y383830D01*
X-1178094Y384553D01*
X-1178631Y385070D01*
X-1179167Y385277D01*
X-1179857D01*
G01X-1179167D02*
X-1178707Y385587D01*
X-1178324Y386103D01*
X-1178171Y386723D01*
X-1178324Y387343D01*
X-1178707Y387860D01*
X-1179397Y388170D01*
X-1180087Y388067D01*
X-1180777Y387653D01*
G01X-1173504Y388170D02*
X-1174117Y387963D01*
X-1174577Y387447D01*
X-1174884Y386827D01*
X-1175114Y386000D01*
X-1175191Y385070D01*
X-1175114Y384140D01*
X-1174884Y383313D01*
X-1174577Y382693D01*
X-1174117Y382177D01*
X-1173504Y381970D01*
X-1172891Y382177D01*
X-1172431Y382693D01*
X-1172124Y383313D01*
X-1171894Y384140D01*
X-1171817Y385070D01*
X-1171894Y386000D01*
X-1172124Y386827D01*
X-1172431Y387447D01*
X-1172891Y387963D01*
X-1173504Y388170D01*
G01X-1172804Y-205262D02*
X-1166604D01*
G01X-1172804Y-207025D02*
Y-203499D01*
G01X-1166604Y-200595D02*
X-1172804D01*
Y-198755D01*
X-1172494Y-198142D01*
X-1171771Y-197682D01*
X-1170944Y-197529D01*
X-1170117Y-197682D01*
X-1169497Y-198065D01*
X-1169187Y-198755D01*
Y-200595D01*
G01X-1166604Y-191942D02*
X-1172804D01*
X-1168361Y-194779D01*
Y-190945D01*
G01X-1167327Y-187965D02*
X-1166811Y-187429D01*
X-1166604Y-186815D01*
X-1166811Y-186202D01*
X-1167430Y-185665D01*
X-1168361Y-185282D01*
X-1169291Y-185129D01*
X-1170427D01*
X-1171357Y-185282D01*
X-1172184Y-185665D01*
X-1172597Y-186125D01*
X-1172804Y-186662D01*
X-1172597Y-187275D01*
X-1172184Y-187735D01*
X-1171564Y-188042D01*
X-1170737Y-188195D01*
X-1170014Y-188042D01*
X-1169291Y-187659D01*
X-1168877Y-187199D01*
X-1168774Y-186662D01*
X-1168981Y-186049D01*
X-1169497Y-185589D01*
X-1170427Y-185129D01*
G01X-1166604Y-181795D02*
X-1172804D01*
Y-179879D01*
X-1172494Y-179265D01*
X-1172081Y-178882D01*
X-1171254Y-178729D01*
X-1170427Y-178882D01*
X-1169911Y-179342D01*
X-1169601Y-179879D01*
Y-181795D01*
G01Y-179879D02*
X-1166604Y-178729D01*
G01X-1171771Y-175519D02*
X-1172391Y-175059D01*
X-1172701Y-174522D01*
X-1172804Y-173909D01*
X-1172597Y-173142D01*
X-1172081Y-172605D01*
X-1171461Y-172452D01*
X-1170841Y-172529D01*
X-1170324Y-172835D01*
X-1169291Y-174369D01*
X-1168567Y-175059D01*
X-1167534Y-175519D01*
X-1166604Y-175672D01*
Y-172452D01*
G01X-1167844Y-169549D02*
X-1167121Y-169089D01*
X-1166707Y-168475D01*
X-1166604Y-167785D01*
X-1166707Y-167172D01*
X-1167224Y-166559D01*
X-1167844Y-166175D01*
X-1168464Y-166099D01*
X-1169187Y-166252D01*
X-1169704Y-166789D01*
X-1169911Y-167325D01*
Y-168015D01*
G01Y-167325D02*
X-1170221Y-166865D01*
X-1170737Y-166482D01*
X-1171357Y-166329D01*
X-1171977Y-166482D01*
X-1172494Y-166865D01*
X-1172804Y-167555D01*
X-1172701Y-168245D01*
X-1172287Y-168935D01*
G01X-1167534Y-163349D02*
X-1167017Y-162889D01*
X-1166707Y-162352D01*
X-1166604Y-161662D01*
X-1166811Y-160972D01*
X-1167224Y-160435D01*
X-1167947Y-160052D01*
X-1168774Y-159975D01*
X-1169601Y-160129D01*
X-1170117Y-160512D01*
X-1170531Y-161049D01*
X-1170634Y-161585D01*
X-1170531Y-162122D01*
X-1170117Y-162812D01*
X-1172804Y-162582D01*
Y-160512D01*
G01X-1160161Y-161479D02*
X-1159624Y-160755D01*
X-1159164Y-160342D01*
X-1158551Y-160135D01*
X-1158014Y-160342D01*
X-1157631Y-160755D01*
X-1157324Y-161375D01*
X-1157247Y-162099D01*
X-1157324Y-162719D01*
X-1157631Y-163339D01*
X-1158091Y-163855D01*
X-1158627Y-164062D01*
X-1159241Y-163855D01*
X-1159777Y-163236D01*
X-1160084Y-162305D01*
X-1160161Y-161272D01*
X-1160007Y-159929D01*
X-1159777Y-159205D01*
X-1159394Y-158482D01*
X-1158857Y-157965D01*
X-1158321Y-157862D01*
X-1157784Y-158069D01*
X-1157401Y-158585D01*
G01X-1159537Y-129062D02*
Y-122862D01*
X-1157621D01*
X-1157007Y-123172D01*
X-1156624Y-123585D01*
X-1156471Y-124412D01*
X-1156624Y-125239D01*
X-1157084Y-125755D01*
X-1157621Y-126065D01*
X-1159537D01*
G01X-1157621D02*
X-1156471Y-129062D01*
G01X-1153491Y-127822D02*
X-1153031Y-128545D01*
X-1152417Y-128959D01*
X-1151727Y-129062D01*
X-1151114Y-128959D01*
X-1150501Y-128442D01*
X-1150117Y-127822D01*
X-1150041Y-127202D01*
X-1150194Y-126479D01*
X-1150731Y-125962D01*
X-1151267Y-125755D01*
X-1151957D01*
G01X-1151267D02*
X-1150807Y-125445D01*
X-1150424Y-124929D01*
X-1150271Y-124309D01*
X-1150424Y-123689D01*
X-1150807Y-123172D01*
X-1151497Y-122862D01*
X-1152187Y-122965D01*
X-1152877Y-123379D01*
G01X-1147061Y-126479D02*
X-1146524Y-125755D01*
X-1146064Y-125342D01*
X-1145451Y-125135D01*
X-1144914Y-125342D01*
X-1144531Y-125755D01*
X-1144224Y-126375D01*
X-1144147Y-127099D01*
X-1144224Y-127719D01*
X-1144531Y-128339D01*
X-1144991Y-128855D01*
X-1145527Y-129062D01*
X-1146141Y-128855D01*
X-1146677Y-128236D01*
X-1146984Y-127305D01*
X-1147061Y-126272D01*
X-1146907Y-124929D01*
X-1146677Y-124205D01*
X-1146294Y-123482D01*
X-1145757Y-122965D01*
X-1145221Y-122862D01*
X-1144684Y-123069D01*
X-1144301Y-123585D01*
G01X-1139404Y-122862D02*
X-1140017Y-123069D01*
X-1140477Y-123585D01*
X-1140784Y-124205D01*
X-1141014Y-125032D01*
X-1141091Y-125962D01*
X-1141014Y-126892D01*
X-1140784Y-127719D01*
X-1140477Y-128339D01*
X-1140017Y-128855D01*
X-1139404Y-129062D01*
X-1138791Y-128855D01*
X-1138331Y-128339D01*
X-1138024Y-127719D01*
X-1137794Y-126892D01*
X-1137717Y-125962D01*
X-1137794Y-125032D01*
X-1138024Y-124205D01*
X-1138331Y-123585D01*
X-1138791Y-123069D01*
X-1139404Y-122862D01*
G01X-1154638Y-107149D02*
X-1160838D01*
G01Y-104235D02*
X-1157015Y-107149D01*
G01X-1154638Y-103775D02*
X-1158771Y-105845D01*
G01X-1161878Y-100995D02*
X-1161258Y-100612D01*
X-1160845Y-100152D01*
X-1160638Y-99615D01*
X-1160845Y-99002D01*
X-1161258Y-98542D01*
X-1161878Y-98082D01*
X-1162705Y-97929D01*
X-1166838D01*
G01X-1167638Y-107072D02*
X-1173838D01*
G01Y-103852D02*
X-1167638D01*
G01X-1170738D02*
Y-107072D01*
G01X-1157591Y-5762D02*
Y-10205D01*
X-1157284Y-11136D01*
X-1156671Y-11755D01*
X-1155904Y-11962D01*
X-1155137Y-11755D01*
X-1154524Y-11136D01*
X-1154217Y-10205D01*
Y-5762D01*
G01X-1151161Y-6795D02*
X-1150701Y-6175D01*
X-1150164Y-5865D01*
X-1149551Y-5762D01*
X-1148784Y-5969D01*
X-1148247Y-6485D01*
X-1148094Y-7105D01*
X-1148171Y-7725D01*
X-1148477Y-8242D01*
X-1150011Y-9275D01*
X-1150701Y-9999D01*
X-1151161Y-11032D01*
X-1151314Y-11962D01*
X-1148094D01*
G01X-1142584D02*
Y-5762D01*
X-1145421Y-10205D01*
X-1141587D01*
G01X-1166836Y144405D02*
X-1173036D01*
Y146321D01*
X-1172726Y146935D01*
X-1172313Y147318D01*
X-1171486Y147471D01*
X-1170659Y147318D01*
X-1170143Y146858D01*
X-1169833Y146321D01*
Y144405D01*
G01Y146321D02*
X-1166836Y147471D01*
G01X-1168076Y150451D02*
X-1167353Y150911D01*
X-1166939Y151525D01*
X-1166836Y152215D01*
X-1166939Y152828D01*
X-1167456Y153441D01*
X-1168076Y153825D01*
X-1168696Y153901D01*
X-1169419Y153748D01*
X-1169936Y153211D01*
X-1170143Y152675D01*
Y151985D01*
G01Y152675D02*
X-1170453Y153135D01*
X-1170969Y153518D01*
X-1171589Y153671D01*
X-1172209Y153518D01*
X-1172726Y153135D01*
X-1173036Y152445D01*
X-1172933Y151755D01*
X-1172519Y151065D01*
G01X-1172003Y156881D02*
X-1172623Y157341D01*
X-1172933Y157878D01*
X-1173036Y158491D01*
X-1172829Y159258D01*
X-1172313Y159795D01*
X-1171693Y159948D01*
X-1171073Y159871D01*
X-1170556Y159565D01*
X-1169523Y158031D01*
X-1168799Y157341D01*
X-1167766Y156881D01*
X-1166836Y156728D01*
Y159948D01*
G01X-1167766Y162851D02*
X-1167249Y163311D01*
X-1166939Y163848D01*
X-1166836Y164538D01*
X-1167043Y165228D01*
X-1167456Y165765D01*
X-1168179Y166148D01*
X-1169006Y166225D01*
X-1169833Y166071D01*
X-1170349Y165688D01*
X-1170763Y165151D01*
X-1170866Y164615D01*
X-1170763Y164078D01*
X-1170349Y163388D01*
X-1173036Y163618D01*
Y165688D01*
G01X-1162004Y200138D02*
Y193938D01*
G01X-1163767Y200138D02*
X-1160241D01*
G01X-1157337Y193938D02*
Y200138D01*
X-1155497D01*
X-1154884Y199828D01*
X-1154424Y199105D01*
X-1154271Y198278D01*
X-1154424Y197451D01*
X-1154807Y196831D01*
X-1155497Y196521D01*
X-1157337D01*
G01X-1151291Y194868D02*
X-1150831Y194351D01*
X-1150294Y194041D01*
X-1149604Y193938D01*
X-1148914Y194145D01*
X-1148377Y194558D01*
X-1147994Y195281D01*
X-1147917Y196108D01*
X-1148071Y196935D01*
X-1148454Y197451D01*
X-1148991Y197865D01*
X-1149527Y197968D01*
X-1150064Y197865D01*
X-1150754Y197451D01*
X-1150524Y200138D01*
X-1148454D01*
G01X-1145091Y195178D02*
X-1144631Y194455D01*
X-1144017Y194041D01*
X-1143327Y193938D01*
X-1142714Y194041D01*
X-1142101Y194558D01*
X-1141717Y195178D01*
X-1141641Y195798D01*
X-1141794Y196521D01*
X-1142331Y197038D01*
X-1142867Y197245D01*
X-1143557D01*
G01X-1142867D02*
X-1142407Y197555D01*
X-1142024Y198071D01*
X-1141871Y198691D01*
X-1142024Y199311D01*
X-1142407Y199828D01*
X-1143097Y200138D01*
X-1143787Y200035D01*
X-1144477Y199621D01*
G01X-1163804Y205938D02*
Y212138D01*
X-1164724Y210898D01*
G01Y205938D02*
X-1162884D01*
G01X-1159061Y211105D02*
X-1158601Y211725D01*
X-1158064Y212035D01*
X-1157451Y212138D01*
X-1156684Y211931D01*
X-1156147Y211415D01*
X-1155994Y210795D01*
X-1156071Y210175D01*
X-1156377Y209658D01*
X-1157911Y208625D01*
X-1158601Y207901D01*
X-1159061Y206868D01*
X-1159214Y205938D01*
X-1155994D01*
G01X-1159857Y233938D02*
X-1159704Y235281D01*
X-1159474Y236418D01*
X-1159167Y237451D01*
X-1158784Y238588D01*
X-1158171Y240138D01*
X-1161237D01*
G01X-1160791Y284370D02*
Y279927D01*
X-1160484Y278996D01*
X-1159871Y278377D01*
X-1159104Y278170D01*
X-1158337Y278377D01*
X-1157724Y278996D01*
X-1157417Y279927D01*
Y284370D01*
G01X-1154591Y279410D02*
X-1154131Y278687D01*
X-1153517Y278273D01*
X-1152827Y278170D01*
X-1152214Y278273D01*
X-1151601Y278790D01*
X-1151217Y279410D01*
X-1151141Y280030D01*
X-1151294Y280753D01*
X-1151831Y281270D01*
X-1152367Y281477D01*
X-1153057D01*
G01X-1152367D02*
X-1151907Y281787D01*
X-1151524Y282303D01*
X-1151371Y282923D01*
X-1151524Y283543D01*
X-1151907Y284060D01*
X-1152597Y284370D01*
X-1153287Y284267D01*
X-1153977Y283853D01*
G01X-1146704Y278170D02*
X-1146167Y278273D01*
X-1145554Y278583D01*
X-1145171Y279100D01*
X-1145017Y279823D01*
X-1145171Y280547D01*
X-1145631Y281167D01*
X-1146321Y281477D01*
X-1147087D01*
X-1147547Y281683D01*
X-1147931Y282200D01*
X-1148084Y282923D01*
X-1147854Y283647D01*
X-1147317Y284163D01*
X-1146704Y284370D01*
X-1146091Y284163D01*
X-1145554Y283647D01*
X-1145324Y282923D01*
X-1145477Y282200D01*
X-1145861Y281683D01*
X-1146321Y281477D01*
X-1147087D01*
X-1147777Y281167D01*
X-1148237Y280547D01*
X-1148391Y279823D01*
X-1148237Y279100D01*
X-1147854Y278583D01*
X-1147241Y278273D01*
X-1146704Y278170D01*
G01X-1169735Y321061D02*
X-1170459Y321598D01*
X-1170872Y322058D01*
X-1171079Y322671D01*
X-1170872Y323208D01*
X-1170459Y323591D01*
X-1169839Y323898D01*
X-1169115Y323975D01*
X-1168495Y323898D01*
X-1167875Y323591D01*
X-1167359Y323131D01*
X-1167152Y322595D01*
X-1167359Y321981D01*
X-1167978Y321445D01*
X-1168909Y321138D01*
X-1169942Y321061D01*
X-1171285Y321215D01*
X-1172009Y321445D01*
X-1172732Y321828D01*
X-1173249Y322365D01*
X-1173352Y322901D01*
X-1173145Y323438D01*
X-1172629Y323821D01*
G01X-1174649Y419949D02*
X-1174189Y420569D01*
X-1173652Y420879D01*
X-1173039Y420982D01*
X-1172272Y420775D01*
X-1171735Y420259D01*
X-1171582Y419639D01*
X-1171659Y419019D01*
X-1171965Y418502D01*
X-1173499Y417469D01*
X-1174189Y416745D01*
X-1174649Y415712D01*
X-1174802Y414782D01*
X-1171582D01*
G01X-1166992D02*
X-1166455Y414885D01*
X-1165842Y415195D01*
X-1165459Y415712D01*
X-1165305Y416435D01*
X-1165459Y417159D01*
X-1165919Y417779D01*
X-1166609Y418089D01*
X-1167375D01*
X-1167835Y418295D01*
X-1168219Y418812D01*
X-1168372Y419535D01*
X-1168142Y420259D01*
X-1167605Y420775D01*
X-1166992Y420982D01*
X-1166379Y420775D01*
X-1165842Y420259D01*
X-1165612Y419535D01*
X-1165765Y418812D01*
X-1166149Y418295D01*
X-1166609Y418089D01*
X-1167375D01*
X-1168065Y417779D01*
X-1168525Y417159D01*
X-1168679Y416435D01*
X-1168525Y415712D01*
X-1168142Y415195D01*
X-1167529Y414885D01*
X-1166992Y414782D01*
G01X-1170092Y478026D02*
X-1169555Y478129D01*
X-1168942Y478439D01*
X-1168559Y478956D01*
X-1168405Y479679D01*
X-1168559Y480403D01*
X-1169019Y481023D01*
X-1169709Y481333D01*
X-1170475D01*
X-1170935Y481539D01*
X-1171319Y482056D01*
X-1171472Y482779D01*
X-1171242Y483503D01*
X-1170705Y484019D01*
X-1170092Y484226D01*
X-1169479Y484019D01*
X-1168942Y483503D01*
X-1168712Y482779D01*
X-1168865Y482056D01*
X-1169249Y481539D01*
X-1169709Y481333D01*
X-1170475D01*
X-1171165Y481023D01*
X-1171625Y480403D01*
X-1171779Y479679D01*
X-1171625Y478956D01*
X-1171242Y478439D01*
X-1170629Y478129D01*
X-1170092Y478026D01*
G01X-1155704Y-200962D02*
Y-194762D01*
X-1156624Y-196002D01*
G01Y-200962D02*
X-1154784D01*
G01X-1143804Y-179062D02*
Y-176272D01*
X-1145337Y-172862D01*
G01X-1142271D02*
X-1143804Y-176272D01*
G01X-1139291Y-177822D02*
X-1138831Y-178545D01*
X-1138217Y-178959D01*
X-1137527Y-179062D01*
X-1136914Y-178959D01*
X-1136301Y-178442D01*
X-1135917Y-177822D01*
X-1135841Y-177202D01*
X-1135994Y-176479D01*
X-1136531Y-175962D01*
X-1137067Y-175755D01*
X-1137757D01*
G01X-1137067D02*
X-1136607Y-175445D01*
X-1136224Y-174929D01*
X-1136071Y-174309D01*
X-1136224Y-173689D01*
X-1136607Y-173172D01*
X-1137297Y-172862D01*
X-1137987Y-172965D01*
X-1138677Y-173379D01*
G01X-1155537Y-160962D02*
Y-154762D01*
X-1153621D01*
X-1153007Y-155072D01*
X-1152624Y-155485D01*
X-1152471Y-156312D01*
X-1152624Y-157139D01*
X-1153084Y-157655D01*
X-1153621Y-157965D01*
X-1155537D01*
G01X-1153621D02*
X-1152471Y-160962D01*
G01X-1149261Y-155795D02*
X-1148801Y-155175D01*
X-1148264Y-154865D01*
X-1147651Y-154762D01*
X-1146884Y-154969D01*
X-1146347Y-155485D01*
X-1146194Y-156105D01*
X-1146271Y-156725D01*
X-1146577Y-157242D01*
X-1148111Y-158275D01*
X-1148801Y-158999D01*
X-1149261Y-160032D01*
X-1149414Y-160962D01*
X-1146194D01*
G01X-1143291Y-159722D02*
X-1142831Y-160445D01*
X-1142217Y-160859D01*
X-1141527Y-160962D01*
X-1140914Y-160859D01*
X-1140301Y-160342D01*
X-1139917Y-159722D01*
X-1139841Y-159102D01*
X-1139994Y-158379D01*
X-1140531Y-157862D01*
X-1141067Y-157655D01*
X-1141757D01*
G01X-1141067D02*
X-1140607Y-157345D01*
X-1140224Y-156829D01*
X-1140071Y-156209D01*
X-1140224Y-155589D01*
X-1140607Y-155072D01*
X-1141297Y-154762D01*
X-1141987Y-154865D01*
X-1142677Y-155279D01*
G01X-1136707Y-160239D02*
X-1136171Y-160755D01*
X-1135557Y-160962D01*
X-1134944Y-160755D01*
X-1134407Y-160136D01*
X-1134024Y-159205D01*
X-1133871Y-158275D01*
Y-157139D01*
X-1134024Y-156209D01*
X-1134407Y-155382D01*
X-1134867Y-154969D01*
X-1135404Y-154762D01*
X-1136017Y-154969D01*
X-1136477Y-155382D01*
X-1136784Y-156002D01*
X-1136937Y-156829D01*
X-1136784Y-157552D01*
X-1136401Y-158275D01*
X-1135941Y-158689D01*
X-1135404Y-158792D01*
X-1134791Y-158585D01*
X-1134331Y-158069D01*
X-1133871Y-157139D01*
G01X-1153838Y-100995D02*
X-1147638D01*
Y-97929D01*
G01X-1141638Y-107455D02*
X-1147838D01*
X-1142671Y-105462D01*
X-1147838Y-103469D01*
X-1141638D01*
G01X-1150291Y229402D02*
Y224959D01*
X-1149984Y224028D01*
X-1149371Y223409D01*
X-1148604Y223202D01*
X-1147837Y223409D01*
X-1147224Y224028D01*
X-1146917Y224959D01*
Y229402D01*
G01X-1143861Y228369D02*
X-1143401Y228989D01*
X-1142864Y229299D01*
X-1142251Y229402D01*
X-1141484Y229195D01*
X-1140947Y228679D01*
X-1140794Y228059D01*
X-1140871Y227439D01*
X-1141177Y226922D01*
X-1142711Y225889D01*
X-1143401Y225165D01*
X-1143861Y224132D01*
X-1144014Y223202D01*
X-1140794D01*
G01X-1137661Y228369D02*
X-1137201Y228989D01*
X-1136664Y229299D01*
X-1136051Y229402D01*
X-1135284Y229195D01*
X-1134747Y228679D01*
X-1134594Y228059D01*
X-1134671Y227439D01*
X-1134977Y226922D01*
X-1136511Y225889D01*
X-1137201Y225165D01*
X-1137661Y224132D01*
X-1137814Y223202D01*
X-1134594D01*
G01X-1140636Y333205D02*
X-1146836D01*
Y335121D01*
X-1146526Y335735D01*
X-1146113Y336118D01*
X-1145286Y336271D01*
X-1144459Y336118D01*
X-1143943Y335658D01*
X-1143633Y335121D01*
Y333205D01*
G01Y335121D02*
X-1140636Y336271D01*
G01Y341858D02*
X-1146836D01*
X-1142393Y339021D01*
Y342855D01*
G01X-1140636Y348058D02*
X-1146836D01*
X-1142393Y345221D01*
Y349055D01*
G01X-1141876Y351651D02*
X-1141153Y352111D01*
X-1140739Y352725D01*
X-1140636Y353415D01*
X-1140739Y354028D01*
X-1141256Y354641D01*
X-1141876Y355025D01*
X-1142496Y355101D01*
X-1143219Y354948D01*
X-1143736Y354411D01*
X-1143943Y353875D01*
Y353185D01*
G01Y353875D02*
X-1144253Y354335D01*
X-1144769Y354718D01*
X-1145389Y354871D01*
X-1146009Y354718D01*
X-1146526Y354335D01*
X-1146836Y353645D01*
X-1146733Y352955D01*
X-1146319Y352265D01*
G01X-1145207Y363761D02*
X-1144671Y363245D01*
X-1144057Y363038D01*
X-1143444Y363245D01*
X-1142907Y363864D01*
X-1142524Y364795D01*
X-1142371Y365725D01*
Y366861D01*
X-1142524Y367791D01*
X-1142907Y368618D01*
X-1143367Y369031D01*
X-1143904Y369238D01*
X-1144517Y369031D01*
X-1144977Y368618D01*
X-1145284Y367998D01*
X-1145437Y367171D01*
X-1145284Y366448D01*
X-1144901Y365725D01*
X-1144441Y365311D01*
X-1143904Y365208D01*
X-1143291Y365415D01*
X-1142831Y365931D01*
X-1142371Y366861D01*
G01X-1155804Y409738D02*
X-1149604D01*
G01X-1155804Y407975D02*
Y411501D01*
G01X-1149604Y414405D02*
X-1155804D01*
Y416245D01*
X-1155494Y416858D01*
X-1154771Y417318D01*
X-1153944Y417471D01*
X-1153117Y417318D01*
X-1152497Y416935D01*
X-1152187Y416245D01*
Y414405D01*
G01X-1154771Y420681D02*
X-1155391Y421141D01*
X-1155701Y421678D01*
X-1155804Y422291D01*
X-1155597Y423058D01*
X-1155081Y423595D01*
X-1154461Y423748D01*
X-1153841Y423671D01*
X-1153324Y423365D01*
X-1152291Y421831D01*
X-1151567Y421141D01*
X-1150534Y420681D01*
X-1149604Y420528D01*
Y423748D01*
G01X-1150534Y426651D02*
X-1150017Y427111D01*
X-1149707Y427648D01*
X-1149604Y428338D01*
X-1149811Y429028D01*
X-1150224Y429565D01*
X-1150947Y429948D01*
X-1151774Y430025D01*
X-1152601Y429871D01*
X-1153117Y429488D01*
X-1153531Y428951D01*
X-1153634Y428415D01*
X-1153531Y427878D01*
X-1153117Y427188D01*
X-1155804Y427418D01*
Y429488D01*
G01X-1146804Y404938D02*
Y411138D01*
X-1147724Y409898D01*
G01Y404938D02*
X-1145884D01*
G01X-1142061Y407521D02*
X-1141524Y408245D01*
X-1141064Y408658D01*
X-1140451Y408865D01*
X-1139914Y408658D01*
X-1139531Y408245D01*
X-1139224Y407625D01*
X-1139147Y406901D01*
X-1139224Y406281D01*
X-1139531Y405661D01*
X-1139991Y405145D01*
X-1140527Y404938D01*
X-1141141Y405145D01*
X-1141677Y405764D01*
X-1141984Y406695D01*
X-1142061Y407728D01*
X-1141907Y409071D01*
X-1141677Y409795D01*
X-1141294Y410518D01*
X-1140757Y411035D01*
X-1140221Y411138D01*
X-1139684Y410931D01*
X-1139301Y410415D01*
G01X-1146537Y418938D02*
Y425138D01*
X-1144621D01*
X-1144007Y424828D01*
X-1143624Y424415D01*
X-1143471Y423588D01*
X-1143624Y422761D01*
X-1144084Y422245D01*
X-1144621Y421935D01*
X-1146537D01*
G01X-1144621D02*
X-1143471Y418938D01*
G01X-1140491Y420178D02*
X-1140031Y419455D01*
X-1139417Y419041D01*
X-1138727Y418938D01*
X-1138114Y419041D01*
X-1137501Y419558D01*
X-1137117Y420178D01*
X-1137041Y420798D01*
X-1137194Y421521D01*
X-1137731Y422038D01*
X-1138267Y422245D01*
X-1138957D01*
G01X-1138267D02*
X-1137807Y422555D01*
X-1137424Y423071D01*
X-1137271Y423691D01*
X-1137424Y424311D01*
X-1137807Y424828D01*
X-1138497Y425138D01*
X-1139187Y425035D01*
X-1139877Y424621D01*
G01X-1134061Y424105D02*
X-1133601Y424725D01*
X-1133064Y425035D01*
X-1132451Y425138D01*
X-1131684Y424931D01*
X-1131147Y424415D01*
X-1130994Y423795D01*
X-1131071Y423175D01*
X-1131377Y422658D01*
X-1132911Y421625D01*
X-1133601Y420901D01*
X-1134061Y419868D01*
X-1134214Y418938D01*
X-1130994D01*
G01X-1126404Y425138D02*
X-1127017Y424931D01*
X-1127477Y424415D01*
X-1127784Y423795D01*
X-1128014Y422968D01*
X-1128091Y422038D01*
X-1128014Y421108D01*
X-1127784Y420281D01*
X-1127477Y419661D01*
X-1127017Y419145D01*
X-1126404Y418938D01*
X-1125791Y419145D01*
X-1125331Y419661D01*
X-1125024Y420281D01*
X-1124794Y421108D01*
X-1124717Y422038D01*
X-1124794Y422968D01*
X-1125024Y423795D01*
X-1125331Y424415D01*
X-1125791Y424931D01*
X-1126404Y425138D01*
G01X-1146537Y428938D02*
Y435138D01*
X-1144621D01*
X-1144007Y434828D01*
X-1143624Y434415D01*
X-1143471Y433588D01*
X-1143624Y432761D01*
X-1144084Y432245D01*
X-1144621Y431935D01*
X-1146537D01*
G01X-1144621D02*
X-1143471Y428938D01*
G01X-1140491Y430178D02*
X-1140031Y429455D01*
X-1139417Y429041D01*
X-1138727Y428938D01*
X-1138114Y429041D01*
X-1137501Y429558D01*
X-1137117Y430178D01*
X-1137041Y430798D01*
X-1137194Y431521D01*
X-1137731Y432038D01*
X-1138267Y432245D01*
X-1138957D01*
G01X-1138267D02*
X-1137807Y432555D01*
X-1137424Y433071D01*
X-1137271Y433691D01*
X-1137424Y434311D01*
X-1137807Y434828D01*
X-1138497Y435138D01*
X-1139187Y435035D01*
X-1139877Y434621D01*
G01X-1134061Y434105D02*
X-1133601Y434725D01*
X-1133064Y435035D01*
X-1132451Y435138D01*
X-1131684Y434931D01*
X-1131147Y434415D01*
X-1130994Y433795D01*
X-1131071Y433175D01*
X-1131377Y432658D01*
X-1132911Y431625D01*
X-1133601Y430901D01*
X-1134061Y429868D01*
X-1134214Y428938D01*
X-1130994D01*
G01X-1125484D02*
Y435138D01*
X-1128321Y430695D01*
X-1124487D01*
G01X-1143317Y444621D02*
X-1143777Y444931D01*
X-1144314Y445138D01*
X-1144927D01*
X-1145617Y444828D01*
X-1146154Y444311D01*
X-1146537Y443691D01*
X-1146844Y442658D01*
X-1146921Y441728D01*
X-1146767Y440798D01*
X-1146537Y440178D01*
X-1146077Y439558D01*
X-1145541Y439145D01*
X-1145004Y438938D01*
X-1144467D01*
X-1143931Y439145D01*
X-1143471Y439455D01*
X-1143087Y439868D01*
G01X-1140491Y440178D02*
X-1140031Y439455D01*
X-1139417Y439041D01*
X-1138727Y438938D01*
X-1138114Y439041D01*
X-1137501Y439558D01*
X-1137117Y440178D01*
X-1137041Y440798D01*
X-1137194Y441521D01*
X-1137731Y442038D01*
X-1138267Y442245D01*
X-1138957D01*
G01X-1138267D02*
X-1137807Y442555D01*
X-1137424Y443071D01*
X-1137271Y443691D01*
X-1137424Y444311D01*
X-1137807Y444828D01*
X-1138497Y445138D01*
X-1139187Y445035D01*
X-1139877Y444621D01*
G01X-1132604Y438938D02*
Y445138D01*
X-1133524Y443898D01*
G01Y438938D02*
X-1131684D01*
G01X-1125484D02*
Y445138D01*
X-1128321Y440695D01*
X-1124487D01*
G01X-1146537Y448938D02*
Y455138D01*
X-1144621D01*
X-1144007Y454828D01*
X-1143624Y454415D01*
X-1143471Y453588D01*
X-1143624Y452761D01*
X-1144084Y452245D01*
X-1144621Y451935D01*
X-1146537D01*
G01X-1144621D02*
X-1143471Y448938D01*
G01X-1140491Y450178D02*
X-1140031Y449455D01*
X-1139417Y449041D01*
X-1138727Y448938D01*
X-1138114Y449041D01*
X-1137501Y449558D01*
X-1137117Y450178D01*
X-1137041Y450798D01*
X-1137194Y451521D01*
X-1137731Y452038D01*
X-1138267Y452245D01*
X-1138957D01*
G01X-1138267D02*
X-1137807Y452555D01*
X-1137424Y453071D01*
X-1137271Y453691D01*
X-1137424Y454311D01*
X-1137807Y454828D01*
X-1138497Y455138D01*
X-1139187Y455035D01*
X-1139877Y454621D01*
G01X-1134061Y454105D02*
X-1133601Y454725D01*
X-1133064Y455035D01*
X-1132451Y455138D01*
X-1131684Y454931D01*
X-1131147Y454415D01*
X-1130994Y453795D01*
X-1131071Y453175D01*
X-1131377Y452658D01*
X-1132911Y451625D01*
X-1133601Y450901D01*
X-1134061Y449868D01*
X-1134214Y448938D01*
X-1130994D01*
G01X-1128091Y450178D02*
X-1127631Y449455D01*
X-1127017Y449041D01*
X-1126327Y448938D01*
X-1125714Y449041D01*
X-1125101Y449558D01*
X-1124717Y450178D01*
X-1124641Y450798D01*
X-1124794Y451521D01*
X-1125331Y452038D01*
X-1125867Y452245D01*
X-1126557D01*
G01X-1125867D02*
X-1125407Y452555D01*
X-1125024Y453071D01*
X-1124871Y453691D01*
X-1125024Y454311D01*
X-1125407Y454828D01*
X-1126097Y455138D01*
X-1126787Y455035D01*
X-1127477Y454621D01*
G01X-1146537Y459970D02*
Y466170D01*
X-1144621D01*
X-1144007Y465860D01*
X-1143624Y465447D01*
X-1143471Y464620D01*
X-1143624Y463793D01*
X-1144084Y463277D01*
X-1144621Y462967D01*
X-1146537D01*
G01X-1144621D02*
X-1143471Y459970D01*
G01X-1140491Y461210D02*
X-1140031Y460487D01*
X-1139417Y460073D01*
X-1138727Y459970D01*
X-1138114Y460073D01*
X-1137501Y460590D01*
X-1137117Y461210D01*
X-1137041Y461830D01*
X-1137194Y462553D01*
X-1137731Y463070D01*
X-1138267Y463277D01*
X-1138957D01*
G01X-1138267D02*
X-1137807Y463587D01*
X-1137424Y464103D01*
X-1137271Y464723D01*
X-1137424Y465343D01*
X-1137807Y465860D01*
X-1138497Y466170D01*
X-1139187Y466067D01*
X-1139877Y465653D01*
G01X-1134061Y462553D02*
X-1133524Y463277D01*
X-1133064Y463690D01*
X-1132451Y463897D01*
X-1131914Y463690D01*
X-1131531Y463277D01*
X-1131224Y462657D01*
X-1131147Y461933D01*
X-1131224Y461313D01*
X-1131531Y460693D01*
X-1131991Y460177D01*
X-1132527Y459970D01*
X-1133141Y460177D01*
X-1133677Y460796D01*
X-1133984Y461727D01*
X-1134061Y462760D01*
X-1133907Y464103D01*
X-1133677Y464827D01*
X-1133294Y465550D01*
X-1132757Y466067D01*
X-1132221Y466170D01*
X-1131684Y465963D01*
X-1131301Y465447D01*
G01X-1125484Y459970D02*
Y466170D01*
X-1128321Y461727D01*
X-1124487D01*
G01X-1148937Y458114D02*
X-1148784Y459457D01*
X-1148554Y460594D01*
X-1148247Y461627D01*
X-1147864Y462764D01*
X-1147251Y464314D01*
X-1150317D01*
G01X-1146537Y469970D02*
Y476170D01*
X-1144621D01*
X-1144007Y475860D01*
X-1143624Y475447D01*
X-1143471Y474620D01*
X-1143624Y473793D01*
X-1144084Y473277D01*
X-1144621Y472967D01*
X-1146537D01*
G01X-1144621D02*
X-1143471Y469970D01*
G01X-1140491Y471210D02*
X-1140031Y470487D01*
X-1139417Y470073D01*
X-1138727Y469970D01*
X-1138114Y470073D01*
X-1137501Y470590D01*
X-1137117Y471210D01*
X-1137041Y471830D01*
X-1137194Y472553D01*
X-1137731Y473070D01*
X-1138267Y473277D01*
X-1138957D01*
G01X-1138267D02*
X-1137807Y473587D01*
X-1137424Y474103D01*
X-1137271Y474723D01*
X-1137424Y475343D01*
X-1137807Y475860D01*
X-1138497Y476170D01*
X-1139187Y476067D01*
X-1139877Y475653D01*
G01X-1134061Y472553D02*
X-1133524Y473277D01*
X-1133064Y473690D01*
X-1132451Y473897D01*
X-1131914Y473690D01*
X-1131531Y473277D01*
X-1131224Y472657D01*
X-1131147Y471933D01*
X-1131224Y471313D01*
X-1131531Y470693D01*
X-1131991Y470177D01*
X-1132527Y469970D01*
X-1133141Y470177D01*
X-1133677Y470796D01*
X-1133984Y471727D01*
X-1134061Y472760D01*
X-1133907Y474103D01*
X-1133677Y474827D01*
X-1133294Y475550D01*
X-1132757Y476067D01*
X-1132221Y476170D01*
X-1131684Y475963D01*
X-1131301Y475447D01*
G01X-1127861Y472553D02*
X-1127324Y473277D01*
X-1126864Y473690D01*
X-1126251Y473897D01*
X-1125714Y473690D01*
X-1125331Y473277D01*
X-1125024Y472657D01*
X-1124947Y471933D01*
X-1125024Y471313D01*
X-1125331Y470693D01*
X-1125791Y470177D01*
X-1126327Y469970D01*
X-1126941Y470177D01*
X-1127477Y470796D01*
X-1127784Y471727D01*
X-1127861Y472760D01*
X-1127707Y474103D01*
X-1127477Y474827D01*
X-1127094Y475550D01*
X-1126557Y476067D01*
X-1126021Y476170D01*
X-1125484Y475963D01*
X-1125101Y475447D01*
G01X-1128537Y-160962D02*
Y-154762D01*
X-1126621D01*
X-1126007Y-155072D01*
X-1125624Y-155485D01*
X-1125471Y-156312D01*
X-1125624Y-157139D01*
X-1126084Y-157655D01*
X-1126621Y-157965D01*
X-1128537D01*
G01X-1126621D02*
X-1125471Y-160962D01*
G01X-1122261Y-155795D02*
X-1121801Y-155175D01*
X-1121264Y-154865D01*
X-1120651Y-154762D01*
X-1119884Y-154969D01*
X-1119347Y-155485D01*
X-1119194Y-156105D01*
X-1119271Y-156725D01*
X-1119577Y-157242D01*
X-1121111Y-158275D01*
X-1121801Y-158999D01*
X-1122261Y-160032D01*
X-1122414Y-160962D01*
X-1119194D01*
G01X-1113684D02*
Y-154762D01*
X-1116521Y-159205D01*
X-1112687D01*
G01X-1108404Y-160962D02*
Y-154762D01*
X-1109324Y-156002D01*
G01Y-160962D02*
X-1107484D01*
G01X-1130487Y-149175D02*
X-1130797Y-149635D01*
X-1131004Y-150172D01*
Y-150785D01*
X-1130694Y-151475D01*
X-1130177Y-152012D01*
X-1129557Y-152395D01*
X-1128524Y-152702D01*
X-1127594Y-152779D01*
X-1126664Y-152625D01*
X-1126044Y-152395D01*
X-1125424Y-151935D01*
X-1125011Y-151399D01*
X-1124804Y-150862D01*
Y-150325D01*
X-1125011Y-149789D01*
X-1125321Y-149329D01*
X-1125734Y-148945D01*
G01X-1129971Y-146119D02*
X-1130591Y-145659D01*
X-1130901Y-145122D01*
X-1131004Y-144509D01*
X-1130797Y-143742D01*
X-1130281Y-143205D01*
X-1129661Y-143052D01*
X-1129041Y-143129D01*
X-1128524Y-143435D01*
X-1127491Y-144969D01*
X-1126767Y-145659D01*
X-1125734Y-146119D01*
X-1124804Y-146272D01*
Y-143052D01*
G01X-1125734Y-140149D02*
X-1125217Y-139689D01*
X-1124907Y-139152D01*
X-1124804Y-138462D01*
X-1125011Y-137772D01*
X-1125424Y-137235D01*
X-1126147Y-136852D01*
X-1126974Y-136775D01*
X-1127801Y-136929D01*
X-1128317Y-137312D01*
X-1128731Y-137849D01*
X-1128834Y-138385D01*
X-1128731Y-138922D01*
X-1128317Y-139612D01*
X-1131004Y-139382D01*
Y-137312D01*
G01X-1124804Y-132262D02*
X-1131004D01*
X-1129764Y-133182D01*
G01X-1124804D02*
Y-131342D01*
G01X-1139487Y-149175D02*
X-1139797Y-149635D01*
X-1140004Y-150172D01*
Y-150785D01*
X-1139694Y-151475D01*
X-1139177Y-152012D01*
X-1138557Y-152395D01*
X-1137524Y-152702D01*
X-1136594Y-152779D01*
X-1135664Y-152625D01*
X-1135044Y-152395D01*
X-1134424Y-151935D01*
X-1134011Y-151399D01*
X-1133804Y-150862D01*
Y-150325D01*
X-1134011Y-149789D01*
X-1134321Y-149329D01*
X-1134734Y-148945D01*
G01X-1138971Y-146119D02*
X-1139591Y-145659D01*
X-1139901Y-145122D01*
X-1140004Y-144509D01*
X-1139797Y-143742D01*
X-1139281Y-143205D01*
X-1138661Y-143052D01*
X-1138041Y-143129D01*
X-1137524Y-143435D01*
X-1136491Y-144969D01*
X-1135767Y-145659D01*
X-1134734Y-146119D01*
X-1133804Y-146272D01*
Y-143052D01*
G01X-1134734Y-140149D02*
X-1134217Y-139689D01*
X-1133907Y-139152D01*
X-1133804Y-138462D01*
X-1134011Y-137772D01*
X-1134424Y-137235D01*
X-1135147Y-136852D01*
X-1135974Y-136775D01*
X-1136801Y-136929D01*
X-1137317Y-137312D01*
X-1137731Y-137849D01*
X-1137834Y-138385D01*
X-1137731Y-138922D01*
X-1137317Y-139612D01*
X-1140004Y-139382D01*
Y-137312D01*
G01X-1138971Y-133719D02*
X-1139591Y-133259D01*
X-1139901Y-132722D01*
X-1140004Y-132109D01*
X-1139797Y-131342D01*
X-1139281Y-130805D01*
X-1138661Y-130652D01*
X-1138041Y-130729D01*
X-1137524Y-131035D01*
X-1136491Y-132569D01*
X-1135767Y-133259D01*
X-1134734Y-133719D01*
X-1133804Y-133872D01*
Y-130652D01*
G01X-1132537Y-129062D02*
Y-122862D01*
X-1130621D01*
X-1130007Y-123172D01*
X-1129624Y-123585D01*
X-1129471Y-124412D01*
X-1129624Y-125239D01*
X-1130084Y-125755D01*
X-1130621Y-126065D01*
X-1132537D01*
G01X-1130621D02*
X-1129471Y-129062D01*
G01X-1126491Y-127822D02*
X-1126031Y-128545D01*
X-1125417Y-128959D01*
X-1124727Y-129062D01*
X-1124114Y-128959D01*
X-1123501Y-128442D01*
X-1123117Y-127822D01*
X-1123041Y-127202D01*
X-1123194Y-126479D01*
X-1123731Y-125962D01*
X-1124267Y-125755D01*
X-1124957D01*
G01X-1124267D02*
X-1123807Y-125445D01*
X-1123424Y-124929D01*
X-1123271Y-124309D01*
X-1123424Y-123689D01*
X-1123807Y-123172D01*
X-1124497Y-122862D01*
X-1125187Y-122965D01*
X-1125877Y-123379D01*
G01X-1120291Y-128132D02*
X-1119831Y-128649D01*
X-1119294Y-128959D01*
X-1118604Y-129062D01*
X-1117914Y-128855D01*
X-1117377Y-128442D01*
X-1116994Y-127719D01*
X-1116917Y-126892D01*
X-1117071Y-126065D01*
X-1117454Y-125549D01*
X-1117991Y-125135D01*
X-1118527Y-125032D01*
X-1119064Y-125135D01*
X-1119754Y-125549D01*
X-1119524Y-122862D01*
X-1117454D01*
G01X-1113707Y-128339D02*
X-1113171Y-128855D01*
X-1112557Y-129062D01*
X-1111944Y-128855D01*
X-1111407Y-128236D01*
X-1111024Y-127305D01*
X-1110871Y-126375D01*
Y-125239D01*
X-1111024Y-124309D01*
X-1111407Y-123482D01*
X-1111867Y-123069D01*
X-1112404Y-122862D01*
X-1113017Y-123069D01*
X-1113477Y-123482D01*
X-1113784Y-124102D01*
X-1113937Y-124929D01*
X-1113784Y-125652D01*
X-1113401Y-126375D01*
X-1112941Y-126789D01*
X-1112404Y-126892D01*
X-1111791Y-126685D01*
X-1111331Y-126169D01*
X-1110871Y-125239D01*
G01X-1118638Y-100995D02*
X-1124838D01*
Y-99079D01*
X-1124528Y-98465D01*
X-1124115Y-98082D01*
X-1123288Y-97929D01*
X-1122461Y-98082D01*
X-1121945Y-98542D01*
X-1121635Y-99079D01*
Y-100995D01*
G01Y-99079D02*
X-1118638Y-97929D01*
G01X-1127638Y-106995D02*
X-1133838D01*
Y-105155D01*
X-1133528Y-104542D01*
X-1132805Y-104082D01*
X-1131978Y-103929D01*
X-1131151Y-104082D01*
X-1130531Y-104465D01*
X-1130221Y-105155D01*
Y-106995D01*
G01X-1132638Y-101225D02*
X-1138838D01*
X-1132638Y-97699D01*
X-1138838D01*
G01X-1119604Y126205D02*
X-1125804D01*
Y128121D01*
X-1125494Y128735D01*
X-1125081Y129118D01*
X-1124254Y129271D01*
X-1123427Y129118D01*
X-1122911Y128658D01*
X-1122601Y128121D01*
Y126205D01*
G01Y128121D02*
X-1119604Y129271D01*
G01X-1124771Y132481D02*
X-1125391Y132941D01*
X-1125701Y133478D01*
X-1125804Y134091D01*
X-1125597Y134858D01*
X-1125081Y135395D01*
X-1124461Y135548D01*
X-1123841Y135471D01*
X-1123324Y135165D01*
X-1122291Y133631D01*
X-1121567Y132941D01*
X-1120534Y132481D01*
X-1119604Y132328D01*
Y135548D01*
G01Y140138D02*
X-1125804D01*
X-1124564Y139218D01*
G01X-1119604D02*
Y141058D01*
G01Y147258D02*
X-1125804D01*
X-1121361Y144421D01*
Y148255D01*
G01X-1128604Y126205D02*
X-1134804D01*
Y128121D01*
X-1134494Y128735D01*
X-1134081Y129118D01*
X-1133254Y129271D01*
X-1132427Y129118D01*
X-1131911Y128658D01*
X-1131601Y128121D01*
Y126205D01*
G01Y128121D02*
X-1128604Y129271D01*
G01X-1133771Y132481D02*
X-1134391Y132941D01*
X-1134701Y133478D01*
X-1134804Y134091D01*
X-1134597Y134858D01*
X-1134081Y135395D01*
X-1133461Y135548D01*
X-1132841Y135471D01*
X-1132324Y135165D01*
X-1131291Y133631D01*
X-1130567Y132941D01*
X-1129534Y132481D01*
X-1128604Y132328D01*
Y135548D01*
G01Y140138D02*
X-1134804D01*
X-1133564Y139218D01*
G01X-1128604D02*
Y141058D01*
G01X-1129844Y144651D02*
X-1129121Y145111D01*
X-1128707Y145725D01*
X-1128604Y146415D01*
X-1128707Y147028D01*
X-1129224Y147641D01*
X-1129844Y148025D01*
X-1130464Y148101D01*
X-1131187Y147948D01*
X-1131704Y147411D01*
X-1131911Y146875D01*
Y146185D01*
G01Y146875D02*
X-1132221Y147335D01*
X-1132737Y147718D01*
X-1133357Y147871D01*
X-1133977Y147718D01*
X-1134494Y147335D01*
X-1134804Y146645D01*
X-1134701Y145955D01*
X-1134287Y145265D01*
G01X-1135287Y185425D02*
X-1135597Y184965D01*
X-1135804Y184428D01*
Y183815D01*
X-1135494Y183125D01*
X-1134977Y182588D01*
X-1134357Y182205D01*
X-1133324Y181898D01*
X-1132394Y181821D01*
X-1131464Y181975D01*
X-1130844Y182205D01*
X-1130224Y182665D01*
X-1129811Y183201D01*
X-1129604Y183738D01*
Y184275D01*
X-1129811Y184811D01*
X-1130121Y185271D01*
X-1130534Y185655D01*
G01X-1134771Y188481D02*
X-1135391Y188941D01*
X-1135701Y189478D01*
X-1135804Y190091D01*
X-1135597Y190858D01*
X-1135081Y191395D01*
X-1134461Y191548D01*
X-1133841Y191471D01*
X-1133324Y191165D01*
X-1132291Y189631D01*
X-1131567Y188941D01*
X-1130534Y188481D01*
X-1129604Y188328D01*
Y191548D01*
G01X-1130844Y194451D02*
X-1130121Y194911D01*
X-1129707Y195525D01*
X-1129604Y196215D01*
X-1129707Y196828D01*
X-1130224Y197441D01*
X-1130844Y197825D01*
X-1131464Y197901D01*
X-1132187Y197748D01*
X-1132704Y197211D01*
X-1132911Y196675D01*
Y195985D01*
G01Y196675D02*
X-1133221Y197135D01*
X-1133737Y197518D01*
X-1134357Y197671D01*
X-1134977Y197518D01*
X-1135494Y197135D01*
X-1135804Y196445D01*
X-1135701Y195755D01*
X-1135287Y195065D01*
G01X-1130844Y200651D02*
X-1130121Y201111D01*
X-1129707Y201725D01*
X-1129604Y202415D01*
X-1129707Y203028D01*
X-1130224Y203641D01*
X-1130844Y204025D01*
X-1131464Y204101D01*
X-1132187Y203948D01*
X-1132704Y203411D01*
X-1132911Y202875D01*
Y202185D01*
G01Y202875D02*
X-1133221Y203335D01*
X-1133737Y203718D01*
X-1134357Y203871D01*
X-1134977Y203718D01*
X-1135494Y203335D01*
X-1135804Y202645D01*
X-1135701Y201955D01*
X-1135287Y201265D01*
G01X-1124804Y302938D02*
Y309138D01*
X-1125724Y307898D01*
G01Y302938D02*
X-1123884D01*
G01X-1120061Y305521D02*
X-1119524Y306245D01*
X-1119064Y306658D01*
X-1118451Y306865D01*
X-1117914Y306658D01*
X-1117531Y306245D01*
X-1117224Y305625D01*
X-1117147Y304901D01*
X-1117224Y304281D01*
X-1117531Y303661D01*
X-1117991Y303145D01*
X-1118527Y302938D01*
X-1119141Y303145D01*
X-1119677Y303764D01*
X-1119984Y304695D01*
X-1120061Y305728D01*
X-1119907Y307071D01*
X-1119677Y307795D01*
X-1119294Y308518D01*
X-1118757Y309035D01*
X-1118221Y309138D01*
X-1117684Y308931D01*
X-1117301Y308415D01*
G01X-1126804Y361972D02*
X-1127417Y362075D01*
X-1127954Y362489D01*
X-1128414Y363109D01*
X-1128721Y363832D01*
X-1128874Y364659D01*
Y365485D01*
X-1128721Y366312D01*
X-1128414Y367035D01*
X-1127954Y367655D01*
X-1127417Y368069D01*
X-1126804Y368172D01*
X-1126191Y368069D01*
X-1125654Y367655D01*
X-1125194Y367035D01*
X-1124887Y366312D01*
X-1124734Y365485D01*
Y364659D01*
X-1124887Y363832D01*
X-1125194Y363109D01*
X-1125654Y362489D01*
X-1126191Y362075D01*
X-1126804Y361972D01*
G01X-1126191Y363625D02*
X-1125271Y361972D01*
G01X-1120604D02*
Y368172D01*
X-1121524Y366932D01*
G01Y361972D02*
X-1119684D01*
G01X-1138537Y385970D02*
Y392170D01*
X-1136621D01*
X-1136007Y391860D01*
X-1135624Y391447D01*
X-1135471Y390620D01*
X-1135624Y389793D01*
X-1136084Y389277D01*
X-1136621Y388967D01*
X-1138537D01*
G01X-1136621D02*
X-1135471Y385970D01*
G01X-1129884D02*
Y392170D01*
X-1132721Y387727D01*
X-1128887D01*
G01X-1126291Y386900D02*
X-1125831Y386383D01*
X-1125294Y386073D01*
X-1124604Y385970D01*
X-1123914Y386177D01*
X-1123377Y386590D01*
X-1122994Y387313D01*
X-1122917Y388140D01*
X-1123071Y388967D01*
X-1123454Y389483D01*
X-1123991Y389897D01*
X-1124527Y390000D01*
X-1125064Y389897D01*
X-1125754Y389483D01*
X-1125524Y392170D01*
X-1123454D01*
G01X-1119861Y391137D02*
X-1119401Y391757D01*
X-1118864Y392067D01*
X-1118251Y392170D01*
X-1117484Y391963D01*
X-1116947Y391447D01*
X-1116794Y390827D01*
X-1116871Y390207D01*
X-1117177Y389690D01*
X-1118711Y388657D01*
X-1119401Y387933D01*
X-1119861Y386900D01*
X-1120014Y385970D01*
X-1116794D01*
G01X-1138537Y394970D02*
Y401170D01*
X-1136621D01*
X-1136007Y400860D01*
X-1135624Y400447D01*
X-1135471Y399620D01*
X-1135624Y398793D01*
X-1136084Y398277D01*
X-1136621Y397967D01*
X-1138537D01*
G01X-1136621D02*
X-1135471Y394970D01*
G01X-1129884D02*
Y401170D01*
X-1132721Y396727D01*
X-1128887D01*
G01X-1126291Y395900D02*
X-1125831Y395383D01*
X-1125294Y395073D01*
X-1124604Y394970D01*
X-1123914Y395177D01*
X-1123377Y395590D01*
X-1122994Y396313D01*
X-1122917Y397140D01*
X-1123071Y397967D01*
X-1123454Y398483D01*
X-1123991Y398897D01*
X-1124527Y399000D01*
X-1125064Y398897D01*
X-1125754Y398483D01*
X-1125524Y401170D01*
X-1123454D01*
G01X-1120091Y396210D02*
X-1119631Y395487D01*
X-1119017Y395073D01*
X-1118327Y394970D01*
X-1117714Y395073D01*
X-1117101Y395590D01*
X-1116717Y396210D01*
X-1116641Y396830D01*
X-1116794Y397553D01*
X-1117331Y398070D01*
X-1117867Y398277D01*
X-1118557D01*
G01X-1117867D02*
X-1117407Y398587D01*
X-1117024Y399103D01*
X-1116871Y399723D01*
X-1117024Y400343D01*
X-1117407Y400860D01*
X-1118097Y401170D01*
X-1118787Y401067D01*
X-1119477Y400653D01*
G01X-1132217Y410621D02*
X-1132677Y410931D01*
X-1133214Y411138D01*
X-1133827D01*
X-1134517Y410828D01*
X-1135054Y410311D01*
X-1135437Y409691D01*
X-1135744Y408658D01*
X-1135821Y407728D01*
X-1135667Y406798D01*
X-1135437Y406178D01*
X-1134977Y405558D01*
X-1134441Y405145D01*
X-1133904Y404938D01*
X-1133367D01*
X-1132831Y405145D01*
X-1132371Y405455D01*
X-1131987Y405868D01*
G01X-1127704Y404938D02*
X-1127167Y405041D01*
X-1126554Y405351D01*
X-1126171Y405868D01*
X-1126017Y406591D01*
X-1126171Y407315D01*
X-1126631Y407935D01*
X-1127321Y408245D01*
X-1128087D01*
X-1128547Y408451D01*
X-1128931Y408968D01*
X-1129084Y409691D01*
X-1128854Y410415D01*
X-1128317Y410931D01*
X-1127704Y411138D01*
X-1127091Y410931D01*
X-1126554Y410415D01*
X-1126324Y409691D01*
X-1126477Y408968D01*
X-1126861Y408451D01*
X-1127321Y408245D01*
X-1128087D01*
X-1128777Y407935D01*
X-1129237Y407315D01*
X-1129391Y406591D01*
X-1129237Y405868D01*
X-1128854Y405351D01*
X-1128241Y405041D01*
X-1127704Y404938D01*
G01X-1122807Y405661D02*
X-1122271Y405145D01*
X-1121657Y404938D01*
X-1121044Y405145D01*
X-1120507Y405764D01*
X-1120124Y406695D01*
X-1119971Y407625D01*
Y408761D01*
X-1120124Y409691D01*
X-1120507Y410518D01*
X-1120967Y410931D01*
X-1121504Y411138D01*
X-1122117Y410931D01*
X-1122577Y410518D01*
X-1122884Y409898D01*
X-1123037Y409071D01*
X-1122884Y408348D01*
X-1122501Y407625D01*
X-1122041Y407211D01*
X-1121504Y407108D01*
X-1120891Y407315D01*
X-1120431Y407831D01*
X-1119971Y408761D01*
G01X-1122391Y-199722D02*
X-1121931Y-200445D01*
X-1121317Y-200859D01*
X-1120627Y-200962D01*
X-1120014Y-200859D01*
X-1119401Y-200342D01*
X-1119017Y-199722D01*
X-1118941Y-199102D01*
X-1119094Y-198379D01*
X-1119631Y-197862D01*
X-1120167Y-197655D01*
X-1120857D01*
G01X-1120167D02*
X-1119707Y-197345D01*
X-1119324Y-196829D01*
X-1119171Y-196209D01*
X-1119324Y-195589D01*
X-1119707Y-195072D01*
X-1120397Y-194762D01*
X-1121087Y-194865D01*
X-1121777Y-195279D01*
G01X-1113784Y-168962D02*
Y-162762D01*
X-1116621Y-167205D01*
X-1112787D01*
G01X-1102636Y-129795D02*
X-1108836D01*
Y-127879D01*
X-1108526Y-127265D01*
X-1108113Y-126882D01*
X-1107286Y-126729D01*
X-1106459Y-126882D01*
X-1105943Y-127342D01*
X-1105633Y-127879D01*
Y-129795D01*
G01Y-127879D02*
X-1102636Y-126729D01*
G01Y-121142D02*
X-1108836D01*
X-1104393Y-123979D01*
Y-120145D01*
G01X-1103876Y-117549D02*
X-1103153Y-117089D01*
X-1102739Y-116475D01*
X-1102636Y-115785D01*
X-1102739Y-115172D01*
X-1103256Y-114559D01*
X-1103876Y-114175D01*
X-1104496Y-114099D01*
X-1105219Y-114252D01*
X-1105736Y-114789D01*
X-1105943Y-115325D01*
Y-116015D01*
G01Y-115325D02*
X-1106253Y-114865D01*
X-1106769Y-114482D01*
X-1107389Y-114329D01*
X-1108009Y-114482D01*
X-1108526Y-114865D01*
X-1108836Y-115555D01*
X-1108733Y-116245D01*
X-1108319Y-116935D01*
G01X-1103359Y-110965D02*
X-1102843Y-110429D01*
X-1102636Y-109815D01*
X-1102843Y-109202D01*
X-1103462Y-108665D01*
X-1104393Y-108282D01*
X-1105323Y-108129D01*
X-1106459D01*
X-1107389Y-108282D01*
X-1108216Y-108665D01*
X-1108629Y-109125D01*
X-1108836Y-109662D01*
X-1108629Y-110275D01*
X-1108216Y-110735D01*
X-1107596Y-111042D01*
X-1106769Y-111195D01*
X-1106046Y-111042D01*
X-1105323Y-110659D01*
X-1104909Y-110199D01*
X-1104806Y-109662D01*
X-1105013Y-109049D01*
X-1105529Y-108589D01*
X-1106459Y-108129D01*
G01X-1118838Y-105462D02*
X-1112638D01*
G01X-1118838Y-107225D02*
Y-103699D01*
G01X-1111838Y-101149D02*
X-1107395D01*
X-1106464Y-100842D01*
X-1105845Y-100229D01*
X-1105638Y-99462D01*
X-1105845Y-98695D01*
X-1106464Y-98082D01*
X-1107395Y-97775D01*
X-1111838D01*
G01X-1100604Y102205D02*
X-1106804D01*
Y104121D01*
X-1106494Y104735D01*
X-1106081Y105118D01*
X-1105254Y105271D01*
X-1104427Y105118D01*
X-1103911Y104658D01*
X-1103601Y104121D01*
Y102205D01*
G01Y104121D02*
X-1100604Y105271D01*
G01X-1105771Y108481D02*
X-1106391Y108941D01*
X-1106701Y109478D01*
X-1106804Y110091D01*
X-1106597Y110858D01*
X-1106081Y111395D01*
X-1105461Y111548D01*
X-1104841Y111471D01*
X-1104324Y111165D01*
X-1103291Y109631D01*
X-1102567Y108941D01*
X-1101534Y108481D01*
X-1100604Y108328D01*
Y111548D01*
G01X-1101844Y114451D02*
X-1101121Y114911D01*
X-1100707Y115525D01*
X-1100604Y116215D01*
X-1100707Y116828D01*
X-1101224Y117441D01*
X-1101844Y117825D01*
X-1102464Y117901D01*
X-1103187Y117748D01*
X-1103704Y117211D01*
X-1103911Y116675D01*
Y115985D01*
G01Y116675D02*
X-1104221Y117135D01*
X-1104737Y117518D01*
X-1105357Y117671D01*
X-1105977Y117518D01*
X-1106494Y117135D01*
X-1106804Y116445D01*
X-1106701Y115755D01*
X-1106287Y115065D01*
G01X-1100604Y122338D02*
X-1100707Y122875D01*
X-1101017Y123488D01*
X-1101534Y123871D01*
X-1102257Y124025D01*
X-1102981Y123871D01*
X-1103601Y123411D01*
X-1103911Y122721D01*
Y121955D01*
X-1104117Y121495D01*
X-1104634Y121111D01*
X-1105357Y120958D01*
X-1106081Y121188D01*
X-1106597Y121725D01*
X-1106804Y122338D01*
X-1106597Y122951D01*
X-1106081Y123488D01*
X-1105357Y123718D01*
X-1104634Y123565D01*
X-1104117Y123181D01*
X-1103911Y122721D01*
Y121955D01*
X-1103601Y121265D01*
X-1102981Y120805D01*
X-1102257Y120651D01*
X-1101534Y120805D01*
X-1101017Y121188D01*
X-1100707Y121801D01*
X-1100604Y122338D01*
G01X-1102636Y126205D02*
X-1108836D01*
Y128121D01*
X-1108526Y128735D01*
X-1108113Y129118D01*
X-1107286Y129271D01*
X-1106459Y129118D01*
X-1105943Y128658D01*
X-1105633Y128121D01*
Y126205D01*
G01Y128121D02*
X-1102636Y129271D01*
G01X-1103876Y132251D02*
X-1103153Y132711D01*
X-1102739Y133325D01*
X-1102636Y134015D01*
X-1102739Y134628D01*
X-1103256Y135241D01*
X-1103876Y135625D01*
X-1104496Y135701D01*
X-1105219Y135548D01*
X-1105736Y135011D01*
X-1105943Y134475D01*
Y133785D01*
G01Y134475D02*
X-1106253Y134935D01*
X-1106769Y135318D01*
X-1107389Y135471D01*
X-1108009Y135318D01*
X-1108526Y134935D01*
X-1108836Y134245D01*
X-1108733Y133555D01*
X-1108319Y132865D01*
G01X-1103876Y138451D02*
X-1103153Y138911D01*
X-1102739Y139525D01*
X-1102636Y140215D01*
X-1102739Y140828D01*
X-1103256Y141441D01*
X-1103876Y141825D01*
X-1104496Y141901D01*
X-1105219Y141748D01*
X-1105736Y141211D01*
X-1105943Y140675D01*
Y139985D01*
G01Y140675D02*
X-1106253Y141135D01*
X-1106769Y141518D01*
X-1107389Y141671D01*
X-1108009Y141518D01*
X-1108526Y141135D01*
X-1108836Y140445D01*
X-1108733Y139755D01*
X-1108319Y139065D01*
G01X-1103359Y145035D02*
X-1102843Y145571D01*
X-1102636Y146185D01*
X-1102843Y146798D01*
X-1103462Y147335D01*
X-1104393Y147718D01*
X-1105323Y147871D01*
X-1106459D01*
X-1107389Y147718D01*
X-1108216Y147335D01*
X-1108629Y146875D01*
X-1108836Y146338D01*
X-1108629Y145725D01*
X-1108216Y145265D01*
X-1107596Y144958D01*
X-1106769Y144805D01*
X-1106046Y144958D01*
X-1105323Y145341D01*
X-1104909Y145801D01*
X-1104806Y146338D01*
X-1105013Y146951D01*
X-1105529Y147411D01*
X-1106459Y147871D01*
G01X-1111636Y126205D02*
X-1117836D01*
Y128121D01*
X-1117526Y128735D01*
X-1117113Y129118D01*
X-1116286Y129271D01*
X-1115459Y129118D01*
X-1114943Y128658D01*
X-1114633Y128121D01*
Y126205D01*
G01Y128121D02*
X-1111636Y129271D01*
G01X-1116803Y132481D02*
X-1117423Y132941D01*
X-1117733Y133478D01*
X-1117836Y134091D01*
X-1117629Y134858D01*
X-1117113Y135395D01*
X-1116493Y135548D01*
X-1115873Y135471D01*
X-1115356Y135165D01*
X-1114323Y133631D01*
X-1113599Y132941D01*
X-1112566Y132481D01*
X-1111636Y132328D01*
Y135548D01*
G01X-1112876Y138451D02*
X-1112153Y138911D01*
X-1111739Y139525D01*
X-1111636Y140215D01*
X-1111739Y140828D01*
X-1112256Y141441D01*
X-1112876Y141825D01*
X-1113496Y141901D01*
X-1114219Y141748D01*
X-1114736Y141211D01*
X-1114943Y140675D01*
Y139985D01*
G01Y140675D02*
X-1115253Y141135D01*
X-1115769Y141518D01*
X-1116389Y141671D01*
X-1117009Y141518D01*
X-1117526Y141135D01*
X-1117836Y140445D01*
X-1117733Y139755D01*
X-1117319Y139065D01*
G01X-1111636Y147258D02*
X-1117836D01*
X-1113393Y144421D01*
Y148255D01*
G01X-1122287Y182425D02*
X-1122597Y181965D01*
X-1122804Y181428D01*
Y180815D01*
X-1122494Y180125D01*
X-1121977Y179588D01*
X-1121357Y179205D01*
X-1120324Y178898D01*
X-1119394Y178821D01*
X-1118464Y178975D01*
X-1117844Y179205D01*
X-1117224Y179665D01*
X-1116811Y180201D01*
X-1116604Y180738D01*
Y181275D01*
X-1116811Y181811D01*
X-1117121Y182271D01*
X-1117534Y182655D01*
G01X-1121771Y185481D02*
X-1122391Y185941D01*
X-1122701Y186478D01*
X-1122804Y187091D01*
X-1122597Y187858D01*
X-1122081Y188395D01*
X-1121461Y188548D01*
X-1120841Y188471D01*
X-1120324Y188165D01*
X-1119291Y186631D01*
X-1118567Y185941D01*
X-1117534Y185481D01*
X-1116604Y185328D01*
Y188548D01*
G01X-1117844Y191451D02*
X-1117121Y191911D01*
X-1116707Y192525D01*
X-1116604Y193215D01*
X-1116707Y193828D01*
X-1117224Y194441D01*
X-1117844Y194825D01*
X-1118464Y194901D01*
X-1119187Y194748D01*
X-1119704Y194211D01*
X-1119911Y193675D01*
Y192985D01*
G01Y193675D02*
X-1120221Y194135D01*
X-1120737Y194518D01*
X-1121357Y194671D01*
X-1121977Y194518D01*
X-1122494Y194135D01*
X-1122804Y193445D01*
X-1122701Y192755D01*
X-1122287Y192065D01*
G01X-1121771Y197881D02*
X-1122391Y198341D01*
X-1122701Y198878D01*
X-1122804Y199491D01*
X-1122597Y200258D01*
X-1122081Y200795D01*
X-1121461Y200948D01*
X-1120841Y200871D01*
X-1120324Y200565D01*
X-1119291Y199031D01*
X-1118567Y198341D01*
X-1117534Y197881D01*
X-1116604Y197728D01*
Y200948D01*
G01X-1112537Y215970D02*
Y222170D01*
X-1110621D01*
X-1110007Y221860D01*
X-1109624Y221447D01*
X-1109471Y220620D01*
X-1109624Y219793D01*
X-1110084Y219277D01*
X-1110621Y218967D01*
X-1112537D01*
G01X-1110621D02*
X-1109471Y215970D01*
G01X-1106261Y221137D02*
X-1105801Y221757D01*
X-1105264Y222067D01*
X-1104651Y222170D01*
X-1103884Y221963D01*
X-1103347Y221447D01*
X-1103194Y220827D01*
X-1103271Y220207D01*
X-1103577Y219690D01*
X-1105111Y218657D01*
X-1105801Y217933D01*
X-1106261Y216900D01*
X-1106414Y215970D01*
X-1103194D01*
G01X-1100291Y217210D02*
X-1099831Y216487D01*
X-1099217Y216073D01*
X-1098527Y215970D01*
X-1097914Y216073D01*
X-1097301Y216590D01*
X-1096917Y217210D01*
X-1096841Y217830D01*
X-1096994Y218553D01*
X-1097531Y219070D01*
X-1098067Y219277D01*
X-1098757D01*
G01X-1098067D02*
X-1097607Y219587D01*
X-1097224Y220103D01*
X-1097071Y220723D01*
X-1097224Y221343D01*
X-1097607Y221860D01*
X-1098297Y222170D01*
X-1098987Y222067D01*
X-1099677Y221653D01*
G01X-1092557Y215970D02*
X-1092404Y217313D01*
X-1092174Y218450D01*
X-1091867Y219483D01*
X-1091484Y220620D01*
X-1090871Y222170D01*
X-1093937D01*
G01X-1119237Y235199D02*
X-1118700Y235923D01*
X-1118240Y236336D01*
X-1117627Y236543D01*
X-1117090Y236336D01*
X-1116707Y235923D01*
X-1116400Y235303D01*
X-1116323Y234579D01*
X-1116400Y233959D01*
X-1116707Y233339D01*
X-1117167Y232823D01*
X-1117703Y232616D01*
X-1118317Y232823D01*
X-1118853Y233442D01*
X-1119160Y234373D01*
X-1119237Y235406D01*
X-1119083Y236749D01*
X-1118853Y237473D01*
X-1118470Y238196D01*
X-1117933Y238713D01*
X-1117397Y238816D01*
X-1116860Y238609D01*
X-1116477Y238093D01*
G01X-1109317Y240621D02*
X-1109777Y240931D01*
X-1110314Y241138D01*
X-1110927D01*
X-1111617Y240828D01*
X-1112154Y240311D01*
X-1112537Y239691D01*
X-1112844Y238658D01*
X-1112921Y237728D01*
X-1112767Y236798D01*
X-1112537Y236178D01*
X-1112077Y235558D01*
X-1111541Y235145D01*
X-1111004Y234938D01*
X-1110467D01*
X-1109931Y235145D01*
X-1109471Y235455D01*
X-1109087Y235868D01*
G01X-1106261Y240105D02*
X-1105801Y240725D01*
X-1105264Y241035D01*
X-1104651Y241138D01*
X-1103884Y240931D01*
X-1103347Y240415D01*
X-1103194Y239795D01*
X-1103271Y239175D01*
X-1103577Y238658D01*
X-1105111Y237625D01*
X-1105801Y236901D01*
X-1106261Y235868D01*
X-1106414Y234938D01*
X-1103194D01*
G01X-1100291Y236178D02*
X-1099831Y235455D01*
X-1099217Y235041D01*
X-1098527Y234938D01*
X-1097914Y235041D01*
X-1097301Y235558D01*
X-1096917Y236178D01*
X-1096841Y236798D01*
X-1096994Y237521D01*
X-1097531Y238038D01*
X-1098067Y238245D01*
X-1098757D01*
G01X-1098067D02*
X-1097607Y238555D01*
X-1097224Y239071D01*
X-1097071Y239691D01*
X-1097224Y240311D01*
X-1097607Y240828D01*
X-1098297Y241138D01*
X-1098987Y241035D01*
X-1099677Y240621D01*
G01X-1093861Y237521D02*
X-1093324Y238245D01*
X-1092864Y238658D01*
X-1092251Y238865D01*
X-1091714Y238658D01*
X-1091331Y238245D01*
X-1091024Y237625D01*
X-1090947Y236901D01*
X-1091024Y236281D01*
X-1091331Y235661D01*
X-1091791Y235145D01*
X-1092327Y234938D01*
X-1092941Y235145D01*
X-1093477Y235764D01*
X-1093784Y236695D01*
X-1093861Y237728D01*
X-1093707Y239071D01*
X-1093477Y239795D01*
X-1093094Y240518D01*
X-1092557Y241035D01*
X-1092021Y241138D01*
X-1091484Y240931D01*
X-1091101Y240415D01*
G01X-1109317Y230621D02*
X-1109777Y230931D01*
X-1110314Y231138D01*
X-1110927D01*
X-1111617Y230828D01*
X-1112154Y230311D01*
X-1112537Y229691D01*
X-1112844Y228658D01*
X-1112921Y227728D01*
X-1112767Y226798D01*
X-1112537Y226178D01*
X-1112077Y225558D01*
X-1111541Y225145D01*
X-1111004Y224938D01*
X-1110467D01*
X-1109931Y225145D01*
X-1109471Y225455D01*
X-1109087Y225868D01*
G01X-1106261Y230105D02*
X-1105801Y230725D01*
X-1105264Y231035D01*
X-1104651Y231138D01*
X-1103884Y230931D01*
X-1103347Y230415D01*
X-1103194Y229795D01*
X-1103271Y229175D01*
X-1103577Y228658D01*
X-1105111Y227625D01*
X-1105801Y226901D01*
X-1106261Y225868D01*
X-1106414Y224938D01*
X-1103194D01*
G01X-1100291Y226178D02*
X-1099831Y225455D01*
X-1099217Y225041D01*
X-1098527Y224938D01*
X-1097914Y225041D01*
X-1097301Y225558D01*
X-1096917Y226178D01*
X-1096841Y226798D01*
X-1096994Y227521D01*
X-1097531Y228038D01*
X-1098067Y228245D01*
X-1098757D01*
G01X-1098067D02*
X-1097607Y228555D01*
X-1097224Y229071D01*
X-1097071Y229691D01*
X-1097224Y230311D01*
X-1097607Y230828D01*
X-1098297Y231138D01*
X-1098987Y231035D01*
X-1099677Y230621D01*
G01X-1094091Y225868D02*
X-1093631Y225351D01*
X-1093094Y225041D01*
X-1092404Y224938D01*
X-1091714Y225145D01*
X-1091177Y225558D01*
X-1090794Y226281D01*
X-1090717Y227108D01*
X-1090871Y227935D01*
X-1091254Y228451D01*
X-1091791Y228865D01*
X-1092327Y228968D01*
X-1092864Y228865D01*
X-1093554Y228451D01*
X-1093324Y231138D01*
X-1091254D01*
G01X-1112537Y244938D02*
Y251138D01*
X-1110621D01*
X-1110007Y250828D01*
X-1109624Y250415D01*
X-1109471Y249588D01*
X-1109624Y248761D01*
X-1110084Y248245D01*
X-1110621Y247935D01*
X-1112537D01*
G01X-1110621D02*
X-1109471Y244938D01*
G01X-1104804D02*
Y251138D01*
X-1105724Y249898D01*
G01Y244938D02*
X-1103884D01*
G01X-1097684D02*
Y251138D01*
X-1100521Y246695D01*
X-1096687D01*
G01X-1094091Y246178D02*
X-1093631Y245455D01*
X-1093017Y245041D01*
X-1092327Y244938D01*
X-1091714Y245041D01*
X-1091101Y245558D01*
X-1090717Y246178D01*
X-1090641Y246798D01*
X-1090794Y247521D01*
X-1091331Y248038D01*
X-1091867Y248245D01*
X-1092557D01*
G01X-1091867D02*
X-1091407Y248555D01*
X-1091024Y249071D01*
X-1090871Y249691D01*
X-1091024Y250311D01*
X-1091407Y250828D01*
X-1092097Y251138D01*
X-1092787Y251035D01*
X-1093477Y250621D01*
G01X-1118407Y259961D02*
X-1117871Y259445D01*
X-1117257Y259238D01*
X-1116644Y259445D01*
X-1116107Y260064D01*
X-1115724Y260995D01*
X-1115571Y261925D01*
Y263061D01*
X-1115724Y263991D01*
X-1116107Y264818D01*
X-1116567Y265231D01*
X-1117104Y265438D01*
X-1117717Y265231D01*
X-1118177Y264818D01*
X-1118484Y264198D01*
X-1118637Y263371D01*
X-1118484Y262648D01*
X-1118101Y261925D01*
X-1117641Y261511D01*
X-1117104Y261408D01*
X-1116491Y261615D01*
X-1116031Y262131D01*
X-1115571Y263061D01*
G01X-1114937Y290970D02*
Y297170D01*
X-1113021D01*
X-1112407Y296860D01*
X-1112024Y296447D01*
X-1111871Y295620D01*
X-1112024Y294793D01*
X-1112484Y294277D01*
X-1113021Y293967D01*
X-1114937D01*
G01X-1113021D02*
X-1111871Y290970D01*
G01X-1106284D02*
Y297170D01*
X-1109121Y292727D01*
X-1105287D01*
G01X-1102691Y291900D02*
X-1102231Y291383D01*
X-1101694Y291073D01*
X-1101004Y290970D01*
X-1100314Y291177D01*
X-1099777Y291590D01*
X-1099394Y292313D01*
X-1099317Y293140D01*
X-1099471Y293967D01*
X-1099854Y294483D01*
X-1100391Y294897D01*
X-1100927Y295000D01*
X-1101464Y294897D01*
X-1102154Y294483D01*
X-1101924Y297170D01*
X-1099854D01*
G01X-1096107Y291693D02*
X-1095571Y291177D01*
X-1094957Y290970D01*
X-1094344Y291177D01*
X-1093807Y291796D01*
X-1093424Y292727D01*
X-1093271Y293657D01*
Y294793D01*
X-1093424Y295723D01*
X-1093807Y296550D01*
X-1094267Y296963D01*
X-1094804Y297170D01*
X-1095417Y296963D01*
X-1095877Y296550D01*
X-1096184Y295930D01*
X-1096337Y295103D01*
X-1096184Y294380D01*
X-1095801Y293657D01*
X-1095341Y293243D01*
X-1094804Y293140D01*
X-1094191Y293347D01*
X-1093731Y293863D01*
X-1093271Y294793D01*
G01X-1109217Y306653D02*
X-1109677Y306963D01*
X-1110214Y307170D01*
X-1110827D01*
X-1111517Y306860D01*
X-1112054Y306343D01*
X-1112437Y305723D01*
X-1112744Y304690D01*
X-1112821Y303760D01*
X-1112667Y302830D01*
X-1112437Y302210D01*
X-1111977Y301590D01*
X-1111441Y301177D01*
X-1110904Y300970D01*
X-1110367D01*
X-1109831Y301177D01*
X-1109371Y301487D01*
X-1108987Y301900D01*
G01X-1106007Y301693D02*
X-1105471Y301177D01*
X-1104857Y300970D01*
X-1104244Y301177D01*
X-1103707Y301796D01*
X-1103324Y302727D01*
X-1103171Y303657D01*
Y304793D01*
X-1103324Y305723D01*
X-1103707Y306550D01*
X-1104167Y306963D01*
X-1104704Y307170D01*
X-1105317Y306963D01*
X-1105777Y306550D01*
X-1106084Y305930D01*
X-1106237Y305103D01*
X-1106084Y304380D01*
X-1105701Y303657D01*
X-1105241Y303243D01*
X-1104704Y303140D01*
X-1104091Y303347D01*
X-1103631Y303863D01*
X-1103171Y304793D01*
G01X-1098657Y300970D02*
X-1098504Y302313D01*
X-1098274Y303450D01*
X-1097967Y304483D01*
X-1097584Y305620D01*
X-1096971Y307170D01*
X-1100037D01*
G01X-1117827Y345283D02*
X-1117367Y345903D01*
X-1116830Y346213D01*
X-1116217Y346316D01*
X-1115450Y346109D01*
X-1114913Y345593D01*
X-1114760Y344973D01*
X-1114837Y344353D01*
X-1115143Y343836D01*
X-1116677Y342803D01*
X-1117367Y342079D01*
X-1117827Y341046D01*
X-1117980Y340116D01*
X-1114760D01*
G01X-1107287Y418525D02*
X-1107597Y418065D01*
X-1107804Y417528D01*
Y416915D01*
X-1107494Y416225D01*
X-1106977Y415688D01*
X-1106357Y415305D01*
X-1105324Y414998D01*
X-1104394Y414921D01*
X-1103464Y415075D01*
X-1102844Y415305D01*
X-1102224Y415765D01*
X-1101811Y416301D01*
X-1101604Y416838D01*
Y417375D01*
X-1101811Y417911D01*
X-1102121Y418371D01*
X-1102534Y418755D01*
G01X-1101604Y423038D02*
X-1101707Y423575D01*
X-1102017Y424188D01*
X-1102534Y424571D01*
X-1103257Y424725D01*
X-1103981Y424571D01*
X-1104601Y424111D01*
X-1104911Y423421D01*
Y422655D01*
X-1105117Y422195D01*
X-1105634Y421811D01*
X-1106357Y421658D01*
X-1107081Y421888D01*
X-1107597Y422425D01*
X-1107804Y423038D01*
X-1107597Y423651D01*
X-1107081Y424188D01*
X-1106357Y424418D01*
X-1105634Y424265D01*
X-1105117Y423881D01*
X-1104911Y423421D01*
Y422655D01*
X-1104601Y421965D01*
X-1103981Y421505D01*
X-1103257Y421351D01*
X-1102534Y421505D01*
X-1102017Y421888D01*
X-1101707Y422501D01*
X-1101604Y423038D01*
G01Y429238D02*
X-1107804D01*
X-1106564Y428318D01*
G01X-1101604D02*
Y430158D01*
G01X-1091636Y-129795D02*
X-1097836D01*
Y-127879D01*
X-1097526Y-127265D01*
X-1097113Y-126882D01*
X-1096286Y-126729D01*
X-1095459Y-126882D01*
X-1094943Y-127342D01*
X-1094633Y-127879D01*
Y-129795D01*
G01Y-127879D02*
X-1091636Y-126729D01*
G01Y-121142D02*
X-1097836D01*
X-1093393Y-123979D01*
Y-120145D01*
G01X-1092876Y-117549D02*
X-1092153Y-117089D01*
X-1091739Y-116475D01*
X-1091636Y-115785D01*
X-1091739Y-115172D01*
X-1092256Y-114559D01*
X-1092876Y-114175D01*
X-1093496Y-114099D01*
X-1094219Y-114252D01*
X-1094736Y-114789D01*
X-1094943Y-115325D01*
Y-116015D01*
G01Y-115325D02*
X-1095253Y-114865D01*
X-1095769Y-114482D01*
X-1096389Y-114329D01*
X-1097009Y-114482D01*
X-1097526Y-114865D01*
X-1097836Y-115555D01*
X-1097733Y-116245D01*
X-1097319Y-116935D01*
G01X-1091636Y-109662D02*
X-1091739Y-109125D01*
X-1092049Y-108512D01*
X-1092566Y-108129D01*
X-1093289Y-107975D01*
X-1094013Y-108129D01*
X-1094633Y-108589D01*
X-1094943Y-109279D01*
Y-110045D01*
X-1095149Y-110505D01*
X-1095666Y-110889D01*
X-1096389Y-111042D01*
X-1097113Y-110812D01*
X-1097629Y-110275D01*
X-1097836Y-109662D01*
X-1097629Y-109049D01*
X-1097113Y-108512D01*
X-1096389Y-108282D01*
X-1095666Y-108435D01*
X-1095149Y-108819D01*
X-1094943Y-109279D01*
Y-110045D01*
X-1094633Y-110735D01*
X-1094013Y-111195D01*
X-1093289Y-111349D01*
X-1092566Y-111195D01*
X-1092049Y-110812D01*
X-1091739Y-110199D01*
X-1091636Y-109662D01*
G01X-1083638Y-105462D02*
X-1086428D01*
X-1089838Y-106995D01*
G01Y-103929D02*
X-1086428Y-105462D01*
G01X-1095838Y-101762D02*
X-1089638Y-100689D01*
X-1095838Y-99462D01*
X-1089638Y-98235D01*
X-1095838Y-97162D01*
G01X-1103838Y-107379D02*
X-1097638Y-105462D01*
X-1103838Y-103545D01*
G01X-1084636Y126205D02*
X-1090836D01*
Y128121D01*
X-1090526Y128735D01*
X-1090113Y129118D01*
X-1089286Y129271D01*
X-1088459Y129118D01*
X-1087943Y128658D01*
X-1087633Y128121D01*
Y126205D01*
G01Y128121D02*
X-1084636Y129271D01*
G01X-1085876Y132251D02*
X-1085153Y132711D01*
X-1084739Y133325D01*
X-1084636Y134015D01*
X-1084739Y134628D01*
X-1085256Y135241D01*
X-1085876Y135625D01*
X-1086496Y135701D01*
X-1087219Y135548D01*
X-1087736Y135011D01*
X-1087943Y134475D01*
Y133785D01*
G01Y134475D02*
X-1088253Y134935D01*
X-1088769Y135318D01*
X-1089389Y135471D01*
X-1090009Y135318D01*
X-1090526Y134935D01*
X-1090836Y134245D01*
X-1090733Y133555D01*
X-1090319Y132865D01*
G01X-1084636Y141058D02*
X-1090836D01*
X-1086393Y138221D01*
Y142055D01*
G01X-1084636Y146338D02*
X-1084739Y146875D01*
X-1085049Y147488D01*
X-1085566Y147871D01*
X-1086289Y148025D01*
X-1087013Y147871D01*
X-1087633Y147411D01*
X-1087943Y146721D01*
Y145955D01*
X-1088149Y145495D01*
X-1088666Y145111D01*
X-1089389Y144958D01*
X-1090113Y145188D01*
X-1090629Y145725D01*
X-1090836Y146338D01*
X-1090629Y146951D01*
X-1090113Y147488D01*
X-1089389Y147718D01*
X-1088666Y147565D01*
X-1088149Y147181D01*
X-1087943Y146721D01*
Y145955D01*
X-1087633Y145265D01*
X-1087013Y144805D01*
X-1086289Y144651D01*
X-1085566Y144805D01*
X-1085049Y145188D01*
X-1084739Y145801D01*
X-1084636Y146338D01*
G01X-1093636Y126205D02*
X-1099836D01*
Y128121D01*
X-1099526Y128735D01*
X-1099113Y129118D01*
X-1098286Y129271D01*
X-1097459Y129118D01*
X-1096943Y128658D01*
X-1096633Y128121D01*
Y126205D01*
G01Y128121D02*
X-1093636Y129271D01*
G01Y134858D02*
X-1099836D01*
X-1095393Y132021D01*
Y135855D01*
G01X-1094876Y138451D02*
X-1094153Y138911D01*
X-1093739Y139525D01*
X-1093636Y140215D01*
X-1093739Y140828D01*
X-1094256Y141441D01*
X-1094876Y141825D01*
X-1095496Y141901D01*
X-1096219Y141748D01*
X-1096736Y141211D01*
X-1096943Y140675D01*
Y139985D01*
G01Y140675D02*
X-1097253Y141135D01*
X-1097769Y141518D01*
X-1098389Y141671D01*
X-1099009Y141518D01*
X-1099526Y141135D01*
X-1099836Y140445D01*
X-1099733Y139755D01*
X-1099319Y139065D01*
G01X-1094566Y144651D02*
X-1094049Y145111D01*
X-1093739Y145648D01*
X-1093636Y146338D01*
X-1093843Y147028D01*
X-1094256Y147565D01*
X-1094979Y147948D01*
X-1095806Y148025D01*
X-1096633Y147871D01*
X-1097149Y147488D01*
X-1097563Y146951D01*
X-1097666Y146415D01*
X-1097563Y145878D01*
X-1097149Y145188D01*
X-1099836Y145418D01*
Y147488D01*
G01X-1093875Y426040D02*
Y419840D01*
X-1090809D01*
G01X-1086142D02*
Y426040D01*
X-1087062Y424800D01*
G01Y419840D02*
X-1085222D01*
G01X-1081399Y422423D02*
X-1080862Y423147D01*
X-1080402Y423560D01*
X-1079789Y423767D01*
X-1079252Y423560D01*
X-1078869Y423147D01*
X-1078562Y422527D01*
X-1078485Y421803D01*
X-1078562Y421183D01*
X-1078869Y420563D01*
X-1079329Y420047D01*
X-1079865Y419840D01*
X-1080479Y420047D01*
X-1081015Y420666D01*
X-1081322Y421597D01*
X-1081399Y422630D01*
X-1081245Y423973D01*
X-1081015Y424697D01*
X-1080632Y425420D01*
X-1080095Y425937D01*
X-1079559Y426040D01*
X-1079022Y425833D01*
X-1078639Y425317D01*
G01X-1091017Y437021D02*
X-1091477Y437331D01*
X-1092014Y437538D01*
X-1092627D01*
X-1093317Y437228D01*
X-1093854Y436711D01*
X-1094237Y436091D01*
X-1094544Y435058D01*
X-1094621Y434128D01*
X-1094467Y433198D01*
X-1094237Y432578D01*
X-1093777Y431958D01*
X-1093241Y431545D01*
X-1092704Y431338D01*
X-1092167D01*
X-1091631Y431545D01*
X-1091171Y431855D01*
X-1090787Y432268D01*
G01X-1086657Y431338D02*
X-1086504Y432681D01*
X-1086274Y433818D01*
X-1085967Y434851D01*
X-1085584Y435988D01*
X-1084971Y437538D01*
X-1088037D01*
G01X-1081607Y432061D02*
X-1081071Y431545D01*
X-1080457Y431338D01*
X-1079844Y431545D01*
X-1079307Y432164D01*
X-1078924Y433095D01*
X-1078771Y434025D01*
Y435161D01*
X-1078924Y436091D01*
X-1079307Y436918D01*
X-1079767Y437331D01*
X-1080304Y437538D01*
X-1080917Y437331D01*
X-1081377Y436918D01*
X-1081684Y436298D01*
X-1081837Y435471D01*
X-1081684Y434748D01*
X-1081301Y434025D01*
X-1080841Y433611D01*
X-1080304Y433508D01*
X-1079691Y433715D01*
X-1079231Y434231D01*
X-1078771Y435161D01*
G01X-1078537Y-196030D02*
Y-189830D01*
X-1076621D01*
X-1076007Y-190140D01*
X-1075624Y-190553D01*
X-1075471Y-191380D01*
X-1075624Y-192207D01*
X-1076084Y-192723D01*
X-1076621Y-193033D01*
X-1078537D01*
G01X-1076621D02*
X-1075471Y-196030D01*
G01X-1069884D02*
Y-189830D01*
X-1072721Y-194273D01*
X-1068887D01*
G01X-1064757Y-196030D02*
X-1064604Y-194687D01*
X-1064374Y-193550D01*
X-1064067Y-192517D01*
X-1063684Y-191380D01*
X-1063071Y-189830D01*
X-1066137D01*
G01X-1060091Y-195100D02*
X-1059631Y-195617D01*
X-1059094Y-195927D01*
X-1058404Y-196030D01*
X-1057714Y-195823D01*
X-1057177Y-195410D01*
X-1056794Y-194687D01*
X-1056717Y-193860D01*
X-1056871Y-193033D01*
X-1057254Y-192517D01*
X-1057791Y-192103D01*
X-1058327Y-192000D01*
X-1058864Y-192103D01*
X-1059554Y-192517D01*
X-1059324Y-189830D01*
X-1057254D01*
G01X-1078537Y-170030D02*
Y-163830D01*
X-1076621D01*
X-1076007Y-164140D01*
X-1075624Y-164553D01*
X-1075471Y-165380D01*
X-1075624Y-166207D01*
X-1076084Y-166723D01*
X-1076621Y-167033D01*
X-1078537D01*
G01X-1076621D02*
X-1075471Y-170030D01*
G01X-1069884D02*
Y-163830D01*
X-1072721Y-168273D01*
X-1068887D01*
G01X-1064604Y-170030D02*
X-1064067Y-169927D01*
X-1063454Y-169617D01*
X-1063071Y-169100D01*
X-1062917Y-168377D01*
X-1063071Y-167653D01*
X-1063531Y-167033D01*
X-1064221Y-166723D01*
X-1064987D01*
X-1065447Y-166517D01*
X-1065831Y-166000D01*
X-1065984Y-165277D01*
X-1065754Y-164553D01*
X-1065217Y-164037D01*
X-1064604Y-163830D01*
X-1063991Y-164037D01*
X-1063454Y-164553D01*
X-1063224Y-165277D01*
X-1063377Y-166000D01*
X-1063761Y-166517D01*
X-1064221Y-166723D01*
X-1064987D01*
X-1065677Y-167033D01*
X-1066137Y-167653D01*
X-1066291Y-168377D01*
X-1066137Y-169100D01*
X-1065754Y-169617D01*
X-1065141Y-169927D01*
X-1064604Y-170030D01*
G01X-1059861Y-167447D02*
X-1059324Y-166723D01*
X-1058864Y-166310D01*
X-1058251Y-166103D01*
X-1057714Y-166310D01*
X-1057331Y-166723D01*
X-1057024Y-167343D01*
X-1056947Y-168067D01*
X-1057024Y-168687D01*
X-1057331Y-169307D01*
X-1057791Y-169823D01*
X-1058327Y-170030D01*
X-1058941Y-169823D01*
X-1059477Y-169204D01*
X-1059784Y-168273D01*
X-1059861Y-167240D01*
X-1059707Y-165897D01*
X-1059477Y-165173D01*
X-1059094Y-164450D01*
X-1058557Y-163933D01*
X-1058021Y-163830D01*
X-1057484Y-164037D01*
X-1057101Y-164553D01*
G01X-1078537Y-180030D02*
Y-173830D01*
X-1076621D01*
X-1076007Y-174140D01*
X-1075624Y-174553D01*
X-1075471Y-175380D01*
X-1075624Y-176207D01*
X-1076084Y-176723D01*
X-1076621Y-177033D01*
X-1078537D01*
G01X-1076621D02*
X-1075471Y-180030D01*
G01X-1069884D02*
Y-173830D01*
X-1072721Y-178273D01*
X-1068887D01*
G01X-1064757Y-180030D02*
X-1064604Y-178687D01*
X-1064374Y-177550D01*
X-1064067Y-176517D01*
X-1063684Y-175380D01*
X-1063071Y-173830D01*
X-1066137D01*
G01X-1057484Y-180030D02*
Y-173830D01*
X-1060321Y-178273D01*
X-1056487D01*
G01X-1078537Y-160030D02*
Y-153830D01*
X-1076621D01*
X-1076007Y-154140D01*
X-1075624Y-154553D01*
X-1075471Y-155380D01*
X-1075624Y-156207D01*
X-1076084Y-156723D01*
X-1076621Y-157033D01*
X-1078537D01*
G01X-1076621D02*
X-1075471Y-160030D01*
G01X-1069884D02*
Y-153830D01*
X-1072721Y-158273D01*
X-1068887D01*
G01X-1064604Y-160030D02*
X-1064067Y-159927D01*
X-1063454Y-159617D01*
X-1063071Y-159100D01*
X-1062917Y-158377D01*
X-1063071Y-157653D01*
X-1063531Y-157033D01*
X-1064221Y-156723D01*
X-1064987D01*
X-1065447Y-156517D01*
X-1065831Y-156000D01*
X-1065984Y-155277D01*
X-1065754Y-154553D01*
X-1065217Y-154037D01*
X-1064604Y-153830D01*
X-1063991Y-154037D01*
X-1063454Y-154553D01*
X-1063224Y-155277D01*
X-1063377Y-156000D01*
X-1063761Y-156517D01*
X-1064221Y-156723D01*
X-1064987D01*
X-1065677Y-157033D01*
X-1066137Y-157653D01*
X-1066291Y-158377D01*
X-1066137Y-159100D01*
X-1065754Y-159617D01*
X-1065141Y-159927D01*
X-1064604Y-160030D01*
G01X-1060091Y-159100D02*
X-1059631Y-159617D01*
X-1059094Y-159927D01*
X-1058404Y-160030D01*
X-1057714Y-159823D01*
X-1057177Y-159410D01*
X-1056794Y-158687D01*
X-1056717Y-157860D01*
X-1056871Y-157033D01*
X-1057254Y-156517D01*
X-1057791Y-156103D01*
X-1058327Y-156000D01*
X-1058864Y-156103D01*
X-1059554Y-156517D01*
X-1059324Y-153830D01*
X-1057254D01*
G01X-1073638Y-107479D02*
X-1079838Y-105562D01*
X-1073638Y-103645D01*
G01X-1075808Y-104335D02*
Y-106789D01*
G01X-1073638Y-101279D02*
X-1079838Y-99362D01*
X-1073638Y-97445D01*
G01X-1075808Y-98135D02*
Y-100589D01*
G01X-1078636Y102205D02*
X-1084836D01*
Y104121D01*
X-1084526Y104735D01*
X-1084113Y105118D01*
X-1083286Y105271D01*
X-1082459Y105118D01*
X-1081943Y104658D01*
X-1081633Y104121D01*
Y102205D01*
G01Y104121D02*
X-1078636Y105271D01*
G01X-1079876Y108251D02*
X-1079153Y108711D01*
X-1078739Y109325D01*
X-1078636Y110015D01*
X-1078739Y110628D01*
X-1079256Y111241D01*
X-1079876Y111625D01*
X-1080496Y111701D01*
X-1081219Y111548D01*
X-1081736Y111011D01*
X-1081943Y110475D01*
Y109785D01*
G01Y110475D02*
X-1082253Y110935D01*
X-1082769Y111318D01*
X-1083389Y111471D01*
X-1084009Y111318D01*
X-1084526Y110935D01*
X-1084836Y110245D01*
X-1084733Y109555D01*
X-1084319Y108865D01*
G01X-1081219Y114681D02*
X-1081943Y115218D01*
X-1082356Y115678D01*
X-1082563Y116291D01*
X-1082356Y116828D01*
X-1081943Y117211D01*
X-1081323Y117518D01*
X-1080599Y117595D01*
X-1079979Y117518D01*
X-1079359Y117211D01*
X-1078843Y116751D01*
X-1078636Y116215D01*
X-1078843Y115601D01*
X-1079462Y115065D01*
X-1080393Y114758D01*
X-1081426Y114681D01*
X-1082769Y114835D01*
X-1083493Y115065D01*
X-1084216Y115448D01*
X-1084733Y115985D01*
X-1084836Y116521D01*
X-1084629Y117058D01*
X-1084113Y117441D01*
G01X-1083803Y120881D02*
X-1084423Y121341D01*
X-1084733Y121878D01*
X-1084836Y122491D01*
X-1084629Y123258D01*
X-1084113Y123795D01*
X-1083493Y123948D01*
X-1082873Y123871D01*
X-1082356Y123565D01*
X-1081323Y122031D01*
X-1080599Y121341D01*
X-1079566Y120881D01*
X-1078636Y120728D01*
Y123948D01*
G01X-1079804Y346738D02*
X-1073604D01*
G01X-1079804Y344975D02*
Y348501D01*
G01X-1073604Y351405D02*
X-1079804D01*
Y353245D01*
X-1079494Y353858D01*
X-1078771Y354318D01*
X-1077944Y354471D01*
X-1077117Y354318D01*
X-1076497Y353935D01*
X-1076187Y353245D01*
Y351405D01*
G01X-1073604Y359138D02*
X-1079804D01*
X-1078564Y358218D01*
G01X-1073604D02*
Y360058D01*
G01X-1074534Y363651D02*
X-1074017Y364111D01*
X-1073707Y364648D01*
X-1073604Y365338D01*
X-1073811Y366028D01*
X-1074224Y366565D01*
X-1074947Y366948D01*
X-1075774Y367025D01*
X-1076601Y366871D01*
X-1077117Y366488D01*
X-1077531Y365951D01*
X-1077634Y365415D01*
X-1077531Y364878D01*
X-1077117Y364188D01*
X-1079804Y364418D01*
Y366488D01*
G01X-1053804Y-174262D02*
X-1047604D01*
G01X-1053804Y-176025D02*
Y-172499D01*
G01X-1047604Y-169595D02*
X-1053804D01*
Y-167755D01*
X-1053494Y-167142D01*
X-1052771Y-166682D01*
X-1051944Y-166529D01*
X-1051117Y-166682D01*
X-1050497Y-167065D01*
X-1050187Y-167755D01*
Y-169595D01*
G01X-1047604Y-161862D02*
X-1053804D01*
X-1052564Y-162782D01*
G01X-1047604D02*
Y-160942D01*
G01X-1052771Y-157119D02*
X-1053391Y-156659D01*
X-1053701Y-156122D01*
X-1053804Y-155509D01*
X-1053597Y-154742D01*
X-1053081Y-154205D01*
X-1052461Y-154052D01*
X-1051841Y-154129D01*
X-1051324Y-154435D01*
X-1050291Y-155969D01*
X-1049567Y-156659D01*
X-1048534Y-157119D01*
X-1047604Y-157272D01*
Y-154052D01*
G01X-1063658Y-107619D02*
X-1069858Y-105702D01*
X-1063658Y-103785D01*
G01X-1065828Y-104475D02*
Y-106929D01*
G01X-1066965Y-98889D02*
X-1067275Y-98582D01*
X-1067791Y-98352D01*
X-1068515Y-98199D01*
X-1069135Y-98352D01*
X-1069548Y-98659D01*
X-1069858Y-99195D01*
Y-101265D01*
X-1063658D01*
Y-98735D01*
X-1064071Y-98199D01*
X-1064691Y-97892D01*
X-1065415Y-97739D01*
X-1066138Y-97892D01*
X-1066758Y-98352D01*
X-1066965Y-98889D01*
Y-101265D01*
G01X-1065287Y139225D02*
X-1065597Y138765D01*
X-1065804Y138228D01*
Y137615D01*
X-1065494Y136925D01*
X-1064977Y136388D01*
X-1064357Y136005D01*
X-1063324Y135698D01*
X-1062394Y135621D01*
X-1061464Y135775D01*
X-1060844Y136005D01*
X-1060224Y136465D01*
X-1059811Y137001D01*
X-1059604Y137538D01*
Y138075D01*
X-1059811Y138611D01*
X-1060121Y139071D01*
X-1060534Y139455D01*
G01X-1059604Y143738D02*
X-1065804D01*
X-1064564Y142818D01*
G01X-1059604D02*
Y144658D01*
G01Y149785D02*
X-1060947Y149938D01*
X-1062084Y150168D01*
X-1063117Y150475D01*
X-1064254Y150858D01*
X-1065804Y151471D01*
Y148405D01*
G01X-1059604Y157058D02*
X-1065804D01*
X-1061361Y154221D01*
Y158055D01*
G01X-1050604Y343205D02*
X-1056804D01*
Y345121D01*
X-1056494Y345735D01*
X-1056081Y346118D01*
X-1055254Y346271D01*
X-1054427Y346118D01*
X-1053911Y345658D01*
X-1053601Y345121D01*
Y343205D01*
G01Y345121D02*
X-1050604Y346271D01*
G01Y350938D02*
X-1056804D01*
X-1055564Y350018D01*
G01X-1050604D02*
Y351858D01*
G01Y357138D02*
X-1056804D01*
X-1055564Y356218D01*
G01X-1050604D02*
Y358058D01*
G01X-1053187Y361881D02*
X-1053911Y362418D01*
X-1054324Y362878D01*
X-1054531Y363491D01*
X-1054324Y364028D01*
X-1053911Y364411D01*
X-1053291Y364718D01*
X-1052567Y364795D01*
X-1051947Y364718D01*
X-1051327Y364411D01*
X-1050811Y363951D01*
X-1050604Y363415D01*
X-1050811Y362801D01*
X-1051430Y362265D01*
X-1052361Y361958D01*
X-1053394Y361881D01*
X-1054737Y362035D01*
X-1055461Y362265D01*
X-1056184Y362648D01*
X-1056701Y363185D01*
X-1056804Y363721D01*
X-1056597Y364258D01*
X-1056081Y364641D01*
G01X-1060604Y343205D02*
X-1066804D01*
Y345121D01*
X-1066494Y345735D01*
X-1066081Y346118D01*
X-1065254Y346271D01*
X-1064427Y346118D01*
X-1063911Y345658D01*
X-1063601Y345121D01*
Y343205D01*
G01Y345121D02*
X-1060604Y346271D01*
G01Y350938D02*
X-1066804D01*
X-1065564Y350018D01*
G01X-1060604D02*
Y351858D01*
G01Y357138D02*
X-1066804D01*
X-1065564Y356218D01*
G01X-1060604D02*
Y358058D01*
G01Y364258D02*
X-1066804D01*
X-1062361Y361421D01*
Y365255D01*
G01X-1063704Y379038D02*
X-1063167Y379141D01*
X-1062554Y379451D01*
X-1062171Y379968D01*
X-1062017Y380691D01*
X-1062171Y381415D01*
X-1062631Y382035D01*
X-1063321Y382345D01*
X-1064087D01*
X-1064547Y382551D01*
X-1064931Y383068D01*
X-1065084Y383791D01*
X-1064854Y384515D01*
X-1064317Y385031D01*
X-1063704Y385238D01*
X-1063091Y385031D01*
X-1062554Y384515D01*
X-1062324Y383791D01*
X-1062477Y383068D01*
X-1062861Y382551D01*
X-1063321Y382345D01*
X-1064087D01*
X-1064777Y382035D01*
X-1065237Y381415D01*
X-1065391Y380691D01*
X-1065237Y379968D01*
X-1064854Y379451D01*
X-1064241Y379141D01*
X-1063704Y379038D01*
G01X-1064161Y437205D02*
X-1063701Y437825D01*
X-1063164Y438135D01*
X-1062551Y438238D01*
X-1061784Y438031D01*
X-1061247Y437515D01*
X-1061094Y436895D01*
X-1061171Y436275D01*
X-1061477Y435758D01*
X-1063011Y434725D01*
X-1063701Y434001D01*
X-1064161Y432968D01*
X-1064314Y432038D01*
X-1061094D01*
G01X-1045704Y-204962D02*
X-1045167Y-204859D01*
X-1044554Y-204549D01*
X-1044171Y-204032D01*
X-1044017Y-203309D01*
X-1044171Y-202585D01*
X-1044631Y-201965D01*
X-1045321Y-201655D01*
X-1046087D01*
X-1046547Y-201449D01*
X-1046931Y-200932D01*
X-1047084Y-200209D01*
X-1046854Y-199485D01*
X-1046317Y-198969D01*
X-1045704Y-198762D01*
X-1045091Y-198969D01*
X-1044554Y-199485D01*
X-1044324Y-200209D01*
X-1044477Y-200932D01*
X-1044861Y-201449D01*
X-1045321Y-201655D01*
X-1046087D01*
X-1046777Y-201965D01*
X-1047237Y-202585D01*
X-1047391Y-203309D01*
X-1047237Y-204032D01*
X-1046854Y-204549D01*
X-1046241Y-204859D01*
X-1045704Y-204962D01*
G01X-1037437Y-28062D02*
Y-21862D01*
X-1035521D01*
X-1034907Y-22172D01*
X-1034524Y-22585D01*
X-1034371Y-23412D01*
X-1034524Y-24239D01*
X-1034984Y-24755D01*
X-1035521Y-25065D01*
X-1037437D01*
G01X-1035521D02*
X-1034371Y-28062D01*
G01X-1031007Y-27339D02*
X-1030471Y-27855D01*
X-1029857Y-28062D01*
X-1029244Y-27855D01*
X-1028707Y-27236D01*
X-1028324Y-26305D01*
X-1028171Y-25375D01*
Y-24239D01*
X-1028324Y-23309D01*
X-1028707Y-22482D01*
X-1029167Y-22069D01*
X-1029704Y-21862D01*
X-1030317Y-22069D01*
X-1030777Y-22482D01*
X-1031084Y-23102D01*
X-1031237Y-23929D01*
X-1031084Y-24652D01*
X-1030701Y-25375D01*
X-1030241Y-25789D01*
X-1029704Y-25892D01*
X-1029091Y-25685D01*
X-1028631Y-25169D01*
X-1028171Y-24239D01*
G01X-1025191Y-26822D02*
X-1024731Y-27545D01*
X-1024117Y-27959D01*
X-1023427Y-28062D01*
X-1022814Y-27959D01*
X-1022201Y-27442D01*
X-1021817Y-26822D01*
X-1021741Y-26202D01*
X-1021894Y-25479D01*
X-1022431Y-24962D01*
X-1022967Y-24755D01*
X-1023657D01*
G01X-1022967D02*
X-1022507Y-24445D01*
X-1022124Y-23929D01*
X-1021971Y-23309D01*
X-1022124Y-22689D01*
X-1022507Y-22172D01*
X-1023197Y-21862D01*
X-1023887Y-21965D01*
X-1024577Y-22379D01*
G01X-1040537Y-10062D02*
Y-3862D01*
X-1038621D01*
X-1038007Y-4172D01*
X-1037624Y-4585D01*
X-1037471Y-5412D01*
X-1037624Y-6239D01*
X-1038084Y-6755D01*
X-1038621Y-7065D01*
X-1040537D01*
G01X-1038621D02*
X-1037471Y-10062D01*
G01X-1034261Y-4895D02*
X-1033801Y-4275D01*
X-1033264Y-3965D01*
X-1032651Y-3862D01*
X-1031884Y-4069D01*
X-1031347Y-4585D01*
X-1031194Y-5205D01*
X-1031271Y-5825D01*
X-1031577Y-6342D01*
X-1033111Y-7375D01*
X-1033801Y-8099D01*
X-1034261Y-9132D01*
X-1034414Y-10062D01*
X-1031194D01*
G01X-1026604D02*
Y-3862D01*
X-1027524Y-5102D01*
G01Y-10062D02*
X-1025684D01*
G01X-1021861Y-4895D02*
X-1021401Y-4275D01*
X-1020864Y-3965D01*
X-1020251Y-3862D01*
X-1019484Y-4069D01*
X-1018947Y-4585D01*
X-1018794Y-5205D01*
X-1018871Y-5825D01*
X-1019177Y-6342D01*
X-1020711Y-7375D01*
X-1021401Y-8099D01*
X-1021861Y-9132D01*
X-1022014Y-10062D01*
X-1018794D01*
G01X-1040537Y-19062D02*
Y-12862D01*
X-1038621D01*
X-1038007Y-13172D01*
X-1037624Y-13585D01*
X-1037471Y-14412D01*
X-1037624Y-15239D01*
X-1038084Y-15755D01*
X-1038621Y-16065D01*
X-1040537D01*
G01X-1038621D02*
X-1037471Y-19062D01*
G01X-1034261Y-13895D02*
X-1033801Y-13275D01*
X-1033264Y-12965D01*
X-1032651Y-12862D01*
X-1031884Y-13069D01*
X-1031347Y-13585D01*
X-1031194Y-14205D01*
X-1031271Y-14825D01*
X-1031577Y-15342D01*
X-1033111Y-16375D01*
X-1033801Y-17099D01*
X-1034261Y-18132D01*
X-1034414Y-19062D01*
X-1031194D01*
G01X-1026604D02*
X-1026067Y-18959D01*
X-1025454Y-18649D01*
X-1025071Y-18132D01*
X-1024917Y-17409D01*
X-1025071Y-16685D01*
X-1025531Y-16065D01*
X-1026221Y-15755D01*
X-1026987D01*
X-1027447Y-15549D01*
X-1027831Y-15032D01*
X-1027984Y-14309D01*
X-1027754Y-13585D01*
X-1027217Y-13069D01*
X-1026604Y-12862D01*
X-1025991Y-13069D01*
X-1025454Y-13585D01*
X-1025224Y-14309D01*
X-1025377Y-15032D01*
X-1025761Y-15549D01*
X-1026221Y-15755D01*
X-1026987D01*
X-1027677Y-16065D01*
X-1028137Y-16685D01*
X-1028291Y-17409D01*
X-1028137Y-18132D01*
X-1027754Y-18649D01*
X-1027141Y-18959D01*
X-1026604Y-19062D01*
G01X-1020404D02*
X-1019867Y-18959D01*
X-1019254Y-18649D01*
X-1018871Y-18132D01*
X-1018717Y-17409D01*
X-1018871Y-16685D01*
X-1019331Y-16065D01*
X-1020021Y-15755D01*
X-1020787D01*
X-1021247Y-15549D01*
X-1021631Y-15032D01*
X-1021784Y-14309D01*
X-1021554Y-13585D01*
X-1021017Y-13069D01*
X-1020404Y-12862D01*
X-1019791Y-13069D01*
X-1019254Y-13585D01*
X-1019024Y-14309D01*
X-1019177Y-15032D01*
X-1019561Y-15549D01*
X-1020021Y-15755D01*
X-1020787D01*
X-1021477Y-16065D01*
X-1021937Y-16685D01*
X-1022091Y-17409D01*
X-1021937Y-18132D01*
X-1021554Y-18649D01*
X-1020941Y-18959D01*
X-1020404Y-19062D01*
G01X-1040537Y-1062D02*
Y5138D01*
X-1038621D01*
X-1038007Y4828D01*
X-1037624Y4415D01*
X-1037471Y3588D01*
X-1037624Y2761D01*
X-1038084Y2245D01*
X-1038621Y1935D01*
X-1040537D01*
G01X-1038621D02*
X-1037471Y-1062D01*
G01X-1034261Y4105D02*
X-1033801Y4725D01*
X-1033264Y5035D01*
X-1032651Y5138D01*
X-1031884Y4931D01*
X-1031347Y4415D01*
X-1031194Y3795D01*
X-1031271Y3175D01*
X-1031577Y2658D01*
X-1033111Y1625D01*
X-1033801Y901D01*
X-1034261Y-132D01*
X-1034414Y-1062D01*
X-1031194D01*
G01X-1026604D02*
Y5138D01*
X-1027524Y3898D01*
G01Y-1062D02*
X-1025684D01*
G01X-1020404D02*
Y5138D01*
X-1021324Y3898D01*
G01Y-1062D02*
X-1019484D01*
G01X-1037437Y40938D02*
Y47138D01*
X-1035521D01*
X-1034907Y46828D01*
X-1034524Y46415D01*
X-1034371Y45588D01*
X-1034524Y44761D01*
X-1034984Y44245D01*
X-1035521Y43935D01*
X-1037437D01*
G01X-1035521D02*
X-1034371Y40938D01*
G01X-1031007Y41661D02*
X-1030471Y41145D01*
X-1029857Y40938D01*
X-1029244Y41145D01*
X-1028707Y41764D01*
X-1028324Y42695D01*
X-1028171Y43625D01*
Y44761D01*
X-1028324Y45691D01*
X-1028707Y46518D01*
X-1029167Y46931D01*
X-1029704Y47138D01*
X-1030317Y46931D01*
X-1030777Y46518D01*
X-1031084Y45898D01*
X-1031237Y45071D01*
X-1031084Y44348D01*
X-1030701Y43625D01*
X-1030241Y43211D01*
X-1029704Y43108D01*
X-1029091Y43315D01*
X-1028631Y43831D01*
X-1028171Y44761D01*
G01X-1022584Y40938D02*
Y47138D01*
X-1025421Y42695D01*
X-1021587D01*
G01X-1037437Y50938D02*
Y57138D01*
X-1035521D01*
X-1034907Y56828D01*
X-1034524Y56415D01*
X-1034371Y55588D01*
X-1034524Y54761D01*
X-1034984Y54245D01*
X-1035521Y53935D01*
X-1037437D01*
G01X-1035521D02*
X-1034371Y50938D01*
G01X-1031007Y51661D02*
X-1030471Y51145D01*
X-1029857Y50938D01*
X-1029244Y51145D01*
X-1028707Y51764D01*
X-1028324Y52695D01*
X-1028171Y53625D01*
Y54761D01*
X-1028324Y55691D01*
X-1028707Y56518D01*
X-1029167Y56931D01*
X-1029704Y57138D01*
X-1030317Y56931D01*
X-1030777Y56518D01*
X-1031084Y55898D01*
X-1031237Y55071D01*
X-1031084Y54348D01*
X-1030701Y53625D01*
X-1030241Y53211D01*
X-1029704Y53108D01*
X-1029091Y53315D01*
X-1028631Y53831D01*
X-1028171Y54761D01*
G01X-1025191Y51868D02*
X-1024731Y51351D01*
X-1024194Y51041D01*
X-1023504Y50938D01*
X-1022814Y51145D01*
X-1022277Y51558D01*
X-1021894Y52281D01*
X-1021817Y53108D01*
X-1021971Y53935D01*
X-1022354Y54451D01*
X-1022891Y54865D01*
X-1023427Y54968D01*
X-1023964Y54865D01*
X-1024654Y54451D01*
X-1024424Y57138D01*
X-1022354D01*
G01X-1049804Y65738D02*
X-1043604D01*
G01X-1049804Y63975D02*
Y67501D01*
G01X-1043604Y70405D02*
X-1049804D01*
Y72245D01*
X-1049494Y72858D01*
X-1048771Y73318D01*
X-1047944Y73471D01*
X-1047117Y73318D01*
X-1046497Y72935D01*
X-1046187Y72245D01*
Y70405D01*
G01X-1043604Y79058D02*
X-1049804D01*
X-1045361Y76221D01*
Y80055D01*
G01X-1044534Y82651D02*
X-1044017Y83111D01*
X-1043707Y83648D01*
X-1043604Y84338D01*
X-1043811Y85028D01*
X-1044224Y85565D01*
X-1044947Y85948D01*
X-1045774Y86025D01*
X-1046601Y85871D01*
X-1047117Y85488D01*
X-1047531Y84951D01*
X-1047634Y84415D01*
X-1047531Y83878D01*
X-1047117Y83188D01*
X-1049804Y83418D01*
Y85488D01*
G01X-1040537Y68938D02*
Y75138D01*
X-1038621D01*
X-1038007Y74828D01*
X-1037624Y74415D01*
X-1037471Y73588D01*
X-1037624Y72761D01*
X-1038084Y72245D01*
X-1038621Y71935D01*
X-1040537D01*
G01X-1038621D02*
X-1037471Y68938D01*
G01X-1032804D02*
Y75138D01*
X-1033724Y73898D01*
G01Y68938D02*
X-1031884D01*
G01X-1027907Y69661D02*
X-1027371Y69145D01*
X-1026757Y68938D01*
X-1026144Y69145D01*
X-1025607Y69764D01*
X-1025224Y70695D01*
X-1025071Y71625D01*
Y72761D01*
X-1025224Y73691D01*
X-1025607Y74518D01*
X-1026067Y74931D01*
X-1026604Y75138D01*
X-1027217Y74931D01*
X-1027677Y74518D01*
X-1027984Y73898D01*
X-1028137Y73071D01*
X-1027984Y72348D01*
X-1027601Y71625D01*
X-1027141Y71211D01*
X-1026604Y71108D01*
X-1025991Y71315D01*
X-1025531Y71831D01*
X-1025071Y72761D01*
G01X-1022091Y70178D02*
X-1021631Y69455D01*
X-1021017Y69041D01*
X-1020327Y68938D01*
X-1019714Y69041D01*
X-1019101Y69558D01*
X-1018717Y70178D01*
X-1018641Y70798D01*
X-1018794Y71521D01*
X-1019331Y72038D01*
X-1019867Y72245D01*
X-1020557D01*
G01X-1019867D02*
X-1019407Y72555D01*
X-1019024Y73071D01*
X-1018871Y73691D01*
X-1019024Y74311D01*
X-1019407Y74828D01*
X-1020097Y75138D01*
X-1020787Y75035D01*
X-1021477Y74621D01*
G01X-1040537Y60970D02*
Y67170D01*
X-1038621D01*
X-1038007Y66860D01*
X-1037624Y66447D01*
X-1037471Y65620D01*
X-1037624Y64793D01*
X-1038084Y64277D01*
X-1038621Y63967D01*
X-1040537D01*
G01X-1038621D02*
X-1037471Y60970D01*
G01X-1034491Y62210D02*
X-1034031Y61487D01*
X-1033417Y61073D01*
X-1032727Y60970D01*
X-1032114Y61073D01*
X-1031501Y61590D01*
X-1031117Y62210D01*
X-1031041Y62830D01*
X-1031194Y63553D01*
X-1031731Y64070D01*
X-1032267Y64277D01*
X-1032957D01*
G01X-1032267D02*
X-1031807Y64587D01*
X-1031424Y65103D01*
X-1031271Y65723D01*
X-1031424Y66343D01*
X-1031807Y66860D01*
X-1032497Y67170D01*
X-1033187Y67067D01*
X-1033877Y66653D01*
G01X-1028291Y61900D02*
X-1027831Y61383D01*
X-1027294Y61073D01*
X-1026604Y60970D01*
X-1025914Y61177D01*
X-1025377Y61590D01*
X-1024994Y62313D01*
X-1024917Y63140D01*
X-1025071Y63967D01*
X-1025454Y64483D01*
X-1025991Y64897D01*
X-1026527Y65000D01*
X-1027064Y64897D01*
X-1027754Y64483D01*
X-1027524Y67170D01*
X-1025454D01*
G01X-1021861Y63553D02*
X-1021324Y64277D01*
X-1020864Y64690D01*
X-1020251Y64897D01*
X-1019714Y64690D01*
X-1019331Y64277D01*
X-1019024Y63657D01*
X-1018947Y62933D01*
X-1019024Y62313D01*
X-1019331Y61693D01*
X-1019791Y61177D01*
X-1020327Y60970D01*
X-1020941Y61177D01*
X-1021477Y61796D01*
X-1021784Y62727D01*
X-1021861Y63760D01*
X-1021707Y65103D01*
X-1021477Y65827D01*
X-1021094Y66550D01*
X-1020557Y67067D01*
X-1020021Y67170D01*
X-1019484Y66963D01*
X-1019101Y66447D01*
G01X-1047804Y185738D02*
X-1041604D01*
G01X-1047804Y183975D02*
Y187501D01*
G01X-1041604Y190405D02*
X-1047804D01*
Y192245D01*
X-1047494Y192858D01*
X-1046771Y193318D01*
X-1045944Y193471D01*
X-1045117Y193318D01*
X-1044497Y192935D01*
X-1044187Y192245D01*
Y190405D01*
G01X-1041604Y199058D02*
X-1047804D01*
X-1043361Y196221D01*
Y200055D01*
G01X-1047804Y204338D02*
X-1047597Y203725D01*
X-1047081Y203265D01*
X-1046461Y202958D01*
X-1045634Y202728D01*
X-1044704Y202651D01*
X-1043774Y202728D01*
X-1042947Y202958D01*
X-1042327Y203265D01*
X-1041811Y203725D01*
X-1041604Y204338D01*
X-1041811Y204951D01*
X-1042327Y205411D01*
X-1042947Y205718D01*
X-1043774Y205948D01*
X-1044704Y206025D01*
X-1045634Y205948D01*
X-1046461Y205718D01*
X-1047081Y205411D01*
X-1047597Y204951D01*
X-1047804Y204338D01*
G01X-1040604Y343205D02*
X-1046804D01*
Y345121D01*
X-1046494Y345735D01*
X-1046081Y346118D01*
X-1045254Y346271D01*
X-1044427Y346118D01*
X-1043911Y345658D01*
X-1043601Y345121D01*
Y343205D01*
G01Y345121D02*
X-1040604Y346271D01*
G01Y350938D02*
X-1046804D01*
X-1045564Y350018D01*
G01X-1040604D02*
Y351858D01*
G01Y357138D02*
X-1046804D01*
X-1045564Y356218D01*
G01X-1040604D02*
Y358058D01*
G01Y363185D02*
X-1041947Y363338D01*
X-1043084Y363568D01*
X-1044117Y363875D01*
X-1045254Y364258D01*
X-1046804Y364871D01*
Y361805D01*
G01X-1030604Y343205D02*
X-1036804D01*
Y345121D01*
X-1036494Y345735D01*
X-1036081Y346118D01*
X-1035254Y346271D01*
X-1034427Y346118D01*
X-1033911Y345658D01*
X-1033601Y345121D01*
Y343205D01*
G01Y345121D02*
X-1030604Y346271D01*
G01Y350938D02*
X-1036804D01*
X-1035564Y350018D01*
G01X-1030604D02*
Y351858D01*
G01Y357138D02*
X-1036804D01*
X-1035564Y356218D01*
G01X-1030604D02*
Y358058D01*
G01X-1031844Y361651D02*
X-1031121Y362111D01*
X-1030707Y362725D01*
X-1030604Y363415D01*
X-1030707Y364028D01*
X-1031224Y364641D01*
X-1031844Y365025D01*
X-1032464Y365101D01*
X-1033187Y364948D01*
X-1033704Y364411D01*
X-1033911Y363875D01*
Y363185D01*
G01Y363875D02*
X-1034221Y364335D01*
X-1034737Y364718D01*
X-1035357Y364871D01*
X-1035977Y364718D01*
X-1036494Y364335D01*
X-1036804Y363645D01*
X-1036701Y362955D01*
X-1036287Y362265D01*
G01X-1037400Y402437D02*
X-1043600D01*
Y404277D01*
X-1043290Y404890D01*
X-1042567Y405350D01*
X-1041740Y405503D01*
X-1040913Y405350D01*
X-1040293Y404967D01*
X-1039983Y404277D01*
Y402437D01*
G01X-1042567Y408713D02*
X-1043187Y409173D01*
X-1043497Y409710D01*
X-1043600Y410323D01*
X-1043393Y411090D01*
X-1042877Y411627D01*
X-1042257Y411780D01*
X-1041637Y411703D01*
X-1041120Y411397D01*
X-1040087Y409863D01*
X-1039363Y409173D01*
X-1038330Y408713D01*
X-1037400Y408560D01*
Y411780D01*
G01X-1024117Y-96679D02*
X-1024577Y-96369D01*
X-1025114Y-96162D01*
X-1025727D01*
X-1026417Y-96472D01*
X-1026954Y-96989D01*
X-1027337Y-97609D01*
X-1027644Y-98642D01*
X-1027721Y-99572D01*
X-1027567Y-100502D01*
X-1027337Y-101122D01*
X-1026877Y-101742D01*
X-1026341Y-102155D01*
X-1025804Y-102362D01*
X-1025267D01*
X-1024731Y-102155D01*
X-1024271Y-101845D01*
X-1023887Y-101432D01*
G01X-1021061Y-97195D02*
X-1020601Y-96575D01*
X-1020064Y-96265D01*
X-1019451Y-96162D01*
X-1018684Y-96369D01*
X-1018147Y-96885D01*
X-1017994Y-97505D01*
X-1018071Y-98125D01*
X-1018377Y-98642D01*
X-1019911Y-99675D01*
X-1020601Y-100399D01*
X-1021061Y-101432D01*
X-1021214Y-102362D01*
X-1017994D01*
G01X-1014707Y-101639D02*
X-1014171Y-102155D01*
X-1013557Y-102362D01*
X-1012944Y-102155D01*
X-1012407Y-101536D01*
X-1012024Y-100605D01*
X-1011871Y-99675D01*
Y-98539D01*
X-1012024Y-97609D01*
X-1012407Y-96782D01*
X-1012867Y-96369D01*
X-1013404Y-96162D01*
X-1014017Y-96369D01*
X-1014477Y-96782D01*
X-1014784Y-97402D01*
X-1014937Y-98229D01*
X-1014784Y-98952D01*
X-1014401Y-99675D01*
X-1013941Y-100089D01*
X-1013404Y-100192D01*
X-1012791Y-99985D01*
X-1012331Y-99469D01*
X-1011871Y-98539D01*
G01X-1008661Y-97195D02*
X-1008201Y-96575D01*
X-1007664Y-96265D01*
X-1007051Y-96162D01*
X-1006284Y-96369D01*
X-1005747Y-96885D01*
X-1005594Y-97505D01*
X-1005671Y-98125D01*
X-1005977Y-98642D01*
X-1007511Y-99675D01*
X-1008201Y-100399D01*
X-1008661Y-101432D01*
X-1008814Y-102362D01*
X-1005594D01*
G01X-1025537Y-87062D02*
Y-80862D01*
X-1023621D01*
X-1023007Y-81172D01*
X-1022624Y-81585D01*
X-1022471Y-82412D01*
X-1022624Y-83239D01*
X-1023084Y-83755D01*
X-1023621Y-84065D01*
X-1025537D01*
G01X-1023621D02*
X-1022471Y-87062D01*
G01X-1017804D02*
Y-80862D01*
X-1018724Y-82102D01*
G01Y-87062D02*
X-1016884D01*
G01X-1012907Y-86339D02*
X-1012371Y-86855D01*
X-1011757Y-87062D01*
X-1011144Y-86855D01*
X-1010607Y-86236D01*
X-1010224Y-85305D01*
X-1010071Y-84375D01*
Y-83239D01*
X-1010224Y-82309D01*
X-1010607Y-81482D01*
X-1011067Y-81069D01*
X-1011604Y-80862D01*
X-1012217Y-81069D01*
X-1012677Y-81482D01*
X-1012984Y-82102D01*
X-1013137Y-82929D01*
X-1012984Y-83652D01*
X-1012601Y-84375D01*
X-1012141Y-84789D01*
X-1011604Y-84892D01*
X-1010991Y-84685D01*
X-1010531Y-84169D01*
X-1010071Y-83239D01*
G01X-1004484Y-87062D02*
Y-80862D01*
X-1007321Y-85305D01*
X-1003487D01*
G01X-1025537Y-68062D02*
Y-61862D01*
X-1023621D01*
X-1023007Y-62172D01*
X-1022624Y-62585D01*
X-1022471Y-63412D01*
X-1022624Y-64239D01*
X-1023084Y-64755D01*
X-1023621Y-65065D01*
X-1025537D01*
G01X-1023621D02*
X-1022471Y-68062D01*
G01X-1019261Y-62895D02*
X-1018801Y-62275D01*
X-1018264Y-61965D01*
X-1017651Y-61862D01*
X-1016884Y-62069D01*
X-1016347Y-62585D01*
X-1016194Y-63205D01*
X-1016271Y-63825D01*
X-1016577Y-64342D01*
X-1018111Y-65375D01*
X-1018801Y-66099D01*
X-1019261Y-67132D01*
X-1019414Y-68062D01*
X-1016194D01*
G01X-1013061Y-62895D02*
X-1012601Y-62275D01*
X-1012064Y-61965D01*
X-1011451Y-61862D01*
X-1010684Y-62069D01*
X-1010147Y-62585D01*
X-1009994Y-63205D01*
X-1010071Y-63825D01*
X-1010377Y-64342D01*
X-1011911Y-65375D01*
X-1012601Y-66099D01*
X-1013061Y-67132D01*
X-1013214Y-68062D01*
X-1009994D01*
G01X-1006861Y-62895D02*
X-1006401Y-62275D01*
X-1005864Y-61965D01*
X-1005251Y-61862D01*
X-1004484Y-62069D01*
X-1003947Y-62585D01*
X-1003794Y-63205D01*
X-1003871Y-63825D01*
X-1004177Y-64342D01*
X-1005711Y-65375D01*
X-1006401Y-66099D01*
X-1006861Y-67132D01*
X-1007014Y-68062D01*
X-1003794D01*
G01X-1025537Y-77062D02*
Y-70862D01*
X-1023621D01*
X-1023007Y-71172D01*
X-1022624Y-71585D01*
X-1022471Y-72412D01*
X-1022624Y-73239D01*
X-1023084Y-73755D01*
X-1023621Y-74065D01*
X-1025537D01*
G01X-1023621D02*
X-1022471Y-77062D01*
G01X-1019261Y-71895D02*
X-1018801Y-71275D01*
X-1018264Y-70965D01*
X-1017651Y-70862D01*
X-1016884Y-71069D01*
X-1016347Y-71585D01*
X-1016194Y-72205D01*
X-1016271Y-72825D01*
X-1016577Y-73342D01*
X-1018111Y-74375D01*
X-1018801Y-75099D01*
X-1019261Y-76132D01*
X-1019414Y-77062D01*
X-1016194D01*
G01X-1013061Y-71895D02*
X-1012601Y-71275D01*
X-1012064Y-70965D01*
X-1011451Y-70862D01*
X-1010684Y-71069D01*
X-1010147Y-71585D01*
X-1009994Y-72205D01*
X-1010071Y-72825D01*
X-1010377Y-73342D01*
X-1011911Y-74375D01*
X-1012601Y-75099D01*
X-1013061Y-76132D01*
X-1013214Y-77062D01*
X-1009994D01*
G01X-1005404D02*
Y-70862D01*
X-1006324Y-72102D01*
G01Y-77062D02*
X-1004484D01*
G01X-1024838Y-39780D02*
Y-45980D01*
G01X-1026601Y-39780D02*
X-1023075D01*
G01X-1020171Y-45980D02*
Y-39780D01*
X-1018331D01*
X-1017718Y-40090D01*
X-1017258Y-40813D01*
X-1017105Y-41640D01*
X-1017258Y-42467D01*
X-1017641Y-43087D01*
X-1018331Y-43397D01*
X-1020171D01*
G01X-1013895D02*
X-1013358Y-42673D01*
X-1012898Y-42260D01*
X-1012285Y-42053D01*
X-1011748Y-42260D01*
X-1011365Y-42673D01*
X-1011058Y-43293D01*
X-1010981Y-44017D01*
X-1011058Y-44637D01*
X-1011365Y-45257D01*
X-1011825Y-45773D01*
X-1012361Y-45980D01*
X-1012975Y-45773D01*
X-1013511Y-45154D01*
X-1013818Y-44223D01*
X-1013895Y-43190D01*
X-1013741Y-41847D01*
X-1013511Y-41123D01*
X-1013128Y-40400D01*
X-1012591Y-39883D01*
X-1012055Y-39780D01*
X-1011518Y-39987D01*
X-1011135Y-40503D01*
G01X-1007695Y-40813D02*
X-1007235Y-40193D01*
X-1006698Y-39883D01*
X-1006085Y-39780D01*
X-1005318Y-39987D01*
X-1004781Y-40503D01*
X-1004628Y-41123D01*
X-1004705Y-41743D01*
X-1005011Y-42260D01*
X-1006545Y-43293D01*
X-1007235Y-44017D01*
X-1007695Y-45050D01*
X-1007848Y-45980D01*
X-1004628D01*
G01X-1027204Y143005D02*
X-1021004D01*
Y146071D01*
G01X-1023587Y149281D02*
X-1024311Y149818D01*
X-1024724Y150278D01*
X-1024931Y150891D01*
X-1024724Y151428D01*
X-1024311Y151811D01*
X-1023691Y152118D01*
X-1022967Y152195D01*
X-1022347Y152118D01*
X-1021727Y151811D01*
X-1021211Y151351D01*
X-1021004Y150815D01*
X-1021211Y150201D01*
X-1021830Y149665D01*
X-1022761Y149358D01*
X-1023794Y149281D01*
X-1025137Y149435D01*
X-1025861Y149665D01*
X-1026584Y150048D01*
X-1027101Y150585D01*
X-1027204Y151121D01*
X-1026997Y151658D01*
X-1026481Y152041D01*
G01X-1015704Y155205D02*
X-1021904D01*
Y157121D01*
X-1021594Y157735D01*
X-1021181Y158118D01*
X-1020354Y158271D01*
X-1019527Y158118D01*
X-1019011Y157658D01*
X-1018701Y157121D01*
Y155205D01*
G01Y157121D02*
X-1015704Y158271D01*
G01Y162938D02*
X-1021904D01*
X-1020664Y162018D01*
G01X-1015704D02*
Y163858D01*
G01X-1018287Y167681D02*
X-1019011Y168218D01*
X-1019424Y168678D01*
X-1019631Y169291D01*
X-1019424Y169828D01*
X-1019011Y170211D01*
X-1018391Y170518D01*
X-1017667Y170595D01*
X-1017047Y170518D01*
X-1016427Y170211D01*
X-1015911Y169751D01*
X-1015704Y169215D01*
X-1015911Y168601D01*
X-1016530Y168065D01*
X-1017461Y167758D01*
X-1018494Y167681D01*
X-1019837Y167835D01*
X-1020561Y168065D01*
X-1021284Y168448D01*
X-1021801Y168985D01*
X-1021904Y169521D01*
X-1021697Y170058D01*
X-1021181Y170441D01*
G01X-1018287Y173881D02*
X-1019011Y174418D01*
X-1019424Y174878D01*
X-1019631Y175491D01*
X-1019424Y176028D01*
X-1019011Y176411D01*
X-1018391Y176718D01*
X-1017667Y176795D01*
X-1017047Y176718D01*
X-1016427Y176411D01*
X-1015911Y175951D01*
X-1015704Y175415D01*
X-1015911Y174801D01*
X-1016530Y174265D01*
X-1017461Y173958D01*
X-1018494Y173881D01*
X-1019837Y174035D01*
X-1020561Y174265D01*
X-1021284Y174648D01*
X-1021801Y175185D01*
X-1021904Y175721D01*
X-1021697Y176258D01*
X-1021181Y176641D01*
G01X-1029804Y179605D02*
X-1036004D01*
Y181521D01*
X-1035694Y182135D01*
X-1035281Y182518D01*
X-1034454Y182671D01*
X-1033627Y182518D01*
X-1033111Y182058D01*
X-1032801Y181521D01*
Y179605D01*
G01Y181521D02*
X-1029804Y182671D01*
G01Y187338D02*
X-1036004D01*
X-1034764Y186418D01*
G01X-1029804D02*
Y188258D01*
G01Y194458D02*
X-1036004D01*
X-1031561Y191621D01*
Y195455D01*
G01X-1029804Y199738D02*
X-1036004D01*
X-1034764Y198818D01*
G01X-1029804D02*
Y200658D01*
G01X-1021087Y182825D02*
X-1021397Y182365D01*
X-1021604Y181828D01*
Y181215D01*
X-1021294Y180525D01*
X-1020777Y179988D01*
X-1020157Y179605D01*
X-1019124Y179298D01*
X-1018194Y179221D01*
X-1017264Y179375D01*
X-1016644Y179605D01*
X-1016024Y180065D01*
X-1015611Y180601D01*
X-1015404Y181138D01*
Y181675D01*
X-1015611Y182211D01*
X-1015921Y182671D01*
X-1016334Y183055D01*
G01X-1015404Y187338D02*
X-1021604D01*
X-1020364Y186418D01*
G01X-1015404D02*
Y188258D01*
G01Y193538D02*
X-1015507Y194075D01*
X-1015817Y194688D01*
X-1016334Y195071D01*
X-1017057Y195225D01*
X-1017781Y195071D01*
X-1018401Y194611D01*
X-1018711Y193921D01*
Y193155D01*
X-1018917Y192695D01*
X-1019434Y192311D01*
X-1020157Y192158D01*
X-1020881Y192388D01*
X-1021397Y192925D01*
X-1021604Y193538D01*
X-1021397Y194151D01*
X-1020881Y194688D01*
X-1020157Y194918D01*
X-1019434Y194765D01*
X-1018917Y194381D01*
X-1018711Y193921D01*
Y193155D01*
X-1018401Y192465D01*
X-1017781Y192005D01*
X-1017057Y191851D01*
X-1016334Y192005D01*
X-1015817Y192388D01*
X-1015507Y193001D01*
X-1015404Y193538D01*
G01Y199585D02*
X-1016747Y199738D01*
X-1017884Y199968D01*
X-1018917Y200275D01*
X-1020054Y200658D01*
X-1021604Y201271D01*
Y198205D01*
G01X-1026317Y209721D02*
X-1026777Y210031D01*
X-1027314Y210238D01*
X-1027927D01*
X-1028617Y209928D01*
X-1029154Y209411D01*
X-1029537Y208791D01*
X-1029844Y207758D01*
X-1029921Y206828D01*
X-1029767Y205898D01*
X-1029537Y205278D01*
X-1029077Y204658D01*
X-1028541Y204245D01*
X-1028004Y204038D01*
X-1027467D01*
X-1026931Y204245D01*
X-1026471Y204555D01*
X-1026087Y204968D01*
G01X-1021804Y204038D02*
Y210238D01*
X-1022724Y208998D01*
G01Y204038D02*
X-1020884D01*
G01X-1016907Y204761D02*
X-1016371Y204245D01*
X-1015757Y204038D01*
X-1015144Y204245D01*
X-1014607Y204864D01*
X-1014224Y205795D01*
X-1014071Y206725D01*
Y207861D01*
X-1014224Y208791D01*
X-1014607Y209618D01*
X-1015067Y210031D01*
X-1015604Y210238D01*
X-1016217Y210031D01*
X-1016677Y209618D01*
X-1016984Y208998D01*
X-1017137Y208171D01*
X-1016984Y207448D01*
X-1016601Y206725D01*
X-1016141Y206311D01*
X-1015604Y206208D01*
X-1014991Y206415D01*
X-1014531Y206931D01*
X-1014071Y207861D01*
G01X-1009404Y204038D02*
Y210238D01*
X-1010324Y208998D01*
G01Y204038D02*
X-1008484D01*
G01X-1030709Y265230D02*
Y271430D01*
X-1028716Y266263D01*
X-1026723Y271430D01*
Y265230D01*
G01X-1020983D02*
X-1024049D01*
Y271430D01*
X-1020983D01*
G01X-1022209Y268433D02*
X-1024049D01*
G01X-1015396Y265230D02*
Y271430D01*
X-1018233Y266987D01*
X-1014399D01*
G01X-1020604Y343205D02*
X-1026804D01*
Y345121D01*
X-1026494Y345735D01*
X-1026081Y346118D01*
X-1025254Y346271D01*
X-1024427Y346118D01*
X-1023911Y345658D01*
X-1023601Y345121D01*
Y343205D01*
G01Y345121D02*
X-1020604Y346271D01*
G01X-1025771Y349481D02*
X-1026391Y349941D01*
X-1026701Y350478D01*
X-1026804Y351091D01*
X-1026597Y351858D01*
X-1026081Y352395D01*
X-1025461Y352548D01*
X-1024841Y352471D01*
X-1024324Y352165D01*
X-1023291Y350631D01*
X-1022567Y349941D01*
X-1021534Y349481D01*
X-1020604Y349328D01*
Y352548D01*
G01X-1023187Y355681D02*
X-1023911Y356218D01*
X-1024324Y356678D01*
X-1024531Y357291D01*
X-1024324Y357828D01*
X-1023911Y358211D01*
X-1023291Y358518D01*
X-1022567Y358595D01*
X-1021947Y358518D01*
X-1021327Y358211D01*
X-1020811Y357751D01*
X-1020604Y357215D01*
X-1020811Y356601D01*
X-1021430Y356065D01*
X-1022361Y355758D01*
X-1023394Y355681D01*
X-1024737Y355835D01*
X-1025461Y356065D01*
X-1026184Y356448D01*
X-1026701Y356985D01*
X-1026804Y357521D01*
X-1026597Y358058D01*
X-1026081Y358441D01*
G01X-1020604Y363338D02*
X-1020707Y363875D01*
X-1021017Y364488D01*
X-1021534Y364871D01*
X-1022257Y365025D01*
X-1022981Y364871D01*
X-1023601Y364411D01*
X-1023911Y363721D01*
Y362955D01*
X-1024117Y362495D01*
X-1024634Y362111D01*
X-1025357Y361958D01*
X-1026081Y362188D01*
X-1026597Y362725D01*
X-1026804Y363338D01*
X-1026597Y363951D01*
X-1026081Y364488D01*
X-1025357Y364718D01*
X-1024634Y364565D01*
X-1024117Y364181D01*
X-1023911Y363721D01*
Y362955D01*
X-1023601Y362265D01*
X-1022981Y361805D01*
X-1022257Y361651D01*
X-1021534Y361805D01*
X-1021017Y362188D01*
X-1020707Y362801D01*
X-1020604Y363338D01*
G01X-1017559Y378448D02*
X-1017406Y379791D01*
X-1017176Y380928D01*
X-1016869Y381961D01*
X-1016486Y383098D01*
X-1015873Y384648D01*
X-1018939D01*
G01X-1019704Y431038D02*
Y437238D01*
X-1020624Y435998D01*
G01Y431038D02*
X-1018784D01*
G01X-1030709Y469954D02*
Y476154D01*
X-1028716Y470987D01*
X-1026723Y476154D01*
Y469954D01*
G01X-1020983D02*
X-1024049D01*
Y476154D01*
X-1020983D01*
G01X-1022209Y473157D02*
X-1024049D01*
G01X-1018003Y471194D02*
X-1017543Y470471D01*
X-1016929Y470057D01*
X-1016239Y469954D01*
X-1015626Y470057D01*
X-1015013Y470574D01*
X-1014629Y471194D01*
X-1014553Y471814D01*
X-1014706Y472537D01*
X-1015243Y473054D01*
X-1015779Y473261D01*
X-1016469D01*
G01X-1015779D02*
X-1015319Y473571D01*
X-1014936Y474087D01*
X-1014783Y474707D01*
X-1014936Y475327D01*
X-1015319Y475844D01*
X-1016009Y476154D01*
X-1016699Y476051D01*
X-1017389Y475637D01*
G01X-1017591Y-180830D02*
Y-185273D01*
X-1017284Y-186204D01*
X-1016671Y-186823D01*
X-1015904Y-187030D01*
X-1015137Y-186823D01*
X-1014524Y-186204D01*
X-1014217Y-185273D01*
Y-180830D01*
G01X-1011391Y-185790D02*
X-1010931Y-186513D01*
X-1010317Y-186927D01*
X-1009627Y-187030D01*
X-1009014Y-186927D01*
X-1008401Y-186410D01*
X-1008017Y-185790D01*
X-1007941Y-185170D01*
X-1008094Y-184447D01*
X-1008631Y-183930D01*
X-1009167Y-183723D01*
X-1009857D01*
G01X-1009167D02*
X-1008707Y-183413D01*
X-1008324Y-182897D01*
X-1008171Y-182277D01*
X-1008324Y-181657D01*
X-1008707Y-181140D01*
X-1009397Y-180830D01*
X-1010087Y-180933D01*
X-1010777Y-181347D01*
G01X-1003657Y-187030D02*
X-1003504Y-185687D01*
X-1003274Y-184550D01*
X-1002967Y-183517D01*
X-1002584Y-182380D01*
X-1001971Y-180830D01*
X-1005037D01*
G01X-1011317Y146421D02*
X-1011777Y146731D01*
X-1012314Y146938D01*
X-1012927D01*
X-1013617Y146628D01*
X-1014154Y146111D01*
X-1014537Y145491D01*
X-1014844Y144458D01*
X-1014921Y143528D01*
X-1014767Y142598D01*
X-1014537Y141978D01*
X-1014077Y141358D01*
X-1013541Y140945D01*
X-1013004Y140738D01*
X-1012467D01*
X-1011931Y140945D01*
X-1011471Y141255D01*
X-1011087Y141668D01*
G01X-1006804Y140738D02*
Y146938D01*
X-1007724Y145698D01*
G01Y140738D02*
X-1005884D01*
G01X-1000604D02*
X-1000067Y140841D01*
X-999454Y141151D01*
X-999071Y141668D01*
X-998917Y142391D01*
X-999071Y143115D01*
X-999531Y143735D01*
X-1000221Y144045D01*
X-1000987D01*
X-1001447Y144251D01*
X-1001831Y144768D01*
X-1001984Y145491D01*
X-1001754Y146215D01*
X-1001217Y146731D01*
X-1000604Y146938D01*
X-999991Y146731D01*
X-999454Y146215D01*
X-999224Y145491D01*
X-999377Y144768D01*
X-999761Y144251D01*
X-1000221Y144045D01*
X-1000987D01*
X-1001677Y143735D01*
X-1002137Y143115D01*
X-1002291Y142391D01*
X-1002137Y141668D01*
X-1001754Y141151D01*
X-1001141Y140841D01*
X-1000604Y140738D01*
G01X-996091Y141978D02*
X-995631Y141255D01*
X-995017Y140841D01*
X-994327Y140738D01*
X-993714Y140841D01*
X-993101Y141358D01*
X-992717Y141978D01*
X-992641Y142598D01*
X-992794Y143321D01*
X-993331Y143838D01*
X-993867Y144045D01*
X-994557D01*
G01X-993867D02*
X-993407Y144355D01*
X-993024Y144871D01*
X-992871Y145491D01*
X-993024Y146111D01*
X-993407Y146628D01*
X-994097Y146938D01*
X-994787Y146835D01*
X-995477Y146421D01*
G01X-1008917Y158421D02*
X-1009377Y158731D01*
X-1009914Y158938D01*
X-1010527D01*
X-1011217Y158628D01*
X-1011754Y158111D01*
X-1012137Y157491D01*
X-1012444Y156458D01*
X-1012521Y155528D01*
X-1012367Y154598D01*
X-1012137Y153978D01*
X-1011677Y153358D01*
X-1011141Y152945D01*
X-1010604Y152738D01*
X-1010067D01*
X-1009531Y152945D01*
X-1009071Y153255D01*
X-1008687Y153668D01*
G01X-1004404Y152738D02*
Y158938D01*
X-1005324Y157698D01*
G01Y152738D02*
X-1003484D01*
G01X-998204D02*
X-997667Y152841D01*
X-997054Y153151D01*
X-996671Y153668D01*
X-996517Y154391D01*
X-996671Y155115D01*
X-997131Y155735D01*
X-997821Y156045D01*
X-998587D01*
X-999047Y156251D01*
X-999431Y156768D01*
X-999584Y157491D01*
X-999354Y158215D01*
X-998817Y158731D01*
X-998204Y158938D01*
X-997591Y158731D01*
X-997054Y158215D01*
X-996824Y157491D01*
X-996977Y156768D01*
X-997361Y156251D01*
X-997821Y156045D01*
X-998587D01*
X-999277Y155735D01*
X-999737Y155115D01*
X-999891Y154391D01*
X-999737Y153668D01*
X-999354Y153151D01*
X-998741Y152841D01*
X-998204Y152738D01*
G01X-993461Y155321D02*
X-992924Y156045D01*
X-992464Y156458D01*
X-991851Y156665D01*
X-991314Y156458D01*
X-990931Y156045D01*
X-990624Y155425D01*
X-990547Y154701D01*
X-990624Y154081D01*
X-990931Y153461D01*
X-991391Y152945D01*
X-991927Y152738D01*
X-992541Y152945D01*
X-993077Y153564D01*
X-993384Y154495D01*
X-993461Y155528D01*
X-993307Y156871D01*
X-993077Y157595D01*
X-992694Y158318D01*
X-992157Y158835D01*
X-991621Y158938D01*
X-991084Y158731D01*
X-990701Y158215D01*
G01X-1005717Y171021D02*
X-1006177Y171331D01*
X-1006714Y171538D01*
X-1007327D01*
X-1008017Y171228D01*
X-1008554Y170711D01*
X-1008937Y170091D01*
X-1009244Y169058D01*
X-1009321Y168128D01*
X-1009167Y167198D01*
X-1008937Y166578D01*
X-1008477Y165958D01*
X-1007941Y165545D01*
X-1007404Y165338D01*
X-1006867D01*
X-1006331Y165545D01*
X-1005871Y165855D01*
X-1005487Y166268D01*
G01X-1001204Y165338D02*
Y171538D01*
X-1002124Y170298D01*
G01Y165338D02*
X-1000284D01*
G01X-995004D02*
X-994467Y165441D01*
X-993854Y165751D01*
X-993471Y166268D01*
X-993317Y166991D01*
X-993471Y167715D01*
X-993931Y168335D01*
X-994621Y168645D01*
X-995387D01*
X-995847Y168851D01*
X-996231Y169368D01*
X-996384Y170091D01*
X-996154Y170815D01*
X-995617Y171331D01*
X-995004Y171538D01*
X-994391Y171331D01*
X-993854Y170815D01*
X-993624Y170091D01*
X-993777Y169368D01*
X-994161Y168851D01*
X-994621Y168645D01*
X-995387D01*
X-996077Y168335D01*
X-996537Y167715D01*
X-996691Y166991D01*
X-996537Y166268D01*
X-996154Y165751D01*
X-995541Y165441D01*
X-995004Y165338D01*
G01X-990107Y166061D02*
X-989571Y165545D01*
X-988957Y165338D01*
X-988344Y165545D01*
X-987807Y166164D01*
X-987424Y167095D01*
X-987271Y168025D01*
Y169161D01*
X-987424Y170091D01*
X-987807Y170918D01*
X-988267Y171331D01*
X-988804Y171538D01*
X-989417Y171331D01*
X-989877Y170918D01*
X-990184Y170298D01*
X-990337Y169471D01*
X-990184Y168748D01*
X-989801Y168025D01*
X-989341Y167611D01*
X-988804Y167508D01*
X-988191Y167715D01*
X-987731Y168231D01*
X-987271Y169161D01*
G01X-1006604Y176938D02*
X-1012804D01*
X-1011564Y176018D01*
G01X-1006604D02*
Y177858D01*
G01X-1012804Y183138D02*
X-1012597Y182525D01*
X-1012081Y182065D01*
X-1011461Y181758D01*
X-1010634Y181528D01*
X-1009704Y181451D01*
X-1008774Y181528D01*
X-1007947Y181758D01*
X-1007327Y182065D01*
X-1006811Y182525D01*
X-1006604Y183138D01*
X-1006811Y183751D01*
X-1007327Y184211D01*
X-1007947Y184518D01*
X-1008774Y184748D01*
X-1009704Y184825D01*
X-1010634Y184748D01*
X-1011461Y184518D01*
X-1012081Y184211D01*
X-1012597Y183751D01*
X-1012804Y183138D01*
G01X-1011161Y198521D02*
X-1010624Y199245D01*
X-1010164Y199658D01*
X-1009551Y199865D01*
X-1009014Y199658D01*
X-1008631Y199245D01*
X-1008324Y198625D01*
X-1008247Y197901D01*
X-1008324Y197281D01*
X-1008631Y196661D01*
X-1009091Y196145D01*
X-1009627Y195938D01*
X-1010241Y196145D01*
X-1010777Y196764D01*
X-1011084Y197695D01*
X-1011161Y198728D01*
X-1011007Y200071D01*
X-1010777Y200795D01*
X-1010394Y201518D01*
X-1009857Y202035D01*
X-1009321Y202138D01*
X-1008784Y201931D01*
X-1008401Y201415D01*
G01X-1010604Y343205D02*
X-1016804D01*
Y345121D01*
X-1016494Y345735D01*
X-1016081Y346118D01*
X-1015254Y346271D01*
X-1014427Y346118D01*
X-1013911Y345658D01*
X-1013601Y345121D01*
Y343205D01*
G01Y345121D02*
X-1010604Y346271D01*
G01Y350938D02*
X-1016804D01*
X-1015564Y350018D01*
G01X-1010604D02*
Y351858D01*
G01Y357138D02*
X-1016804D01*
X-1015564Y356218D01*
G01X-1010604D02*
Y358058D01*
G01X-1015771Y361881D02*
X-1016391Y362341D01*
X-1016701Y362878D01*
X-1016804Y363491D01*
X-1016597Y364258D01*
X-1016081Y364795D01*
X-1015461Y364948D01*
X-1014841Y364871D01*
X-1014324Y364565D01*
X-1013291Y363031D01*
X-1012567Y362341D01*
X-1011534Y361881D01*
X-1010604Y361728D01*
Y364948D01*
G01X-1003287Y418525D02*
X-1003597Y418065D01*
X-1003804Y417528D01*
Y416915D01*
X-1003494Y416225D01*
X-1002977Y415688D01*
X-1002357Y415305D01*
X-1001324Y414998D01*
X-1000394Y414921D01*
X-999464Y415075D01*
X-998844Y415305D01*
X-998224Y415765D01*
X-997811Y416301D01*
X-997604Y416838D01*
Y417375D01*
X-997811Y417911D01*
X-998121Y418371D01*
X-998534Y418755D01*
G01X-997604Y422885D02*
X-998947Y423038D01*
X-1000084Y423268D01*
X-1001117Y423575D01*
X-1002254Y423958D01*
X-1003804Y424571D01*
Y421505D01*
G01X-1002771Y427781D02*
X-1003391Y428241D01*
X-1003701Y428778D01*
X-1003804Y429391D01*
X-1003597Y430158D01*
X-1003081Y430695D01*
X-1002461Y430848D01*
X-1001841Y430771D01*
X-1001324Y430465D01*
X-1000291Y428931D01*
X-999567Y428241D01*
X-998534Y427781D01*
X-997604Y427628D01*
Y430848D01*
G01X-981717Y170021D02*
X-982177Y170331D01*
X-982714Y170538D01*
X-983327D01*
X-984017Y170228D01*
X-984554Y169711D01*
X-984937Y169091D01*
X-985244Y168058D01*
X-985321Y167128D01*
X-985167Y166198D01*
X-984937Y165578D01*
X-984477Y164958D01*
X-983941Y164545D01*
X-983404Y164338D01*
X-982867D01*
X-982331Y164545D01*
X-981871Y164855D01*
X-981487Y165268D01*
G01X-977204Y164338D02*
Y170538D01*
X-978124Y169298D01*
G01Y164338D02*
X-976284D01*
G01X-972307Y165061D02*
X-971771Y164545D01*
X-971157Y164338D01*
X-970544Y164545D01*
X-970007Y165164D01*
X-969624Y166095D01*
X-969471Y167025D01*
Y168161D01*
X-969624Y169091D01*
X-970007Y169918D01*
X-970467Y170331D01*
X-971004Y170538D01*
X-971617Y170331D01*
X-972077Y169918D01*
X-972384Y169298D01*
X-972537Y168471D01*
X-972384Y167748D01*
X-972001Y167025D01*
X-971541Y166611D01*
X-971004Y166508D01*
X-970391Y166715D01*
X-969931Y167231D01*
X-969471Y168161D01*
G01X-964957Y164338D02*
X-964804Y165681D01*
X-964574Y166818D01*
X-964267Y167851D01*
X-963884Y168988D01*
X-963271Y170538D01*
X-966337D01*
G01X-999003Y195820D02*
Y191377D01*
X-998696Y190446D01*
X-998083Y189827D01*
X-997316Y189620D01*
X-996549Y189827D01*
X-995936Y190446D01*
X-995629Y191377D01*
Y195820D01*
G01X-992573Y194787D02*
X-992113Y195407D01*
X-991576Y195717D01*
X-990963Y195820D01*
X-990196Y195613D01*
X-989659Y195097D01*
X-989506Y194477D01*
X-989583Y193857D01*
X-989889Y193340D01*
X-991423Y192307D01*
X-992113Y191583D01*
X-992573Y190550D01*
X-992726Y189620D01*
X-989506D01*
G01X-984916D02*
Y195820D01*
X-985836Y194580D01*
G01Y189620D02*
X-983996D01*
G01X-996317Y406621D02*
X-996777Y406931D01*
X-997314Y407138D01*
X-997927D01*
X-998617Y406828D01*
X-999154Y406311D01*
X-999537Y405691D01*
X-999844Y404658D01*
X-999921Y403728D01*
X-999767Y402798D01*
X-999537Y402178D01*
X-999077Y401558D01*
X-998541Y401145D01*
X-998004Y400938D01*
X-997467D01*
X-996931Y401145D01*
X-996471Y401455D01*
X-996087Y401868D01*
G01X-993261Y406105D02*
X-992801Y406725D01*
X-992264Y407035D01*
X-991651Y407138D01*
X-990884Y406931D01*
X-990347Y406415D01*
X-990194Y405795D01*
X-990271Y405175D01*
X-990577Y404658D01*
X-992111Y403625D01*
X-992801Y402901D01*
X-993261Y401868D01*
X-993414Y400938D01*
X-990194D01*
G01X-985757D02*
X-985604Y402281D01*
X-985374Y403418D01*
X-985067Y404451D01*
X-984684Y405588D01*
X-984071Y407138D01*
X-987137D01*
G01X-980861Y406105D02*
X-980401Y406725D01*
X-979864Y407035D01*
X-979251Y407138D01*
X-978484Y406931D01*
X-977947Y406415D01*
X-977794Y405795D01*
X-977871Y405175D01*
X-978177Y404658D01*
X-979711Y403625D01*
X-980401Y402901D01*
X-980861Y401868D01*
X-981014Y400938D01*
X-977794D01*
G01X-989970Y417743D02*
X-983770D01*
Y420809D01*
G01Y425476D02*
X-989970D01*
X-988730Y424556D01*
G01X-983770D02*
Y426396D01*
G01X-984700Y429989D02*
X-984183Y430449D01*
X-983873Y430986D01*
X-983770Y431676D01*
X-983977Y432366D01*
X-984390Y432903D01*
X-985113Y433286D01*
X-985940Y433363D01*
X-986767Y433209D01*
X-987283Y432826D01*
X-987697Y432289D01*
X-987800Y431753D01*
X-987697Y431216D01*
X-987283Y430526D01*
X-989970Y430756D01*
Y432826D01*
G01X-975207Y-205239D02*
X-974671Y-205755D01*
X-974057Y-205962D01*
X-973444Y-205755D01*
X-972907Y-205136D01*
X-972524Y-204205D01*
X-972371Y-203275D01*
Y-202139D01*
X-972524Y-201209D01*
X-972907Y-200382D01*
X-973367Y-199969D01*
X-973904Y-199762D01*
X-974517Y-199969D01*
X-974977Y-200382D01*
X-975284Y-201002D01*
X-975437Y-201829D01*
X-975284Y-202552D01*
X-974901Y-203275D01*
X-974441Y-203689D01*
X-973904Y-203792D01*
X-973291Y-203585D01*
X-972831Y-203069D01*
X-972371Y-202139D01*
G01X-967537Y-201030D02*
Y-194830D01*
X-965621D01*
X-965007Y-195140D01*
X-964624Y-195553D01*
X-964471Y-196380D01*
X-964624Y-197207D01*
X-965084Y-197723D01*
X-965621Y-198033D01*
X-967537D01*
G01X-965621D02*
X-964471Y-201030D01*
G01X-958884D02*
Y-194830D01*
X-961721Y-199273D01*
X-957887D01*
G01X-953757Y-201030D02*
X-953604Y-199687D01*
X-953374Y-198550D01*
X-953067Y-197517D01*
X-952684Y-196380D01*
X-952071Y-194830D01*
X-955137D01*
G01X-948861Y-198447D02*
X-948324Y-197723D01*
X-947864Y-197310D01*
X-947251Y-197103D01*
X-946714Y-197310D01*
X-946331Y-197723D01*
X-946024Y-198343D01*
X-945947Y-199067D01*
X-946024Y-199687D01*
X-946331Y-200307D01*
X-946791Y-200823D01*
X-947327Y-201030D01*
X-947941Y-200823D01*
X-948477Y-200204D01*
X-948784Y-199273D01*
X-948861Y-198240D01*
X-948707Y-196897D01*
X-948477Y-196173D01*
X-948094Y-195450D01*
X-947557Y-194933D01*
X-947021Y-194830D01*
X-946484Y-195037D01*
X-946101Y-195553D01*
G01X-967537Y-189030D02*
Y-182830D01*
X-965621D01*
X-965007Y-183140D01*
X-964624Y-183553D01*
X-964471Y-184380D01*
X-964624Y-185207D01*
X-965084Y-185723D01*
X-965621Y-186033D01*
X-967537D01*
G01X-965621D02*
X-964471Y-189030D01*
G01X-958884D02*
Y-182830D01*
X-961721Y-187273D01*
X-957887D01*
G01X-953757Y-189030D02*
X-953604Y-187687D01*
X-953374Y-186550D01*
X-953067Y-185517D01*
X-952684Y-184380D01*
X-952071Y-182830D01*
X-955137D01*
G01X-947557Y-189030D02*
X-947404Y-187687D01*
X-947174Y-186550D01*
X-946867Y-185517D01*
X-946484Y-184380D01*
X-945871Y-182830D01*
X-948937D01*
G01X-974404Y-168962D02*
Y-162762D01*
X-975324Y-164002D01*
G01Y-168962D02*
X-973484D01*
G01X-969661Y-166379D02*
X-969124Y-165655D01*
X-968664Y-165242D01*
X-968051Y-165035D01*
X-967514Y-165242D01*
X-967131Y-165655D01*
X-966824Y-166275D01*
X-966747Y-166999D01*
X-966824Y-167619D01*
X-967131Y-168239D01*
X-967591Y-168755D01*
X-968127Y-168962D01*
X-968741Y-168755D01*
X-969277Y-168136D01*
X-969584Y-167205D01*
X-969661Y-166172D01*
X-969507Y-164829D01*
X-969277Y-164105D01*
X-968894Y-163382D01*
X-968357Y-162865D01*
X-967821Y-162762D01*
X-967284Y-162969D01*
X-966901Y-163485D01*
G01X-967537Y-179030D02*
Y-172830D01*
X-965621D01*
X-965007Y-173140D01*
X-964624Y-173553D01*
X-964471Y-174380D01*
X-964624Y-175207D01*
X-965084Y-175723D01*
X-965621Y-176033D01*
X-967537D01*
G01X-965621D02*
X-964471Y-179030D01*
G01X-958884D02*
Y-172830D01*
X-961721Y-177273D01*
X-957887D01*
G01X-953604Y-179030D02*
X-953067Y-178927D01*
X-952454Y-178617D01*
X-952071Y-178100D01*
X-951917Y-177377D01*
X-952071Y-176653D01*
X-952531Y-176033D01*
X-953221Y-175723D01*
X-953987D01*
X-954447Y-175517D01*
X-954831Y-175000D01*
X-954984Y-174277D01*
X-954754Y-173553D01*
X-954217Y-173037D01*
X-953604Y-172830D01*
X-952991Y-173037D01*
X-952454Y-173553D01*
X-952224Y-174277D01*
X-952377Y-175000D01*
X-952761Y-175517D01*
X-953221Y-175723D01*
X-953987D01*
X-954677Y-176033D01*
X-955137Y-176653D01*
X-955291Y-177377D01*
X-955137Y-178100D01*
X-954754Y-178617D01*
X-954141Y-178927D01*
X-953604Y-179030D01*
G01X-946484D02*
Y-172830D01*
X-949321Y-177273D01*
X-945487D01*
G01X-970317Y-100379D02*
X-970777Y-100069D01*
X-971314Y-99862D01*
X-971927D01*
X-972617Y-100172D01*
X-973154Y-100689D01*
X-973537Y-101309D01*
X-973844Y-102342D01*
X-973921Y-103272D01*
X-973767Y-104202D01*
X-973537Y-104822D01*
X-973077Y-105442D01*
X-972541Y-105855D01*
X-972004Y-106062D01*
X-971467D01*
X-970931Y-105855D01*
X-970471Y-105545D01*
X-970087Y-105132D01*
G01X-965804Y-106062D02*
Y-99862D01*
X-966724Y-101102D01*
G01Y-106062D02*
X-964884D01*
G01X-959757D02*
X-959604Y-104719D01*
X-959374Y-103582D01*
X-959067Y-102549D01*
X-958684Y-101412D01*
X-958071Y-99862D01*
X-961137D01*
G01X-955091Y-104822D02*
X-954631Y-105545D01*
X-954017Y-105959D01*
X-953327Y-106062D01*
X-952714Y-105959D01*
X-952101Y-105442D01*
X-951717Y-104822D01*
X-951641Y-104202D01*
X-951794Y-103479D01*
X-952331Y-102962D01*
X-952867Y-102755D01*
X-953557D01*
G01X-952867D02*
X-952407Y-102445D01*
X-952024Y-101929D01*
X-951871Y-101309D01*
X-952024Y-100689D01*
X-952407Y-100172D01*
X-953097Y-99862D01*
X-953787Y-99965D01*
X-954477Y-100379D01*
G01X-969317Y-79379D02*
X-969777Y-79069D01*
X-970314Y-78862D01*
X-970927D01*
X-971617Y-79172D01*
X-972154Y-79689D01*
X-972537Y-80309D01*
X-972844Y-81342D01*
X-972921Y-82272D01*
X-972767Y-83202D01*
X-972537Y-83822D01*
X-972077Y-84442D01*
X-971541Y-84855D01*
X-971004Y-85062D01*
X-970467D01*
X-969931Y-84855D01*
X-969471Y-84545D01*
X-969087Y-84132D01*
G01X-964804Y-85062D02*
Y-78862D01*
X-965724Y-80102D01*
G01Y-85062D02*
X-963884D01*
G01X-958757D02*
X-958604Y-83719D01*
X-958374Y-82582D01*
X-958067Y-81549D01*
X-957684Y-80412D01*
X-957071Y-78862D01*
X-960137D01*
G01X-953861Y-82479D02*
X-953324Y-81755D01*
X-952864Y-81342D01*
X-952251Y-81135D01*
X-951714Y-81342D01*
X-951331Y-81755D01*
X-951024Y-82375D01*
X-950947Y-83099D01*
X-951024Y-83719D01*
X-951331Y-84339D01*
X-951791Y-84855D01*
X-952327Y-85062D01*
X-952941Y-84855D01*
X-953477Y-84236D01*
X-953784Y-83305D01*
X-953861Y-82272D01*
X-953707Y-80929D01*
X-953477Y-80205D01*
X-953094Y-79482D01*
X-952557Y-78965D01*
X-952021Y-78862D01*
X-951484Y-79069D01*
X-951101Y-79585D01*
G01X-969317Y-54379D02*
X-969777Y-54069D01*
X-970314Y-53862D01*
X-970927D01*
X-971617Y-54172D01*
X-972154Y-54689D01*
X-972537Y-55309D01*
X-972844Y-56342D01*
X-972921Y-57272D01*
X-972767Y-58202D01*
X-972537Y-58822D01*
X-972077Y-59442D01*
X-971541Y-59855D01*
X-971004Y-60062D01*
X-970467D01*
X-969931Y-59855D01*
X-969471Y-59545D01*
X-969087Y-59132D01*
G01X-964804Y-60062D02*
Y-53862D01*
X-965724Y-55102D01*
G01Y-60062D02*
X-963884D01*
G01X-958757D02*
X-958604Y-58719D01*
X-958374Y-57582D01*
X-958067Y-56549D01*
X-957684Y-55412D01*
X-957071Y-53862D01*
X-960137D01*
G01X-952557Y-60062D02*
X-952404Y-58719D01*
X-952174Y-57582D01*
X-951867Y-56549D01*
X-951484Y-55412D01*
X-950871Y-53862D01*
X-953937D01*
G01X-969317Y-29379D02*
X-969777Y-29069D01*
X-970314Y-28862D01*
X-970927D01*
X-971617Y-29172D01*
X-972154Y-29689D01*
X-972537Y-30309D01*
X-972844Y-31342D01*
X-972921Y-32272D01*
X-972767Y-33202D01*
X-972537Y-33822D01*
X-972077Y-34442D01*
X-971541Y-34855D01*
X-971004Y-35062D01*
X-970467D01*
X-969931Y-34855D01*
X-969471Y-34545D01*
X-969087Y-34132D01*
G01X-964804Y-35062D02*
Y-28862D01*
X-965724Y-30102D01*
G01Y-35062D02*
X-963884D01*
G01X-958757D02*
X-958604Y-33719D01*
X-958374Y-32582D01*
X-958067Y-31549D01*
X-957684Y-30412D01*
X-957071Y-28862D01*
X-960137D01*
G01X-954091Y-34132D02*
X-953631Y-34649D01*
X-953094Y-34959D01*
X-952404Y-35062D01*
X-951714Y-34855D01*
X-951177Y-34442D01*
X-950794Y-33719D01*
X-950717Y-32892D01*
X-950871Y-32065D01*
X-951254Y-31549D01*
X-951791Y-31135D01*
X-952327Y-31032D01*
X-952864Y-31135D01*
X-953554Y-31549D01*
X-953324Y-28862D01*
X-951254D01*
G01X-975999Y-2696D02*
Y-8896D01*
X-972933D01*
G01X-968266D02*
Y-2696D01*
X-969186Y-3936D01*
G01Y-8896D02*
X-967346D01*
G01X-963523Y-3729D02*
X-963063Y-3109D01*
X-962526Y-2799D01*
X-961913Y-2696D01*
X-961146Y-2903D01*
X-960609Y-3419D01*
X-960456Y-4039D01*
X-960533Y-4659D01*
X-960839Y-5176D01*
X-962373Y-6209D01*
X-963063Y-6933D01*
X-963523Y-7966D01*
X-963676Y-8896D01*
X-960456D01*
G01X-979317Y155821D02*
X-979777Y156131D01*
X-980314Y156338D01*
X-980927D01*
X-981617Y156028D01*
X-982154Y155511D01*
X-982537Y154891D01*
X-982844Y153858D01*
X-982921Y152928D01*
X-982767Y151998D01*
X-982537Y151378D01*
X-982077Y150758D01*
X-981541Y150345D01*
X-981004Y150138D01*
X-980467D01*
X-979931Y150345D01*
X-979471Y150655D01*
X-979087Y151068D01*
G01X-974804Y150138D02*
Y156338D01*
X-975724Y155098D01*
G01Y150138D02*
X-973884D01*
G01X-969907Y150861D02*
X-969371Y150345D01*
X-968757Y150138D01*
X-968144Y150345D01*
X-967607Y150964D01*
X-967224Y151895D01*
X-967071Y152825D01*
Y153961D01*
X-967224Y154891D01*
X-967607Y155718D01*
X-968067Y156131D01*
X-968604Y156338D01*
X-969217Y156131D01*
X-969677Y155718D01*
X-969984Y155098D01*
X-970137Y154271D01*
X-969984Y153548D01*
X-969601Y152825D01*
X-969141Y152411D01*
X-968604Y152308D01*
X-967991Y152515D01*
X-967531Y153031D01*
X-967071Y153961D01*
G01X-964091Y151068D02*
X-963631Y150551D01*
X-963094Y150241D01*
X-962404Y150138D01*
X-961714Y150345D01*
X-961177Y150758D01*
X-960794Y151481D01*
X-960717Y152308D01*
X-960871Y153135D01*
X-961254Y153651D01*
X-961791Y154065D01*
X-962327Y154168D01*
X-962864Y154065D01*
X-963554Y153651D01*
X-963324Y156338D01*
X-961254D01*
G01X-968543Y198808D02*
X-968083Y198291D01*
X-967546Y197981D01*
X-966856Y197878D01*
X-966166Y198085D01*
X-965629Y198498D01*
X-965246Y199221D01*
X-965169Y200048D01*
X-965323Y200875D01*
X-965706Y201391D01*
X-966243Y201805D01*
X-966779Y201908D01*
X-967316Y201805D01*
X-968006Y201391D01*
X-967776Y204078D01*
X-965706D01*
G01X-961217Y-162315D02*
X-961677Y-162005D01*
X-962214Y-161798D01*
X-962827D01*
X-963517Y-162108D01*
X-964054Y-162625D01*
X-964437Y-163245D01*
X-964744Y-164278D01*
X-964821Y-165208D01*
X-964667Y-166138D01*
X-964437Y-166758D01*
X-963977Y-167378D01*
X-963441Y-167791D01*
X-962904Y-167998D01*
X-962367D01*
X-961831Y-167791D01*
X-961371Y-167481D01*
X-960987Y-167068D01*
G01X-958007Y-167275D02*
X-957471Y-167791D01*
X-956857Y-167998D01*
X-956244Y-167791D01*
X-955707Y-167172D01*
X-955324Y-166241D01*
X-955171Y-165311D01*
Y-164175D01*
X-955324Y-163245D01*
X-955707Y-162418D01*
X-956167Y-162005D01*
X-956704Y-161798D01*
X-957317Y-162005D01*
X-957777Y-162418D01*
X-958084Y-163038D01*
X-958237Y-163865D01*
X-958084Y-164588D01*
X-957701Y-165311D01*
X-957241Y-165725D01*
X-956704Y-165828D01*
X-956091Y-165621D01*
X-955631Y-165105D01*
X-955171Y-164175D01*
G01X-951961Y-162831D02*
X-951501Y-162211D01*
X-950964Y-161901D01*
X-950351Y-161798D01*
X-949584Y-162005D01*
X-949047Y-162521D01*
X-948894Y-163141D01*
X-948971Y-163761D01*
X-949277Y-164278D01*
X-950811Y-165311D01*
X-951501Y-166035D01*
X-951961Y-167068D01*
X-952114Y-167998D01*
X-948894D01*
G01X-951004Y159338D02*
Y153138D01*
G01X-952767Y159338D02*
X-949241D01*
G01X-946337Y153138D02*
Y159338D01*
X-944497D01*
X-943884Y159028D01*
X-943424Y158305D01*
X-943271Y157478D01*
X-943424Y156651D01*
X-943807Y156031D01*
X-944497Y155721D01*
X-946337D01*
G01X-940291Y154068D02*
X-939831Y153551D01*
X-939294Y153241D01*
X-938604Y153138D01*
X-937914Y153345D01*
X-937377Y153758D01*
X-936994Y154481D01*
X-936917Y155308D01*
X-937071Y156135D01*
X-937454Y156651D01*
X-937991Y157065D01*
X-938527Y157168D01*
X-939064Y157065D01*
X-939754Y156651D01*
X-939524Y159338D01*
X-937454D01*
G01X-933861Y155721D02*
X-933324Y156445D01*
X-932864Y156858D01*
X-932251Y157065D01*
X-931714Y156858D01*
X-931331Y156445D01*
X-931024Y155825D01*
X-930947Y155101D01*
X-931024Y154481D01*
X-931331Y153861D01*
X-931791Y153345D01*
X-932327Y153138D01*
X-932941Y153345D01*
X-933477Y153964D01*
X-933784Y154895D01*
X-933861Y155928D01*
X-933707Y157271D01*
X-933477Y157995D01*
X-933094Y158718D01*
X-932557Y159235D01*
X-932021Y159338D01*
X-931484Y159131D01*
X-931101Y158615D01*
G01X-952004Y164605D02*
X-958204D01*
Y166521D01*
X-957894Y167135D01*
X-957481Y167518D01*
X-956654Y167671D01*
X-955827Y167518D01*
X-955311Y167058D01*
X-955001Y166521D01*
Y164605D01*
G01Y166521D02*
X-952004Y167671D01*
G01Y172338D02*
X-958204D01*
X-956964Y171418D01*
G01X-952004D02*
Y173258D01*
G01Y178538D02*
X-952107Y179075D01*
X-952417Y179688D01*
X-952934Y180071D01*
X-953657Y180225D01*
X-954381Y180071D01*
X-955001Y179611D01*
X-955311Y178921D01*
Y178155D01*
X-955517Y177695D01*
X-956034Y177311D01*
X-956757Y177158D01*
X-957481Y177388D01*
X-957997Y177925D01*
X-958204Y178538D01*
X-957997Y179151D01*
X-957481Y179688D01*
X-956757Y179918D01*
X-956034Y179765D01*
X-955517Y179381D01*
X-955311Y178921D01*
Y178155D01*
X-955001Y177465D01*
X-954381Y177005D01*
X-953657Y176851D01*
X-952934Y177005D01*
X-952417Y177388D01*
X-952107Y178001D01*
X-952004Y178538D01*
G01Y184585D02*
X-953347Y184738D01*
X-954484Y184968D01*
X-955517Y185275D01*
X-956654Y185658D01*
X-958204Y186271D01*
Y183205D01*
G01X-962317Y196621D02*
X-962777Y196931D01*
X-963314Y197138D01*
X-963927D01*
X-964617Y196828D01*
X-965154Y196311D01*
X-965537Y195691D01*
X-965844Y194658D01*
X-965921Y193728D01*
X-965767Y192798D01*
X-965537Y192178D01*
X-965077Y191558D01*
X-964541Y191145D01*
X-964004Y190938D01*
X-963467D01*
X-962931Y191145D01*
X-962471Y191455D01*
X-962087Y191868D01*
G01X-957804Y190938D02*
Y197138D01*
X-958724Y195898D01*
G01Y190938D02*
X-956884D01*
G01X-952907Y191661D02*
X-952371Y191145D01*
X-951757Y190938D01*
X-951144Y191145D01*
X-950607Y191764D01*
X-950224Y192695D01*
X-950071Y193625D01*
Y194761D01*
X-950224Y195691D01*
X-950607Y196518D01*
X-951067Y196931D01*
X-951604Y197138D01*
X-952217Y196931D01*
X-952677Y196518D01*
X-952984Y195898D01*
X-953137Y195071D01*
X-952984Y194348D01*
X-952601Y193625D01*
X-952141Y193211D01*
X-951604Y193108D01*
X-950991Y193315D01*
X-950531Y193831D01*
X-950071Y194761D01*
G01X-947091Y192178D02*
X-946631Y191455D01*
X-946017Y191041D01*
X-945327Y190938D01*
X-944714Y191041D01*
X-944101Y191558D01*
X-943717Y192178D01*
X-943641Y192798D01*
X-943794Y193521D01*
X-944331Y194038D01*
X-944867Y194245D01*
X-945557D01*
G01X-944867D02*
X-944407Y194555D01*
X-944024Y195071D01*
X-943871Y195691D01*
X-944024Y196311D01*
X-944407Y196828D01*
X-945097Y197138D01*
X-945787Y197035D01*
X-946477Y196621D01*
G01X-943604Y201205D02*
X-949804D01*
Y203121D01*
X-949494Y203735D01*
X-949081Y204118D01*
X-948254Y204271D01*
X-947427Y204118D01*
X-946911Y203658D01*
X-946601Y203121D01*
Y201205D01*
G01Y203121D02*
X-943604Y204271D01*
G01Y208938D02*
X-949804D01*
X-948564Y208018D01*
G01X-943604D02*
Y209858D01*
G01Y215138D02*
X-943707Y215675D01*
X-944017Y216288D01*
X-944534Y216671D01*
X-945257Y216825D01*
X-945981Y216671D01*
X-946601Y216211D01*
X-946911Y215521D01*
Y214755D01*
X-947117Y214295D01*
X-947634Y213911D01*
X-948357Y213758D01*
X-949081Y213988D01*
X-949597Y214525D01*
X-949804Y215138D01*
X-949597Y215751D01*
X-949081Y216288D01*
X-948357Y216518D01*
X-947634Y216365D01*
X-947117Y215981D01*
X-946911Y215521D01*
Y214755D01*
X-946601Y214065D01*
X-945981Y213605D01*
X-945257Y213451D01*
X-944534Y213605D01*
X-944017Y213988D01*
X-943707Y214601D01*
X-943604Y215138D01*
G01X-948771Y219881D02*
X-949391Y220341D01*
X-949701Y220878D01*
X-949804Y221491D01*
X-949597Y222258D01*
X-949081Y222795D01*
X-948461Y222948D01*
X-947841Y222871D01*
X-947324Y222565D01*
X-946291Y221031D01*
X-945567Y220341D01*
X-944534Y219881D01*
X-943604Y219728D01*
Y222948D01*
G01X-953604Y201205D02*
X-959804D01*
Y203121D01*
X-959494Y203735D01*
X-959081Y204118D01*
X-958254Y204271D01*
X-957427Y204118D01*
X-956911Y203658D01*
X-956601Y203121D01*
Y201205D01*
G01Y203121D02*
X-953604Y204271D01*
G01Y208938D02*
X-959804D01*
X-958564Y208018D01*
G01X-953604D02*
Y209858D01*
G01Y214985D02*
X-954947Y215138D01*
X-956084Y215368D01*
X-957117Y215675D01*
X-958254Y216058D01*
X-959804Y216671D01*
Y213605D01*
G01X-954327Y220035D02*
X-953811Y220571D01*
X-953604Y221185D01*
X-953811Y221798D01*
X-954430Y222335D01*
X-955361Y222718D01*
X-956291Y222871D01*
X-957427D01*
X-958357Y222718D01*
X-959184Y222335D01*
X-959597Y221875D01*
X-959804Y221338D01*
X-959597Y220725D01*
X-959184Y220265D01*
X-958564Y219958D01*
X-957737Y219805D01*
X-957014Y219958D01*
X-956291Y220341D01*
X-955877Y220801D01*
X-955774Y221338D01*
X-955981Y221951D01*
X-956497Y222411D01*
X-957427Y222871D01*
G01X-963621Y306238D02*
X-961704Y312438D01*
X-959787Y306238D01*
G01X-960477Y308408D02*
X-962931D01*
G01X-964551Y385525D02*
X-964861Y385065D01*
X-965068Y384528D01*
Y383915D01*
X-964758Y383225D01*
X-964241Y382688D01*
X-963621Y382305D01*
X-962588Y381998D01*
X-961658Y381921D01*
X-960728Y382075D01*
X-960108Y382305D01*
X-959488Y382765D01*
X-959075Y383301D01*
X-958868Y383838D01*
Y384375D01*
X-959075Y384911D01*
X-959385Y385371D01*
X-959798Y385755D01*
G01X-958868Y390038D02*
X-965068D01*
X-963828Y389118D01*
G01X-958868D02*
Y390958D01*
G01X-965068Y396238D02*
X-964861Y395625D01*
X-964345Y395165D01*
X-963725Y394858D01*
X-962898Y394628D01*
X-961968Y394551D01*
X-961038Y394628D01*
X-960211Y394858D01*
X-959591Y395165D01*
X-959075Y395625D01*
X-958868Y396238D01*
X-959075Y396851D01*
X-959591Y397311D01*
X-960211Y397618D01*
X-961038Y397848D01*
X-961968Y397925D01*
X-962898Y397848D01*
X-963725Y397618D01*
X-964345Y397311D01*
X-964861Y396851D01*
X-965068Y396238D01*
G01X-945917Y417021D02*
X-946377Y417331D01*
X-946914Y417538D01*
X-947527D01*
X-948217Y417228D01*
X-948754Y416711D01*
X-949137Y416091D01*
X-949444Y415058D01*
X-949521Y414128D01*
X-949367Y413198D01*
X-949137Y412578D01*
X-948677Y411958D01*
X-948141Y411545D01*
X-947604Y411338D01*
X-947067D01*
X-946531Y411545D01*
X-946071Y411855D01*
X-945687Y412268D01*
G01X-942861Y413921D02*
X-942324Y414645D01*
X-941864Y415058D01*
X-941251Y415265D01*
X-940714Y415058D01*
X-940331Y414645D01*
X-940024Y414025D01*
X-939947Y413301D01*
X-940024Y412681D01*
X-940331Y412061D01*
X-940791Y411545D01*
X-941327Y411338D01*
X-941941Y411545D01*
X-942477Y412164D01*
X-942784Y413095D01*
X-942861Y414128D01*
X-942707Y415471D01*
X-942477Y416195D01*
X-942094Y416918D01*
X-941557Y417435D01*
X-941021Y417538D01*
X-940484Y417331D01*
X-940101Y416815D01*
G01X-950237Y437338D02*
Y443538D01*
X-948321D01*
X-947707Y443228D01*
X-947324Y442815D01*
X-947171Y441988D01*
X-947324Y441161D01*
X-947784Y440645D01*
X-948321Y440335D01*
X-950237D01*
G01X-948321D02*
X-947171Y437338D01*
G01X-942504D02*
Y443538D01*
X-943424Y442298D01*
G01Y437338D02*
X-941584D01*
G01X-936304D02*
Y443538D01*
X-937224Y442298D01*
G01Y437338D02*
X-935384D01*
G01X-958838Y465220D02*
Y459020D01*
G01X-960601Y465220D02*
X-957075D01*
G01X-954171Y459020D02*
Y465220D01*
X-952331D01*
X-951718Y464910D01*
X-951258Y464187D01*
X-951105Y463360D01*
X-951258Y462533D01*
X-951641Y461913D01*
X-952331Y461603D01*
X-954171D01*
G01X-945518Y459020D02*
Y465220D01*
X-948355Y460777D01*
X-944521D01*
G01X-939318Y459020D02*
Y465220D01*
X-942155Y460777D01*
X-938321D01*
G01X-951004Y477153D02*
X-957204D01*
Y478687D01*
X-956894Y479300D01*
X-956481Y479760D01*
X-955861Y480143D01*
X-955137Y480450D01*
X-954104Y480527D01*
X-953071Y480450D01*
X-952347Y480143D01*
X-951727Y479760D01*
X-951314Y479300D01*
X-951004Y478687D01*
Y477153D01*
G01X-951830Y483430D02*
X-951314Y484043D01*
X-951004Y484733D01*
Y485347D01*
X-951314Y485960D01*
X-951830Y486420D01*
X-952554Y486650D01*
X-953277Y486497D01*
X-953897Y486113D01*
X-954311Y485423D01*
X-954517Y484503D01*
X-954931Y483967D01*
X-955654Y483737D01*
X-956377Y483890D01*
X-956894Y484273D01*
X-957204Y484810D01*
Y485347D01*
X-956997Y485883D01*
X-956481Y486343D01*
G01X-951727Y489937D02*
X-951211Y490473D01*
X-951004Y491087D01*
X-951211Y491700D01*
X-951830Y492237D01*
X-952761Y492620D01*
X-953691Y492773D01*
X-954827D01*
X-955757Y492620D01*
X-956584Y492237D01*
X-956997Y491777D01*
X-957204Y491240D01*
X-956997Y490627D01*
X-956584Y490167D01*
X-955964Y489860D01*
X-955137Y489707D01*
X-954414Y489860D01*
X-953691Y490243D01*
X-953277Y490703D01*
X-953174Y491240D01*
X-953381Y491853D01*
X-953897Y492313D01*
X-954827Y492773D01*
G01X-953017Y474721D02*
X-953477Y475031D01*
X-954014Y475238D01*
X-954627D01*
X-955317Y474928D01*
X-955854Y474411D01*
X-956237Y473791D01*
X-956544Y472758D01*
X-956621Y471828D01*
X-956467Y470898D01*
X-956237Y470278D01*
X-955777Y469658D01*
X-955241Y469245D01*
X-954704Y469038D01*
X-954167D01*
X-953631Y469245D01*
X-953171Y469555D01*
X-952787Y469968D01*
G01X-956621Y494038D02*
X-954704Y500238D01*
X-952787Y494038D01*
G01X-953477Y496208D02*
X-955931D01*
G01X-928317Y-221379D02*
X-928777Y-221069D01*
X-929314Y-220862D01*
X-929927D01*
X-930617Y-221172D01*
X-931154Y-221689D01*
X-931537Y-222309D01*
X-931844Y-223342D01*
X-931921Y-224272D01*
X-931767Y-225202D01*
X-931537Y-225822D01*
X-931077Y-226442D01*
X-930541Y-226855D01*
X-930004Y-227062D01*
X-929467D01*
X-928931Y-226855D01*
X-928471Y-226545D01*
X-928087Y-226132D01*
G01X-925261Y-221895D02*
X-924801Y-221275D01*
X-924264Y-220965D01*
X-923651Y-220862D01*
X-922884Y-221069D01*
X-922347Y-221585D01*
X-922194Y-222205D01*
X-922271Y-222825D01*
X-922577Y-223342D01*
X-924111Y-224375D01*
X-924801Y-225099D01*
X-925261Y-226132D01*
X-925414Y-227062D01*
X-922194D01*
G01X-919291Y-225822D02*
X-918831Y-226545D01*
X-918217Y-226959D01*
X-917527Y-227062D01*
X-916914Y-226959D01*
X-916301Y-226442D01*
X-915917Y-225822D01*
X-915841Y-225202D01*
X-915994Y-224479D01*
X-916531Y-223962D01*
X-917067Y-223755D01*
X-917757D01*
G01X-917067D02*
X-916607Y-223445D01*
X-916224Y-222929D01*
X-916071Y-222309D01*
X-916224Y-221689D01*
X-916607Y-221172D01*
X-917297Y-220862D01*
X-917987Y-220965D01*
X-918677Y-221379D01*
G01X-910484Y-227062D02*
Y-220862D01*
X-913321Y-225305D01*
X-909487D01*
G01X-936537Y-216062D02*
Y-209862D01*
X-934621D01*
X-934007Y-210172D01*
X-933624Y-210585D01*
X-933471Y-211412D01*
X-933624Y-212239D01*
X-934084Y-212755D01*
X-934621Y-213065D01*
X-936537D01*
G01X-934621D02*
X-933471Y-216062D01*
G01X-930261Y-210895D02*
X-929801Y-210275D01*
X-929264Y-209965D01*
X-928651Y-209862D01*
X-927884Y-210069D01*
X-927347Y-210585D01*
X-927194Y-211205D01*
X-927271Y-211825D01*
X-927577Y-212342D01*
X-929111Y-213375D01*
X-929801Y-214099D01*
X-930261Y-215132D01*
X-930414Y-216062D01*
X-927194D01*
G01X-924291Y-214822D02*
X-923831Y-215545D01*
X-923217Y-215959D01*
X-922527Y-216062D01*
X-921914Y-215959D01*
X-921301Y-215442D01*
X-920917Y-214822D01*
X-920841Y-214202D01*
X-920994Y-213479D01*
X-921531Y-212962D01*
X-922067Y-212755D01*
X-922757D01*
G01X-922067D02*
X-921607Y-212445D01*
X-921224Y-211929D01*
X-921071Y-211309D01*
X-921224Y-210689D01*
X-921607Y-210172D01*
X-922297Y-209862D01*
X-922987Y-209965D01*
X-923677Y-210379D01*
G01X-916404Y-216062D02*
Y-209862D01*
X-917324Y-211102D01*
G01Y-216062D02*
X-915484D01*
G01X-939004Y-188762D02*
Y-194962D01*
G01X-940767Y-188762D02*
X-937241D01*
G01X-934337Y-194962D02*
Y-188762D01*
X-932497D01*
X-931884Y-189072D01*
X-931424Y-189795D01*
X-931271Y-190622D01*
X-931424Y-191449D01*
X-931807Y-192069D01*
X-932497Y-192379D01*
X-934337D01*
G01X-928291Y-194032D02*
X-927831Y-194549D01*
X-927294Y-194859D01*
X-926604Y-194962D01*
X-925914Y-194755D01*
X-925377Y-194342D01*
X-924994Y-193619D01*
X-924917Y-192792D01*
X-925071Y-191965D01*
X-925454Y-191449D01*
X-925991Y-191035D01*
X-926527Y-190932D01*
X-927064Y-191035D01*
X-927754Y-191449D01*
X-927524Y-188762D01*
X-925454D01*
G01X-920557Y-194962D02*
X-920404Y-193619D01*
X-920174Y-192482D01*
X-919867Y-191449D01*
X-919484Y-190312D01*
X-918871Y-188762D01*
X-921937D01*
G01X-936838Y-155780D02*
Y-161980D01*
G01X-938601Y-155780D02*
X-935075D01*
G01X-932171Y-161980D02*
Y-155780D01*
X-930331D01*
X-929718Y-156090D01*
X-929258Y-156813D01*
X-929105Y-157640D01*
X-929258Y-158467D01*
X-929641Y-159087D01*
X-930331Y-159397D01*
X-932171D01*
G01X-923518Y-161980D02*
Y-155780D01*
X-926355Y-160223D01*
X-922521D01*
G01X-919695Y-159397D02*
X-919158Y-158673D01*
X-918698Y-158260D01*
X-918085Y-158053D01*
X-917548Y-158260D01*
X-917165Y-158673D01*
X-916858Y-159293D01*
X-916781Y-160017D01*
X-916858Y-160637D01*
X-917165Y-161257D01*
X-917625Y-161773D01*
X-918161Y-161980D01*
X-918775Y-161773D01*
X-919311Y-161154D01*
X-919618Y-160223D01*
X-919695Y-159190D01*
X-919541Y-157847D01*
X-919311Y-157123D01*
X-918928Y-156400D01*
X-918391Y-155883D01*
X-917855Y-155780D01*
X-917318Y-155987D01*
X-916935Y-156503D01*
G01X-935287Y-32575D02*
X-935597Y-33035D01*
X-935804Y-33572D01*
Y-34185D01*
X-935494Y-34875D01*
X-934977Y-35412D01*
X-934357Y-35795D01*
X-933324Y-36102D01*
X-932394Y-36179D01*
X-931464Y-36025D01*
X-930844Y-35795D01*
X-930224Y-35335D01*
X-929811Y-34799D01*
X-929604Y-34262D01*
Y-33725D01*
X-929811Y-33189D01*
X-930121Y-32729D01*
X-930534Y-32345D01*
G01X-934771Y-29519D02*
X-935391Y-29059D01*
X-935701Y-28522D01*
X-935804Y-27909D01*
X-935597Y-27142D01*
X-935081Y-26605D01*
X-934461Y-26452D01*
X-933841Y-26529D01*
X-933324Y-26835D01*
X-932291Y-28369D01*
X-931567Y-29059D01*
X-930534Y-29519D01*
X-929604Y-29672D01*
Y-26452D01*
G01Y-22015D02*
X-930947Y-21862D01*
X-932084Y-21632D01*
X-933117Y-21325D01*
X-934254Y-20942D01*
X-935804Y-20329D01*
Y-23395D01*
G01X-929604Y-15662D02*
X-935804D01*
X-934564Y-16582D01*
G01X-929604D02*
Y-14742D01*
G01X-944387Y6425D02*
X-944697Y5965D01*
X-944904Y5428D01*
Y4815D01*
X-944594Y4125D01*
X-944077Y3588D01*
X-943457Y3205D01*
X-942424Y2898D01*
X-941494Y2821D01*
X-940564Y2975D01*
X-939944Y3205D01*
X-939324Y3665D01*
X-938911Y4201D01*
X-938704Y4738D01*
Y5275D01*
X-938911Y5811D01*
X-939221Y6271D01*
X-939634Y6655D01*
G01X-943871Y9481D02*
X-944491Y9941D01*
X-944801Y10478D01*
X-944904Y11091D01*
X-944697Y11858D01*
X-944181Y12395D01*
X-943561Y12548D01*
X-942941Y12471D01*
X-942424Y12165D01*
X-941391Y10631D01*
X-940667Y9941D01*
X-939634Y9481D01*
X-938704Y9328D01*
Y12548D01*
G01Y16985D02*
X-940047Y17138D01*
X-941184Y17368D01*
X-942217Y17675D01*
X-943354Y18058D01*
X-944904Y18671D01*
Y15605D01*
G01Y23338D02*
X-944697Y22725D01*
X-944181Y22265D01*
X-943561Y21958D01*
X-942734Y21728D01*
X-941804Y21651D01*
X-940874Y21728D01*
X-940047Y21958D01*
X-939427Y22265D01*
X-938911Y22725D01*
X-938704Y23338D01*
X-938911Y23951D01*
X-939427Y24411D01*
X-940047Y24718D01*
X-940874Y24948D01*
X-941804Y25025D01*
X-942734Y24948D01*
X-943561Y24718D01*
X-944181Y24411D01*
X-944697Y23951D01*
X-944904Y23338D01*
G01X-931287Y4425D02*
X-931597Y3965D01*
X-931804Y3428D01*
Y2815D01*
X-931494Y2125D01*
X-930977Y1588D01*
X-930357Y1205D01*
X-929324Y898D01*
X-928394Y821D01*
X-927464Y975D01*
X-926844Y1205D01*
X-926224Y1665D01*
X-925811Y2201D01*
X-925604Y2738D01*
Y3275D01*
X-925811Y3811D01*
X-926121Y4271D01*
X-926534Y4655D01*
G01X-930771Y7481D02*
X-931391Y7941D01*
X-931701Y8478D01*
X-931804Y9091D01*
X-931597Y9858D01*
X-931081Y10395D01*
X-930461Y10548D01*
X-929841Y10471D01*
X-929324Y10165D01*
X-928291Y8631D01*
X-927567Y7941D01*
X-926534Y7481D01*
X-925604Y7328D01*
Y10548D01*
G01X-928187Y13681D02*
X-928911Y14218D01*
X-929324Y14678D01*
X-929531Y15291D01*
X-929324Y15828D01*
X-928911Y16211D01*
X-928291Y16518D01*
X-927567Y16595D01*
X-926947Y16518D01*
X-926327Y16211D01*
X-925811Y15751D01*
X-925604Y15215D01*
X-925811Y14601D01*
X-926430Y14065D01*
X-927361Y13758D01*
X-928394Y13681D01*
X-929737Y13835D01*
X-930461Y14065D01*
X-931184Y14448D01*
X-931701Y14985D01*
X-931804Y15521D01*
X-931597Y16058D01*
X-931081Y16441D01*
G01X-925604Y21338D02*
X-925707Y21875D01*
X-926017Y22488D01*
X-926534Y22871D01*
X-927257Y23025D01*
X-927981Y22871D01*
X-928601Y22411D01*
X-928911Y21721D01*
Y20955D01*
X-929117Y20495D01*
X-929634Y20111D01*
X-930357Y19958D01*
X-931081Y20188D01*
X-931597Y20725D01*
X-931804Y21338D01*
X-931597Y21951D01*
X-931081Y22488D01*
X-930357Y22718D01*
X-929634Y22565D01*
X-929117Y22181D01*
X-928911Y21721D01*
Y20955D01*
X-928601Y20265D01*
X-927981Y19805D01*
X-927257Y19651D01*
X-926534Y19805D01*
X-926017Y20188D01*
X-925707Y20801D01*
X-925604Y21338D01*
G01X-936287Y59425D02*
X-936597Y58965D01*
X-936804Y58428D01*
Y57815D01*
X-936494Y57125D01*
X-935977Y56588D01*
X-935357Y56205D01*
X-934324Y55898D01*
X-933394Y55821D01*
X-932464Y55975D01*
X-931844Y56205D01*
X-931224Y56665D01*
X-930811Y57201D01*
X-930604Y57738D01*
Y58275D01*
X-930811Y58811D01*
X-931121Y59271D01*
X-931534Y59655D01*
G01X-935771Y62481D02*
X-936391Y62941D01*
X-936701Y63478D01*
X-936804Y64091D01*
X-936597Y64858D01*
X-936081Y65395D01*
X-935461Y65548D01*
X-934841Y65471D01*
X-934324Y65165D01*
X-933291Y63631D01*
X-932567Y62941D01*
X-931534Y62481D01*
X-930604Y62328D01*
Y65548D01*
G01X-933187Y68681D02*
X-933911Y69218D01*
X-934324Y69678D01*
X-934531Y70291D01*
X-934324Y70828D01*
X-933911Y71211D01*
X-933291Y71518D01*
X-932567Y71595D01*
X-931947Y71518D01*
X-931327Y71211D01*
X-930811Y70751D01*
X-930604Y70215D01*
X-930811Y69601D01*
X-931430Y69065D01*
X-932361Y68758D01*
X-933394Y68681D01*
X-934737Y68835D01*
X-935461Y69065D01*
X-936184Y69448D01*
X-936701Y69985D01*
X-936804Y70521D01*
X-936597Y71058D01*
X-936081Y71441D01*
G01X-936804Y76338D02*
X-936597Y75725D01*
X-936081Y75265D01*
X-935461Y74958D01*
X-934634Y74728D01*
X-933704Y74651D01*
X-932774Y74728D01*
X-931947Y74958D01*
X-931327Y75265D01*
X-930811Y75725D01*
X-930604Y76338D01*
X-930811Y76951D01*
X-931327Y77411D01*
X-931947Y77718D01*
X-932774Y77948D01*
X-933704Y78025D01*
X-934634Y77948D01*
X-935461Y77718D01*
X-936081Y77411D01*
X-936597Y76951D01*
X-936804Y76338D01*
G01X-947087Y93225D02*
X-947397Y92765D01*
X-947604Y92228D01*
Y91615D01*
X-947294Y90925D01*
X-946777Y90388D01*
X-946157Y90005D01*
X-945124Y89698D01*
X-944194Y89621D01*
X-943264Y89775D01*
X-942644Y90005D01*
X-942024Y90465D01*
X-941611Y91001D01*
X-941404Y91538D01*
Y92075D01*
X-941611Y92611D01*
X-941921Y93071D01*
X-942334Y93455D01*
G01X-946571Y96281D02*
X-947191Y96741D01*
X-947501Y97278D01*
X-947604Y97891D01*
X-947397Y98658D01*
X-946881Y99195D01*
X-946261Y99348D01*
X-945641Y99271D01*
X-945124Y98965D01*
X-944091Y97431D01*
X-943367Y96741D01*
X-942334Y96281D01*
X-941404Y96128D01*
Y99348D01*
G01X-942334Y102251D02*
X-941817Y102711D01*
X-941507Y103248D01*
X-941404Y103938D01*
X-941611Y104628D01*
X-942024Y105165D01*
X-942747Y105548D01*
X-943574Y105625D01*
X-944401Y105471D01*
X-944917Y105088D01*
X-945331Y104551D01*
X-945434Y104015D01*
X-945331Y103478D01*
X-944917Y102788D01*
X-947604Y103018D01*
Y105088D01*
G01X-942334Y108451D02*
X-941817Y108911D01*
X-941507Y109448D01*
X-941404Y110138D01*
X-941611Y110828D01*
X-942024Y111365D01*
X-942747Y111748D01*
X-943574Y111825D01*
X-944401Y111671D01*
X-944917Y111288D01*
X-945331Y110751D01*
X-945434Y110215D01*
X-945331Y109678D01*
X-944917Y108988D01*
X-947604Y109218D01*
Y111288D01*
G01X-934804Y95405D02*
X-928604D01*
Y98471D01*
G01X-929327Y101835D02*
X-928811Y102371D01*
X-928604Y102985D01*
X-928811Y103598D01*
X-929430Y104135D01*
X-930361Y104518D01*
X-931291Y104671D01*
X-932427D01*
X-933357Y104518D01*
X-934184Y104135D01*
X-934597Y103675D01*
X-934804Y103138D01*
X-934597Y102525D01*
X-934184Y102065D01*
X-933564Y101758D01*
X-932737Y101605D01*
X-932014Y101758D01*
X-931291Y102141D01*
X-930877Y102601D01*
X-930774Y103138D01*
X-930981Y103751D01*
X-931497Y104211D01*
X-932427Y104671D01*
G01X-933804Y112738D02*
X-927604D01*
G01X-933804Y110975D02*
Y114501D01*
G01X-927604Y117405D02*
X-933804D01*
Y119245D01*
X-933494Y119858D01*
X-932771Y120318D01*
X-931944Y120471D01*
X-931117Y120318D01*
X-930497Y119935D01*
X-930187Y119245D01*
Y117405D01*
G01X-928534Y123451D02*
X-928017Y123911D01*
X-927707Y124448D01*
X-927604Y125138D01*
X-927811Y125828D01*
X-928224Y126365D01*
X-928947Y126748D01*
X-929774Y126825D01*
X-930601Y126671D01*
X-931117Y126288D01*
X-931531Y125751D01*
X-931634Y125215D01*
X-931531Y124678D01*
X-931117Y123988D01*
X-933804Y124218D01*
Y126288D01*
G01X-932771Y129881D02*
X-933391Y130341D01*
X-933701Y130878D01*
X-933804Y131491D01*
X-933597Y132258D01*
X-933081Y132795D01*
X-932461Y132948D01*
X-931841Y132871D01*
X-931324Y132565D01*
X-930291Y131031D01*
X-929567Y130341D01*
X-928534Y129881D01*
X-927604Y129728D01*
Y132948D01*
G01X-942004Y164605D02*
X-948204D01*
Y166521D01*
X-947894Y167135D01*
X-947481Y167518D01*
X-946654Y167671D01*
X-945827Y167518D01*
X-945311Y167058D01*
X-945001Y166521D01*
Y164605D01*
G01Y166521D02*
X-942004Y167671D01*
G01Y172338D02*
X-948204D01*
X-946964Y171418D01*
G01X-942004D02*
Y173258D01*
G01X-942727Y177235D02*
X-942211Y177771D01*
X-942004Y178385D01*
X-942211Y178998D01*
X-942830Y179535D01*
X-943761Y179918D01*
X-944691Y180071D01*
X-945827D01*
X-946757Y179918D01*
X-947584Y179535D01*
X-947997Y179075D01*
X-948204Y178538D01*
X-947997Y177925D01*
X-947584Y177465D01*
X-946964Y177158D01*
X-946137Y177005D01*
X-945414Y177158D01*
X-944691Y177541D01*
X-944277Y178001D01*
X-944174Y178538D01*
X-944381Y179151D01*
X-944897Y179611D01*
X-945827Y180071D01*
G01X-948204Y184738D02*
X-947997Y184125D01*
X-947481Y183665D01*
X-946861Y183358D01*
X-946034Y183128D01*
X-945104Y183051D01*
X-944174Y183128D01*
X-943347Y183358D01*
X-942727Y183665D01*
X-942211Y184125D01*
X-942004Y184738D01*
X-942211Y185351D01*
X-942727Y185811D01*
X-943347Y186118D01*
X-944174Y186348D01*
X-945104Y186425D01*
X-946034Y186348D01*
X-946861Y186118D01*
X-947481Y185811D01*
X-947997Y185351D01*
X-948204Y184738D01*
G01X-930804Y251038D02*
Y257238D01*
X-931724Y255998D01*
G01Y251038D02*
X-929884D01*
G01X-924604Y257238D02*
X-925217Y257031D01*
X-925677Y256515D01*
X-925984Y255895D01*
X-926214Y255068D01*
X-926291Y254138D01*
X-926214Y253208D01*
X-925984Y252381D01*
X-925677Y251761D01*
X-925217Y251245D01*
X-924604Y251038D01*
X-923991Y251245D01*
X-923531Y251761D01*
X-923224Y252381D01*
X-922994Y253208D01*
X-922917Y254138D01*
X-922994Y255068D01*
X-923224Y255895D01*
X-923531Y256515D01*
X-923991Y257031D01*
X-924604Y257238D01*
G01X-934117Y312821D02*
X-934577Y313131D01*
X-935114Y313338D01*
X-935727D01*
X-936417Y313028D01*
X-936954Y312511D01*
X-937337Y311891D01*
X-937644Y310858D01*
X-937721Y309928D01*
X-937567Y308998D01*
X-937337Y308378D01*
X-936877Y307758D01*
X-936341Y307345D01*
X-935804Y307138D01*
X-935267D01*
X-934731Y307345D01*
X-934271Y307655D01*
X-933887Y308068D01*
G01X-931137Y307138D02*
Y313338D01*
X-929221D01*
X-928607Y313028D01*
X-928224Y312615D01*
X-928071Y311788D01*
X-928224Y310961D01*
X-928684Y310445D01*
X-929221Y310135D01*
X-931137D01*
G01X-929221D02*
X-928071Y307138D01*
G01X-923404D02*
Y313338D01*
X-924324Y312098D01*
G01Y307138D02*
X-922484D01*
G01X-917204Y313338D02*
X-917817Y313131D01*
X-918277Y312615D01*
X-918584Y311995D01*
X-918814Y311168D01*
X-918891Y310238D01*
X-918814Y309308D01*
X-918584Y308481D01*
X-918277Y307861D01*
X-917817Y307345D01*
X-917204Y307138D01*
X-916591Y307345D01*
X-916131Y307861D01*
X-915824Y308481D01*
X-915594Y309308D01*
X-915517Y310238D01*
X-915594Y311168D01*
X-915824Y311995D01*
X-916131Y312615D01*
X-916591Y313131D01*
X-917204Y313338D01*
G01X-948151Y388625D02*
X-948461Y388165D01*
X-948668Y387628D01*
Y387015D01*
X-948358Y386325D01*
X-947841Y385788D01*
X-947221Y385405D01*
X-946188Y385098D01*
X-945258Y385021D01*
X-944328Y385175D01*
X-943708Y385405D01*
X-943088Y385865D01*
X-942675Y386401D01*
X-942468Y386938D01*
Y387475D01*
X-942675Y388011D01*
X-942985Y388471D01*
X-943398Y388855D01*
G01X-943191Y391835D02*
X-942675Y392371D01*
X-942468Y392985D01*
X-942675Y393598D01*
X-943294Y394135D01*
X-944225Y394518D01*
X-945155Y394671D01*
X-946291D01*
X-947221Y394518D01*
X-948048Y394135D01*
X-948461Y393675D01*
X-948668Y393138D01*
X-948461Y392525D01*
X-948048Y392065D01*
X-947428Y391758D01*
X-946601Y391605D01*
X-945878Y391758D01*
X-945155Y392141D01*
X-944741Y392601D01*
X-944638Y393138D01*
X-944845Y393751D01*
X-945361Y394211D01*
X-946291Y394671D01*
G01X-933203Y384721D02*
X-932743Y385341D01*
X-932206Y385651D01*
X-931593Y385754D01*
X-930826Y385547D01*
X-930289Y385031D01*
X-930136Y384411D01*
X-930213Y383791D01*
X-930519Y383274D01*
X-932053Y382241D01*
X-932743Y381517D01*
X-933203Y380484D01*
X-933356Y379554D01*
X-930136D01*
G01X-925546Y385754D02*
X-926159Y385547D01*
X-926619Y385031D01*
X-926926Y384411D01*
X-927156Y383584D01*
X-927233Y382654D01*
X-927156Y381724D01*
X-926926Y380897D01*
X-926619Y380277D01*
X-926159Y379761D01*
X-925546Y379554D01*
X-924933Y379761D01*
X-924473Y380277D01*
X-924166Y380897D01*
X-923936Y381724D01*
X-923859Y382654D01*
X-923936Y383584D01*
X-924166Y384411D01*
X-924473Y385031D01*
X-924933Y385547D01*
X-925546Y385754D01*
G01X-947137Y426338D02*
Y432538D01*
X-945221D01*
X-944607Y432228D01*
X-944224Y431815D01*
X-944071Y430988D01*
X-944224Y430161D01*
X-944684Y429645D01*
X-945221Y429335D01*
X-947137D01*
G01X-945221D02*
X-944071Y426338D01*
G01X-940707Y427061D02*
X-940171Y426545D01*
X-939557Y426338D01*
X-938944Y426545D01*
X-938407Y427164D01*
X-938024Y428095D01*
X-937871Y429025D01*
Y430161D01*
X-938024Y431091D01*
X-938407Y431918D01*
X-938867Y432331D01*
X-939404Y432538D01*
X-940017Y432331D01*
X-940477Y431918D01*
X-940784Y431298D01*
X-940937Y430471D01*
X-940784Y429748D01*
X-940401Y429025D01*
X-939941Y428611D01*
X-939404Y428508D01*
X-938791Y428715D01*
X-938331Y429231D01*
X-937871Y430161D01*
G01X-931746Y411050D02*
Y417250D01*
X-932666Y416010D01*
G01Y411050D02*
X-930826D01*
G01X-927003Y416217D02*
X-926543Y416837D01*
X-926006Y417147D01*
X-925393Y417250D01*
X-924626Y417043D01*
X-924089Y416527D01*
X-923936Y415907D01*
X-924013Y415287D01*
X-924319Y414770D01*
X-925853Y413737D01*
X-926543Y413013D01*
X-927003Y411980D01*
X-927156Y411050D01*
X-923936D01*
G01X-932621Y475938D02*
X-930704Y482138D01*
X-928787Y475938D01*
G01X-929477Y478108D02*
X-931931D01*
G01X-914917Y-175779D02*
X-915377Y-175469D01*
X-915914Y-175262D01*
X-916527D01*
X-917217Y-175572D01*
X-917754Y-176089D01*
X-918137Y-176709D01*
X-918444Y-177742D01*
X-918521Y-178672D01*
X-918367Y-179602D01*
X-918137Y-180222D01*
X-917677Y-180842D01*
X-917141Y-181255D01*
X-916604Y-181462D01*
X-916067D01*
X-915531Y-181255D01*
X-915071Y-180945D01*
X-914687Y-180532D01*
G01X-911861Y-176295D02*
X-911401Y-175675D01*
X-910864Y-175365D01*
X-910251Y-175262D01*
X-909484Y-175469D01*
X-908947Y-175985D01*
X-908794Y-176605D01*
X-908871Y-177225D01*
X-909177Y-177742D01*
X-910711Y-178775D01*
X-911401Y-179499D01*
X-911861Y-180532D01*
X-912014Y-181462D01*
X-908794D01*
G01X-905891Y-180222D02*
X-905431Y-180945D01*
X-904817Y-181359D01*
X-904127Y-181462D01*
X-903514Y-181359D01*
X-902901Y-180842D01*
X-902517Y-180222D01*
X-902441Y-179602D01*
X-902594Y-178879D01*
X-903131Y-178362D01*
X-903667Y-178155D01*
X-904357D01*
G01X-903667D02*
X-903207Y-177845D01*
X-902824Y-177329D01*
X-902671Y-176709D01*
X-902824Y-176089D01*
X-903207Y-175572D01*
X-903897Y-175262D01*
X-904587Y-175365D01*
X-905277Y-175779D01*
G01X-899307Y-180739D02*
X-898771Y-181255D01*
X-898157Y-181462D01*
X-897544Y-181255D01*
X-897007Y-180636D01*
X-896624Y-179705D01*
X-896471Y-178775D01*
Y-177639D01*
X-896624Y-176709D01*
X-897007Y-175882D01*
X-897467Y-175469D01*
X-898004Y-175262D01*
X-898617Y-175469D01*
X-899077Y-175882D01*
X-899384Y-176502D01*
X-899537Y-177329D01*
X-899384Y-178052D01*
X-899001Y-178775D01*
X-898541Y-179189D01*
X-898004Y-179292D01*
X-897391Y-179085D01*
X-896931Y-178569D01*
X-896471Y-177639D01*
G01X-915391Y67968D02*
X-914931Y67451D01*
X-914394Y67141D01*
X-913704Y67038D01*
X-913014Y67245D01*
X-912477Y67658D01*
X-912094Y68381D01*
X-912017Y69208D01*
X-912171Y70035D01*
X-912554Y70551D01*
X-913091Y70965D01*
X-913627Y71068D01*
X-914164Y70965D01*
X-914854Y70551D01*
X-914624Y73238D01*
X-912554D01*
G01X-923287Y63425D02*
X-923597Y62965D01*
X-923804Y62428D01*
Y61815D01*
X-923494Y61125D01*
X-922977Y60588D01*
X-922357Y60205D01*
X-921324Y59898D01*
X-920394Y59821D01*
X-919464Y59975D01*
X-918844Y60205D01*
X-918224Y60665D01*
X-917811Y61201D01*
X-917604Y61738D01*
Y62275D01*
X-917811Y62811D01*
X-918121Y63271D01*
X-918534Y63655D01*
G01X-922771Y66481D02*
X-923391Y66941D01*
X-923701Y67478D01*
X-923804Y68091D01*
X-923597Y68858D01*
X-923081Y69395D01*
X-922461Y69548D01*
X-921841Y69471D01*
X-921324Y69165D01*
X-920291Y67631D01*
X-919567Y66941D01*
X-918534Y66481D01*
X-917604Y66328D01*
Y69548D01*
G01X-920187Y72681D02*
X-920911Y73218D01*
X-921324Y73678D01*
X-921531Y74291D01*
X-921324Y74828D01*
X-920911Y75211D01*
X-920291Y75518D01*
X-919567Y75595D01*
X-918947Y75518D01*
X-918327Y75211D01*
X-917811Y74751D01*
X-917604Y74215D01*
X-917811Y73601D01*
X-918430Y73065D01*
X-919361Y72758D01*
X-920394Y72681D01*
X-921737Y72835D01*
X-922461Y73065D01*
X-923184Y73448D01*
X-923701Y73985D01*
X-923804Y74521D01*
X-923597Y75058D01*
X-923081Y75441D01*
G01X-917604Y80338D02*
X-923804D01*
X-922564Y79418D01*
G01X-917604D02*
Y81258D01*
G01X-913646Y96648D02*
Y102848D01*
X-914566Y101608D01*
G01Y96648D02*
X-912726D01*
G01X-907446D02*
X-906909Y96751D01*
X-906296Y97061D01*
X-905913Y97578D01*
X-905759Y98301D01*
X-905913Y99025D01*
X-906373Y99645D01*
X-907063Y99955D01*
X-907829D01*
X-908289Y100161D01*
X-908673Y100678D01*
X-908826Y101401D01*
X-908596Y102125D01*
X-908059Y102641D01*
X-907446Y102848D01*
X-906833Y102641D01*
X-906296Y102125D01*
X-906066Y101401D01*
X-906219Y100678D01*
X-906603Y100161D01*
X-907063Y99955D01*
X-907829D01*
X-908519Y99645D01*
X-908979Y99025D01*
X-909133Y98301D01*
X-908979Y97578D01*
X-908596Y97061D01*
X-907983Y96751D01*
X-907446Y96648D01*
G01X-914604Y107205D02*
X-920804D01*
Y109121D01*
X-920494Y109735D01*
X-920081Y110118D01*
X-919254Y110271D01*
X-918427Y110118D01*
X-917911Y109658D01*
X-917601Y109121D01*
Y107205D01*
G01Y109121D02*
X-914604Y110271D01*
G01X-919771Y113481D02*
X-920391Y113941D01*
X-920701Y114478D01*
X-920804Y115091D01*
X-920597Y115858D01*
X-920081Y116395D01*
X-919461Y116548D01*
X-918841Y116471D01*
X-918324Y116165D01*
X-917291Y114631D01*
X-916567Y113941D01*
X-915534Y113481D01*
X-914604Y113328D01*
Y116548D01*
G01Y122058D02*
X-920804D01*
X-916361Y119221D01*
Y123055D01*
G01X-915534Y125651D02*
X-915017Y126111D01*
X-914707Y126648D01*
X-914604Y127338D01*
X-914811Y128028D01*
X-915224Y128565D01*
X-915947Y128948D01*
X-916774Y129025D01*
X-917601Y128871D01*
X-918117Y128488D01*
X-918531Y127951D01*
X-918634Y127415D01*
X-918531Y126878D01*
X-918117Y126188D01*
X-920804Y126418D01*
Y128488D01*
G01X-929161Y171105D02*
X-928701Y171725D01*
X-928164Y172035D01*
X-927551Y172138D01*
X-926784Y171931D01*
X-926247Y171415D01*
X-926094Y170795D01*
X-926171Y170175D01*
X-926477Y169658D01*
X-928011Y168625D01*
X-928701Y167901D01*
X-929161Y166868D01*
X-929314Y165938D01*
X-926094D01*
G01X-917161Y359738D02*
Y365938D01*
X-914247D01*
G01X-915321Y362941D02*
X-917161D01*
G01X-911191Y365938D02*
Y361495D01*
X-910884Y360564D01*
X-910271Y359945D01*
X-909504Y359738D01*
X-908737Y359945D01*
X-908124Y360564D01*
X-907817Y361495D01*
Y365938D01*
G01X-903304Y359738D02*
Y365938D01*
X-904224Y364698D01*
G01Y359738D02*
X-902384D01*
G01X-912917Y434021D02*
X-913377Y434331D01*
X-913914Y434538D01*
X-914527D01*
X-915217Y434228D01*
X-915754Y433711D01*
X-916137Y433091D01*
X-916444Y432058D01*
X-916521Y431128D01*
X-916367Y430198D01*
X-916137Y429578D01*
X-915677Y428958D01*
X-915141Y428545D01*
X-914604Y428338D01*
X-914067D01*
X-913531Y428545D01*
X-913071Y428855D01*
X-912687Y429268D01*
G01X-908404Y428338D02*
X-907867Y428441D01*
X-907254Y428751D01*
X-906871Y429268D01*
X-906717Y429991D01*
X-906871Y430715D01*
X-907331Y431335D01*
X-908021Y431645D01*
X-908787D01*
X-909247Y431851D01*
X-909631Y432368D01*
X-909784Y433091D01*
X-909554Y433815D01*
X-909017Y434331D01*
X-908404Y434538D01*
X-907791Y434331D01*
X-907254Y433815D01*
X-907024Y433091D01*
X-907177Y432368D01*
X-907561Y431851D01*
X-908021Y431645D01*
X-908787D01*
X-909477Y431335D01*
X-909937Y430715D01*
X-910091Y429991D01*
X-909937Y429268D01*
X-909554Y428751D01*
X-908941Y428441D01*
X-908404Y428338D01*
G01X-921351Y439338D02*
Y445538D01*
X-919435D01*
X-918821Y445228D01*
X-918438Y444815D01*
X-918285Y443988D01*
X-918438Y443161D01*
X-918898Y442645D01*
X-919435Y442335D01*
X-921351D01*
G01X-919435D02*
X-918285Y439338D01*
G01X-913618D02*
Y445538D01*
X-914538Y444298D01*
G01Y439338D02*
X-912698D01*
G01X-908875Y444505D02*
X-908415Y445125D01*
X-907878Y445435D01*
X-907265Y445538D01*
X-906498Y445331D01*
X-905961Y444815D01*
X-905808Y444195D01*
X-905885Y443575D01*
X-906191Y443058D01*
X-907725Y442025D01*
X-908415Y441301D01*
X-908875Y440268D01*
X-909028Y439338D01*
X-905808D01*
G01X-923017Y459621D02*
X-923477Y459931D01*
X-924014Y460138D01*
X-924627D01*
X-925317Y459828D01*
X-925854Y459311D01*
X-926237Y458691D01*
X-926544Y457658D01*
X-926621Y456728D01*
X-926467Y455798D01*
X-926237Y455178D01*
X-925777Y454558D01*
X-925241Y454145D01*
X-924704Y453938D01*
X-924167D01*
X-923631Y454145D01*
X-923171Y454455D01*
X-922787Y454868D01*
G01X-920596Y462805D02*
X-926796D01*
Y464339D01*
X-926486Y464952D01*
X-926073Y465412D01*
X-925453Y465795D01*
X-924729Y466102D01*
X-923696Y466179D01*
X-922663Y466102D01*
X-921939Y465795D01*
X-921319Y465412D01*
X-920906Y464952D01*
X-920596Y464339D01*
Y462805D01*
G01X-921422Y469082D02*
X-920906Y469695D01*
X-920596Y470385D01*
Y470999D01*
X-920906Y471612D01*
X-921422Y472072D01*
X-922146Y472302D01*
X-922869Y472149D01*
X-923489Y471765D01*
X-923903Y471075D01*
X-924109Y470155D01*
X-924523Y469619D01*
X-925246Y469389D01*
X-925969Y469542D01*
X-926486Y469925D01*
X-926796Y470462D01*
Y470999D01*
X-926589Y471535D01*
X-926073Y471995D01*
G01X-923179Y475435D02*
X-923903Y475972D01*
X-924316Y476432D01*
X-924523Y477045D01*
X-924316Y477582D01*
X-923903Y477965D01*
X-923283Y478272D01*
X-922559Y478349D01*
X-921939Y478272D01*
X-921319Y477965D01*
X-920803Y477505D01*
X-920596Y476969D01*
X-920803Y476355D01*
X-921422Y475819D01*
X-922353Y475512D01*
X-923386Y475435D01*
X-924729Y475589D01*
X-925453Y475819D01*
X-926176Y476202D01*
X-926693Y476739D01*
X-926796Y477275D01*
X-926589Y477812D01*
X-926073Y478195D01*
G01X-915017Y492621D02*
X-915477Y492931D01*
X-916014Y493138D01*
X-916627D01*
X-917317Y492828D01*
X-917854Y492311D01*
X-918237Y491691D01*
X-918544Y490658D01*
X-918621Y489728D01*
X-918467Y488798D01*
X-918237Y488178D01*
X-917777Y487558D01*
X-917241Y487145D01*
X-916704Y486938D01*
X-916167D01*
X-915631Y487145D01*
X-915171Y487455D01*
X-914787Y487868D01*
G01X-920604Y490151D02*
X-926804D01*
Y491685D01*
X-926494Y492298D01*
X-926081Y492758D01*
X-925461Y493141D01*
X-924737Y493448D01*
X-923704Y493525D01*
X-922671Y493448D01*
X-921947Y493141D01*
X-921327Y492758D01*
X-920914Y492298D01*
X-920604Y491685D01*
Y490151D01*
G01X-921430Y496428D02*
X-920914Y497041D01*
X-920604Y497731D01*
Y498345D01*
X-920914Y498958D01*
X-921430Y499418D01*
X-922154Y499648D01*
X-922877Y499495D01*
X-923497Y499111D01*
X-923911Y498421D01*
X-924117Y497501D01*
X-924531Y496965D01*
X-925254Y496735D01*
X-925977Y496888D01*
X-926494Y497271D01*
X-926804Y497808D01*
Y498345D01*
X-926597Y498881D01*
X-926081Y499341D01*
G01X-920604Y504238D02*
X-926804D01*
X-925564Y503318D01*
G01X-920604D02*
Y505158D01*
G01X-927621Y508848D02*
X-925704Y515048D01*
X-923787Y508848D01*
G01X-924477Y511018D02*
X-926931D01*
G01X-903391Y-226032D02*
X-902931Y-226549D01*
X-902394Y-226859D01*
X-901704Y-226962D01*
X-901014Y-226755D01*
X-900477Y-226342D01*
X-900094Y-225619D01*
X-900017Y-224792D01*
X-900171Y-223965D01*
X-900554Y-223449D01*
X-901091Y-223035D01*
X-901627Y-222932D01*
X-902164Y-223035D01*
X-902854Y-223449D01*
X-902624Y-220762D01*
X-900554D01*
G01X-908717Y-189979D02*
X-909177Y-189669D01*
X-909714Y-189462D01*
X-910327D01*
X-911017Y-189772D01*
X-911554Y-190289D01*
X-911937Y-190909D01*
X-912244Y-191942D01*
X-912321Y-192872D01*
X-912167Y-193802D01*
X-911937Y-194422D01*
X-911477Y-195042D01*
X-910941Y-195455D01*
X-910404Y-195662D01*
X-909867D01*
X-909331Y-195455D01*
X-908871Y-195145D01*
X-908487Y-194732D01*
G01X-905661Y-190495D02*
X-905201Y-189875D01*
X-904664Y-189565D01*
X-904051Y-189462D01*
X-903284Y-189669D01*
X-902747Y-190185D01*
X-902594Y-190805D01*
X-902671Y-191425D01*
X-902977Y-191942D01*
X-904511Y-192975D01*
X-905201Y-193699D01*
X-905661Y-194732D01*
X-905814Y-195662D01*
X-902594D01*
G01X-897084D02*
Y-189462D01*
X-899921Y-193905D01*
X-896087D01*
G01X-893261Y-190495D02*
X-892801Y-189875D01*
X-892264Y-189565D01*
X-891651Y-189462D01*
X-890884Y-189669D01*
X-890347Y-190185D01*
X-890194Y-190805D01*
X-890271Y-191425D01*
X-890577Y-191942D01*
X-892111Y-192975D01*
X-892801Y-193699D01*
X-893261Y-194732D01*
X-893414Y-195662D01*
X-890194D01*
G01X-898287Y-165575D02*
X-898597Y-166035D01*
X-898804Y-166572D01*
Y-167185D01*
X-898494Y-167875D01*
X-897977Y-168412D01*
X-897357Y-168795D01*
X-896324Y-169102D01*
X-895394Y-169179D01*
X-894464Y-169025D01*
X-893844Y-168795D01*
X-893224Y-168335D01*
X-892811Y-167799D01*
X-892604Y-167262D01*
Y-166725D01*
X-892811Y-166189D01*
X-893121Y-165729D01*
X-893534Y-165345D01*
G01X-897771Y-162519D02*
X-898391Y-162059D01*
X-898701Y-161522D01*
X-898804Y-160909D01*
X-898597Y-160142D01*
X-898081Y-159605D01*
X-897461Y-159452D01*
X-896841Y-159529D01*
X-896324Y-159835D01*
X-895291Y-161369D01*
X-894567Y-162059D01*
X-893534Y-162519D01*
X-892604Y-162672D01*
Y-159452D01*
G01X-897771Y-156319D02*
X-898391Y-155859D01*
X-898701Y-155322D01*
X-898804Y-154709D01*
X-898597Y-153942D01*
X-898081Y-153405D01*
X-897461Y-153252D01*
X-896841Y-153329D01*
X-896324Y-153635D01*
X-895291Y-155169D01*
X-894567Y-155859D01*
X-893534Y-156319D01*
X-892604Y-156472D01*
Y-153252D01*
G01Y-147742D02*
X-898804D01*
X-894361Y-150579D01*
Y-146745D01*
G01X-896804Y10405D02*
X-890604D01*
Y13471D01*
G01X-891534Y16451D02*
X-891017Y16911D01*
X-890707Y17448D01*
X-890604Y18138D01*
X-890811Y18828D01*
X-891224Y19365D01*
X-891947Y19748D01*
X-892774Y19825D01*
X-893601Y19671D01*
X-894117Y19288D01*
X-894531Y18751D01*
X-894634Y18215D01*
X-894531Y17678D01*
X-894117Y16988D01*
X-896804Y17218D01*
Y19288D01*
G01X-908161Y59621D02*
X-907624Y60345D01*
X-907164Y60758D01*
X-906551Y60965D01*
X-906014Y60758D01*
X-905631Y60345D01*
X-905324Y59725D01*
X-905247Y59001D01*
X-905324Y58381D01*
X-905631Y57761D01*
X-906091Y57245D01*
X-906627Y57038D01*
X-907241Y57245D01*
X-907777Y57864D01*
X-908084Y58795D01*
X-908161Y59828D01*
X-908007Y61171D01*
X-907777Y61895D01*
X-907394Y62618D01*
X-906857Y63135D01*
X-906321Y63238D01*
X-905784Y63031D01*
X-905401Y62515D01*
G01X-903591Y84122D02*
Y79679D01*
X-903284Y78748D01*
X-902671Y78129D01*
X-901904Y77922D01*
X-901137Y78129D01*
X-900524Y78748D01*
X-900217Y79679D01*
Y84122D01*
G01X-897161Y83089D02*
X-896701Y83709D01*
X-896164Y84019D01*
X-895551Y84122D01*
X-894784Y83915D01*
X-894247Y83399D01*
X-894094Y82779D01*
X-894171Y82159D01*
X-894477Y81642D01*
X-896011Y80609D01*
X-896701Y79885D01*
X-897161Y78852D01*
X-897314Y77922D01*
X-894094D01*
G01X-890961Y80505D02*
X-890424Y81229D01*
X-889964Y81642D01*
X-889351Y81849D01*
X-888814Y81642D01*
X-888431Y81229D01*
X-888124Y80609D01*
X-888047Y79885D01*
X-888124Y79265D01*
X-888431Y78645D01*
X-888891Y78129D01*
X-889427Y77922D01*
X-890041Y78129D01*
X-890577Y78748D01*
X-890884Y79679D01*
X-890961Y80712D01*
X-890807Y82055D01*
X-890577Y82779D01*
X-890194Y83502D01*
X-889657Y84019D01*
X-889121Y84122D01*
X-888584Y83915D01*
X-888201Y83399D01*
G01X-911287Y109425D02*
X-911597Y108965D01*
X-911804Y108428D01*
Y107815D01*
X-911494Y107125D01*
X-910977Y106588D01*
X-910357Y106205D01*
X-909324Y105898D01*
X-908394Y105821D01*
X-907464Y105975D01*
X-906844Y106205D01*
X-906224Y106665D01*
X-905811Y107201D01*
X-905604Y107738D01*
Y108275D01*
X-905811Y108811D01*
X-906121Y109271D01*
X-906534Y109655D01*
G01X-910771Y112481D02*
X-911391Y112941D01*
X-911701Y113478D01*
X-911804Y114091D01*
X-911597Y114858D01*
X-911081Y115395D01*
X-910461Y115548D01*
X-909841Y115471D01*
X-909324Y115165D01*
X-908291Y113631D01*
X-907567Y112941D01*
X-906534Y112481D01*
X-905604Y112328D01*
Y115548D01*
G01X-906534Y118451D02*
X-906017Y118911D01*
X-905707Y119448D01*
X-905604Y120138D01*
X-905811Y120828D01*
X-906224Y121365D01*
X-906947Y121748D01*
X-907774Y121825D01*
X-908601Y121671D01*
X-909117Y121288D01*
X-909531Y120751D01*
X-909634Y120215D01*
X-909531Y119678D01*
X-909117Y118988D01*
X-911804Y119218D01*
Y121288D01*
G01X-905604Y126338D02*
X-905707Y126875D01*
X-906017Y127488D01*
X-906534Y127871D01*
X-907257Y128025D01*
X-907981Y127871D01*
X-908601Y127411D01*
X-908911Y126721D01*
Y125955D01*
X-909117Y125495D01*
X-909634Y125111D01*
X-910357Y124958D01*
X-911081Y125188D01*
X-911597Y125725D01*
X-911804Y126338D01*
X-911597Y126951D01*
X-911081Y127488D01*
X-910357Y127718D01*
X-909634Y127565D01*
X-909117Y127181D01*
X-908911Y126721D01*
Y125955D01*
X-908601Y125265D01*
X-907981Y124805D01*
X-907257Y124651D01*
X-906534Y124805D01*
X-906017Y125188D01*
X-905707Y125801D01*
X-905604Y126338D01*
G01X-902287Y110425D02*
X-902597Y109965D01*
X-902804Y109428D01*
Y108815D01*
X-902494Y108125D01*
X-901977Y107588D01*
X-901357Y107205D01*
X-900324Y106898D01*
X-899394Y106821D01*
X-898464Y106975D01*
X-897844Y107205D01*
X-897224Y107665D01*
X-896811Y108201D01*
X-896604Y108738D01*
Y109275D01*
X-896811Y109811D01*
X-897121Y110271D01*
X-897534Y110655D01*
G01X-901771Y113481D02*
X-902391Y113941D01*
X-902701Y114478D01*
X-902804Y115091D01*
X-902597Y115858D01*
X-902081Y116395D01*
X-901461Y116548D01*
X-900841Y116471D01*
X-900324Y116165D01*
X-899291Y114631D01*
X-898567Y113941D01*
X-897534Y113481D01*
X-896604Y113328D01*
Y116548D01*
G01X-897534Y119451D02*
X-897017Y119911D01*
X-896707Y120448D01*
X-896604Y121138D01*
X-896811Y121828D01*
X-897224Y122365D01*
X-897947Y122748D01*
X-898774Y122825D01*
X-899601Y122671D01*
X-900117Y122288D01*
X-900531Y121751D01*
X-900634Y121215D01*
X-900531Y120678D01*
X-900117Y119988D01*
X-902804Y120218D01*
Y122288D01*
G01X-899187Y125881D02*
X-899911Y126418D01*
X-900324Y126878D01*
X-900531Y127491D01*
X-900324Y128028D01*
X-899911Y128411D01*
X-899291Y128718D01*
X-898567Y128795D01*
X-897947Y128718D01*
X-897327Y128411D01*
X-896811Y127951D01*
X-896604Y127415D01*
X-896811Y126801D01*
X-897430Y126265D01*
X-898361Y125958D01*
X-899394Y125881D01*
X-900737Y126035D01*
X-901461Y126265D01*
X-902184Y126648D01*
X-902701Y127185D01*
X-902804Y127721D01*
X-902597Y128258D01*
X-902081Y128641D01*
G01X-911191Y401602D02*
Y397159D01*
X-910884Y396228D01*
X-910271Y395609D01*
X-909504Y395402D01*
X-908737Y395609D01*
X-908124Y396228D01*
X-907817Y397159D01*
Y401602D01*
G01X-903304Y395402D02*
Y401602D01*
X-904224Y400362D01*
G01Y395402D02*
X-902384D01*
G01X-902437Y428938D02*
Y435138D01*
X-900521D01*
X-899907Y434828D01*
X-899524Y434415D01*
X-899371Y433588D01*
X-899524Y432761D01*
X-899984Y432245D01*
X-900521Y431935D01*
X-902437D01*
G01X-900521D02*
X-899371Y428938D01*
G01X-894704D02*
Y435138D01*
X-895624Y433898D01*
G01Y428938D02*
X-893784D01*
G01X-887584D02*
Y435138D01*
X-890421Y430695D01*
X-886587D01*
G01X-902437Y437938D02*
Y444138D01*
X-900521D01*
X-899907Y443828D01*
X-899524Y443415D01*
X-899371Y442588D01*
X-899524Y441761D01*
X-899984Y441245D01*
X-900521Y440935D01*
X-902437D01*
G01X-900521D02*
X-899371Y437938D01*
G01X-894704D02*
Y444138D01*
X-895624Y442898D01*
G01Y437938D02*
X-893784D01*
G01X-890191Y439178D02*
X-889731Y438455D01*
X-889117Y438041D01*
X-888427Y437938D01*
X-887814Y438041D01*
X-887201Y438558D01*
X-886817Y439178D01*
X-886741Y439798D01*
X-886894Y440521D01*
X-887431Y441038D01*
X-887967Y441245D01*
X-888657D01*
G01X-887967D02*
X-887507Y441555D01*
X-887124Y442071D01*
X-886971Y442691D01*
X-887124Y443311D01*
X-887507Y443828D01*
X-888197Y444138D01*
X-888887Y444035D01*
X-889577Y443621D01*
G01X-906017Y460621D02*
X-906477Y460931D01*
X-907014Y461138D01*
X-907627D01*
X-908317Y460828D01*
X-908854Y460311D01*
X-909237Y459691D01*
X-909544Y458658D01*
X-909621Y457728D01*
X-909467Y456798D01*
X-909237Y456178D01*
X-908777Y455558D01*
X-908241Y455145D01*
X-907704Y454938D01*
X-907167D01*
X-906631Y455145D01*
X-906171Y455455D01*
X-905787Y455868D01*
G01X-898838Y454220D02*
Y448020D01*
G01X-900601Y454220D02*
X-897075D01*
G01X-894171Y448020D02*
Y454220D01*
X-892331D01*
X-891718Y453910D01*
X-891258Y453187D01*
X-891105Y452360D01*
X-891258Y451533D01*
X-891641Y450913D01*
X-892331Y450603D01*
X-894171D01*
G01X-888125Y449260D02*
X-887665Y448537D01*
X-887051Y448123D01*
X-886361Y448020D01*
X-885748Y448123D01*
X-885135Y448640D01*
X-884751Y449260D01*
X-884675Y449880D01*
X-884828Y450603D01*
X-885365Y451120D01*
X-885901Y451327D01*
X-886591D01*
G01X-885901D02*
X-885441Y451637D01*
X-885058Y452153D01*
X-884905Y452773D01*
X-885058Y453393D01*
X-885441Y453910D01*
X-886131Y454220D01*
X-886821Y454117D01*
X-887511Y453703D01*
G01X-881695Y450603D02*
X-881158Y451327D01*
X-880698Y451740D01*
X-880085Y451947D01*
X-879548Y451740D01*
X-879165Y451327D01*
X-878858Y450707D01*
X-878781Y449983D01*
X-878858Y449363D01*
X-879165Y448743D01*
X-879625Y448227D01*
X-880161Y448020D01*
X-880775Y448227D01*
X-881311Y448846D01*
X-881618Y449777D01*
X-881695Y450810D01*
X-881541Y452153D01*
X-881311Y452877D01*
X-880928Y453600D01*
X-880391Y454117D01*
X-879855Y454220D01*
X-879318Y454013D01*
X-878935Y453497D01*
G01X-909621Y473938D02*
X-907704Y480138D01*
X-905787Y473938D01*
G01X-906477Y476108D02*
X-908931D01*
G01X-896974Y462805D02*
X-903174D01*
Y464339D01*
X-902864Y464952D01*
X-902451Y465412D01*
X-901831Y465795D01*
X-901107Y466102D01*
X-900074Y466179D01*
X-899041Y466102D01*
X-898317Y465795D01*
X-897697Y465412D01*
X-897284Y464952D01*
X-896974Y464339D01*
Y462805D01*
G01X-897800Y469082D02*
X-897284Y469695D01*
X-896974Y470385D01*
Y470999D01*
X-897284Y471612D01*
X-897800Y472072D01*
X-898524Y472302D01*
X-899247Y472149D01*
X-899867Y471765D01*
X-900281Y471075D01*
X-900487Y470155D01*
X-900901Y469619D01*
X-901624Y469389D01*
X-902347Y469542D01*
X-902864Y469925D01*
X-903174Y470462D01*
Y470999D01*
X-902967Y471535D01*
X-902451Y471995D01*
G01X-896974Y476739D02*
X-898317Y476892D01*
X-899454Y477122D01*
X-900487Y477429D01*
X-901624Y477812D01*
X-903174Y478425D01*
Y475359D01*
G01X-897604Y490151D02*
X-903804D01*
Y491685D01*
X-903494Y492298D01*
X-903081Y492758D01*
X-902461Y493141D01*
X-901737Y493448D01*
X-900704Y493525D01*
X-899671Y493448D01*
X-898947Y493141D01*
X-898327Y492758D01*
X-897914Y492298D01*
X-897604Y491685D01*
Y490151D01*
G01X-898430Y496428D02*
X-897914Y497041D01*
X-897604Y497731D01*
Y498345D01*
X-897914Y498958D01*
X-898430Y499418D01*
X-899154Y499648D01*
X-899877Y499495D01*
X-900497Y499111D01*
X-900911Y498421D01*
X-901117Y497501D01*
X-901531Y496965D01*
X-902254Y496735D01*
X-902977Y496888D01*
X-903494Y497271D01*
X-903804Y497808D01*
Y498345D01*
X-903597Y498881D01*
X-903081Y499341D01*
G01X-902771Y502781D02*
X-903391Y503241D01*
X-903701Y503778D01*
X-903804Y504391D01*
X-903597Y505158D01*
X-903081Y505695D01*
X-902461Y505848D01*
X-901841Y505771D01*
X-901324Y505465D01*
X-900291Y503931D01*
X-899567Y503241D01*
X-898534Y502781D01*
X-897604Y502628D01*
Y505848D01*
G01X-902747Y508848D02*
X-900830Y515048D01*
X-898913Y508848D01*
G01X-899603Y511018D02*
X-902057D01*
G01X-893591Y-212062D02*
Y-216505D01*
X-893284Y-217436D01*
X-892671Y-218055D01*
X-891904Y-218262D01*
X-891137Y-218055D01*
X-890524Y-217436D01*
X-890217Y-216505D01*
Y-212062D01*
G01X-887161Y-213095D02*
X-886701Y-212475D01*
X-886164Y-212165D01*
X-885551Y-212062D01*
X-884784Y-212269D01*
X-884247Y-212785D01*
X-884094Y-213405D01*
X-884171Y-214025D01*
X-884477Y-214542D01*
X-886011Y-215575D01*
X-886701Y-216299D01*
X-887161Y-217332D01*
X-887314Y-218262D01*
X-884094D01*
G01X-881191Y-217332D02*
X-880731Y-217849D01*
X-880194Y-218159D01*
X-879504Y-218262D01*
X-878814Y-218055D01*
X-878277Y-217642D01*
X-877894Y-216919D01*
X-877817Y-216092D01*
X-877971Y-215265D01*
X-878354Y-214749D01*
X-878891Y-214335D01*
X-879427Y-214232D01*
X-879964Y-214335D01*
X-880654Y-214749D01*
X-880424Y-212062D01*
X-878354D01*
G01X-884317Y-189979D02*
X-884777Y-189669D01*
X-885314Y-189462D01*
X-885927D01*
X-886617Y-189772D01*
X-887154Y-190289D01*
X-887537Y-190909D01*
X-887844Y-191942D01*
X-887921Y-192872D01*
X-887767Y-193802D01*
X-887537Y-194422D01*
X-887077Y-195042D01*
X-886541Y-195455D01*
X-886004Y-195662D01*
X-885467D01*
X-884931Y-195455D01*
X-884471Y-195145D01*
X-884087Y-194732D01*
G01X-881261Y-190495D02*
X-880801Y-189875D01*
X-880264Y-189565D01*
X-879651Y-189462D01*
X-878884Y-189669D01*
X-878347Y-190185D01*
X-878194Y-190805D01*
X-878271Y-191425D01*
X-878577Y-191942D01*
X-880111Y-192975D01*
X-880801Y-193699D01*
X-881261Y-194732D01*
X-881414Y-195662D01*
X-878194D01*
G01X-875291Y-194422D02*
X-874831Y-195145D01*
X-874217Y-195559D01*
X-873527Y-195662D01*
X-872914Y-195559D01*
X-872301Y-195042D01*
X-871917Y-194422D01*
X-871841Y-193802D01*
X-871994Y-193079D01*
X-872531Y-192562D01*
X-873067Y-192355D01*
X-873757D01*
G01X-873067D02*
X-872607Y-192045D01*
X-872224Y-191529D01*
X-872071Y-190909D01*
X-872224Y-190289D01*
X-872607Y-189772D01*
X-873297Y-189462D01*
X-873987Y-189565D01*
X-874677Y-189979D01*
G01X-867404Y-189462D02*
X-868017Y-189669D01*
X-868477Y-190185D01*
X-868784Y-190805D01*
X-869014Y-191632D01*
X-869091Y-192562D01*
X-869014Y-193492D01*
X-868784Y-194319D01*
X-868477Y-194939D01*
X-868017Y-195455D01*
X-867404Y-195662D01*
X-866791Y-195455D01*
X-866331Y-194939D01*
X-866024Y-194319D01*
X-865794Y-193492D01*
X-865717Y-192562D01*
X-865794Y-191632D01*
X-866024Y-190805D01*
X-866331Y-190185D01*
X-866791Y-189669D01*
X-867404Y-189462D01*
G01X-885317Y-176579D02*
X-885777Y-176269D01*
X-886314Y-176062D01*
X-886927D01*
X-887617Y-176372D01*
X-888154Y-176889D01*
X-888537Y-177509D01*
X-888844Y-178542D01*
X-888921Y-179472D01*
X-888767Y-180402D01*
X-888537Y-181022D01*
X-888077Y-181642D01*
X-887541Y-182055D01*
X-887004Y-182262D01*
X-886467D01*
X-885931Y-182055D01*
X-885471Y-181745D01*
X-885087Y-181332D01*
G01X-882261Y-177095D02*
X-881801Y-176475D01*
X-881264Y-176165D01*
X-880651Y-176062D01*
X-879884Y-176269D01*
X-879347Y-176785D01*
X-879194Y-177405D01*
X-879271Y-178025D01*
X-879577Y-178542D01*
X-881111Y-179575D01*
X-881801Y-180299D01*
X-882261Y-181332D01*
X-882414Y-182262D01*
X-879194D01*
G01X-876061Y-177095D02*
X-875601Y-176475D01*
X-875064Y-176165D01*
X-874451Y-176062D01*
X-873684Y-176269D01*
X-873147Y-176785D01*
X-872994Y-177405D01*
X-873071Y-178025D01*
X-873377Y-178542D01*
X-874911Y-179575D01*
X-875601Y-180299D01*
X-876061Y-181332D01*
X-876214Y-182262D01*
X-872994D01*
G01X-868404D02*
X-867867Y-182159D01*
X-867254Y-181849D01*
X-866871Y-181332D01*
X-866717Y-180609D01*
X-866871Y-179885D01*
X-867331Y-179265D01*
X-868021Y-178955D01*
X-868787D01*
X-869247Y-178749D01*
X-869631Y-178232D01*
X-869784Y-177509D01*
X-869554Y-176785D01*
X-869017Y-176269D01*
X-868404Y-176062D01*
X-867791Y-176269D01*
X-867254Y-176785D01*
X-867024Y-177509D01*
X-867177Y-178232D01*
X-867561Y-178749D01*
X-868021Y-178955D01*
X-868787D01*
X-869477Y-179265D01*
X-869937Y-179885D01*
X-870091Y-180609D01*
X-869937Y-181332D01*
X-869554Y-181849D01*
X-868941Y-182159D01*
X-868404Y-182262D01*
G01X-885287Y-165575D02*
X-885597Y-166035D01*
X-885804Y-166572D01*
Y-167185D01*
X-885494Y-167875D01*
X-884977Y-168412D01*
X-884357Y-168795D01*
X-883324Y-169102D01*
X-882394Y-169179D01*
X-881464Y-169025D01*
X-880844Y-168795D01*
X-880224Y-168335D01*
X-879811Y-167799D01*
X-879604Y-167262D01*
Y-166725D01*
X-879811Y-166189D01*
X-880121Y-165729D01*
X-880534Y-165345D01*
G01X-884771Y-162519D02*
X-885391Y-162059D01*
X-885701Y-161522D01*
X-885804Y-160909D01*
X-885597Y-160142D01*
X-885081Y-159605D01*
X-884461Y-159452D01*
X-883841Y-159529D01*
X-883324Y-159835D01*
X-882291Y-161369D01*
X-881567Y-162059D01*
X-880534Y-162519D01*
X-879604Y-162672D01*
Y-159452D01*
G01X-884771Y-156319D02*
X-885391Y-155859D01*
X-885701Y-155322D01*
X-885804Y-154709D01*
X-885597Y-153942D01*
X-885081Y-153405D01*
X-884461Y-153252D01*
X-883841Y-153329D01*
X-883324Y-153635D01*
X-882291Y-155169D01*
X-881567Y-155859D01*
X-880534Y-156319D01*
X-879604Y-156472D01*
Y-153252D01*
G01X-882187Y-150119D02*
X-882911Y-149582D01*
X-883324Y-149122D01*
X-883531Y-148509D01*
X-883324Y-147972D01*
X-882911Y-147589D01*
X-882291Y-147282D01*
X-881567Y-147205D01*
X-880947Y-147282D01*
X-880327Y-147589D01*
X-879811Y-148049D01*
X-879604Y-148585D01*
X-879811Y-149199D01*
X-880430Y-149735D01*
X-881361Y-150042D01*
X-882394Y-150119D01*
X-883737Y-149965D01*
X-884461Y-149735D01*
X-885184Y-149352D01*
X-885701Y-148815D01*
X-885804Y-148279D01*
X-885597Y-147742D01*
X-885081Y-147359D01*
G01X-884317Y-27279D02*
X-884777Y-26969D01*
X-885314Y-26762D01*
X-885927D01*
X-886617Y-27072D01*
X-887154Y-27589D01*
X-887537Y-28209D01*
X-887844Y-29242D01*
X-887921Y-30172D01*
X-887767Y-31102D01*
X-887537Y-31722D01*
X-887077Y-32342D01*
X-886541Y-32755D01*
X-886004Y-32962D01*
X-885467D01*
X-884931Y-32755D01*
X-884471Y-32445D01*
X-884087Y-32032D01*
G01X-881261Y-27795D02*
X-880801Y-27175D01*
X-880264Y-26865D01*
X-879651Y-26762D01*
X-878884Y-26969D01*
X-878347Y-27485D01*
X-878194Y-28105D01*
X-878271Y-28725D01*
X-878577Y-29242D01*
X-880111Y-30275D01*
X-880801Y-30999D01*
X-881261Y-32032D01*
X-881414Y-32962D01*
X-878194D01*
G01X-875061Y-30379D02*
X-874524Y-29655D01*
X-874064Y-29242D01*
X-873451Y-29035D01*
X-872914Y-29242D01*
X-872531Y-29655D01*
X-872224Y-30275D01*
X-872147Y-30999D01*
X-872224Y-31619D01*
X-872531Y-32239D01*
X-872991Y-32755D01*
X-873527Y-32962D01*
X-874141Y-32755D01*
X-874677Y-32136D01*
X-874984Y-31205D01*
X-875061Y-30172D01*
X-874907Y-28829D01*
X-874677Y-28105D01*
X-874294Y-27382D01*
X-873757Y-26865D01*
X-873221Y-26762D01*
X-872684Y-26969D01*
X-872301Y-27485D01*
G01X-868707Y-32239D02*
X-868171Y-32755D01*
X-867557Y-32962D01*
X-866944Y-32755D01*
X-866407Y-32136D01*
X-866024Y-31205D01*
X-865871Y-30275D01*
Y-29139D01*
X-866024Y-28209D01*
X-866407Y-27382D01*
X-866867Y-26969D01*
X-867404Y-26762D01*
X-868017Y-26969D01*
X-868477Y-27382D01*
X-868784Y-28002D01*
X-868937Y-28829D01*
X-868784Y-29552D01*
X-868401Y-30275D01*
X-867941Y-30689D01*
X-867404Y-30792D01*
X-866791Y-30585D01*
X-866331Y-30069D01*
X-865871Y-29139D01*
G01X-894343Y-25687D02*
X-894963Y-25227D01*
X-895273Y-24690D01*
X-895376Y-24077D01*
X-895169Y-23310D01*
X-894653Y-22773D01*
X-894033Y-22620D01*
X-893413Y-22697D01*
X-892896Y-23003D01*
X-891863Y-24537D01*
X-891139Y-25227D01*
X-890106Y-25687D01*
X-889176Y-25840D01*
Y-22620D01*
G01X-883857Y58038D02*
X-883704Y59381D01*
X-883474Y60518D01*
X-883167Y61551D01*
X-882784Y62688D01*
X-882171Y64238D01*
X-885237D01*
G01X-889844Y57508D02*
X-896044D01*
X-894804Y56588D01*
G01X-889844D02*
Y58428D01*
G01X-877704Y67038D02*
X-877167Y67141D01*
X-876554Y67451D01*
X-876171Y67968D01*
X-876017Y68691D01*
X-876171Y69415D01*
X-876631Y70035D01*
X-877321Y70345D01*
X-878087D01*
X-878547Y70551D01*
X-878931Y71068D01*
X-879084Y71791D01*
X-878854Y72515D01*
X-878317Y73031D01*
X-877704Y73238D01*
X-877091Y73031D01*
X-876554Y72515D01*
X-876324Y71791D01*
X-876477Y71068D01*
X-876861Y70551D01*
X-877321Y70345D01*
X-878087D01*
X-878777Y70035D01*
X-879237Y69415D01*
X-879391Y68691D01*
X-879237Y67968D01*
X-878854Y67451D01*
X-878241Y67141D01*
X-877704Y67038D01*
G01X-891804Y95038D02*
Y101238D01*
X-892724Y99998D01*
G01Y95038D02*
X-890884D01*
G01X-887291Y96278D02*
X-886831Y95555D01*
X-886217Y95141D01*
X-885527Y95038D01*
X-884914Y95141D01*
X-884301Y95658D01*
X-883917Y96278D01*
X-883841Y96898D01*
X-883994Y97621D01*
X-884531Y98138D01*
X-885067Y98345D01*
X-885757D01*
G01X-885067D02*
X-884607Y98655D01*
X-884224Y99171D01*
X-884071Y99791D01*
X-884224Y100411D01*
X-884607Y100928D01*
X-885297Y101238D01*
X-885987Y101135D01*
X-886677Y100721D01*
G01X-878804Y89038D02*
Y95238D01*
X-879724Y93998D01*
G01Y89038D02*
X-877884D01*
G01X-874061Y94205D02*
X-873601Y94825D01*
X-873064Y95135D01*
X-872451Y95238D01*
X-871684Y95031D01*
X-871147Y94515D01*
X-870994Y93895D01*
X-871071Y93275D01*
X-871377Y92758D01*
X-872911Y91725D01*
X-873601Y91001D01*
X-874061Y89968D01*
X-874214Y89038D01*
X-870994D01*
G01X-884287Y105425D02*
X-884597Y104965D01*
X-884804Y104428D01*
Y103815D01*
X-884494Y103125D01*
X-883977Y102588D01*
X-883357Y102205D01*
X-882324Y101898D01*
X-881394Y101821D01*
X-880464Y101975D01*
X-879844Y102205D01*
X-879224Y102665D01*
X-878811Y103201D01*
X-878604Y103738D01*
Y104275D01*
X-878811Y104811D01*
X-879121Y105271D01*
X-879534Y105655D01*
G01X-883771Y108481D02*
X-884391Y108941D01*
X-884701Y109478D01*
X-884804Y110091D01*
X-884597Y110858D01*
X-884081Y111395D01*
X-883461Y111548D01*
X-882841Y111471D01*
X-882324Y111165D01*
X-881291Y109631D01*
X-880567Y108941D01*
X-879534Y108481D01*
X-878604Y108328D01*
Y111548D01*
G01X-881187Y114681D02*
X-881911Y115218D01*
X-882324Y115678D01*
X-882531Y116291D01*
X-882324Y116828D01*
X-881911Y117211D01*
X-881291Y117518D01*
X-880567Y117595D01*
X-879947Y117518D01*
X-879327Y117211D01*
X-878811Y116751D01*
X-878604Y116215D01*
X-878811Y115601D01*
X-879430Y115065D01*
X-880361Y114758D01*
X-881394Y114681D01*
X-882737Y114835D01*
X-883461Y115065D01*
X-884184Y115448D01*
X-884701Y115985D01*
X-884804Y116521D01*
X-884597Y117058D01*
X-884081Y117441D01*
G01X-878604Y123258D02*
X-884804D01*
X-880361Y120421D01*
Y124255D01*
G01X-893287Y110425D02*
X-893597Y109965D01*
X-893804Y109428D01*
Y108815D01*
X-893494Y108125D01*
X-892977Y107588D01*
X-892357Y107205D01*
X-891324Y106898D01*
X-890394Y106821D01*
X-889464Y106975D01*
X-888844Y107205D01*
X-888224Y107665D01*
X-887811Y108201D01*
X-887604Y108738D01*
Y109275D01*
X-887811Y109811D01*
X-888121Y110271D01*
X-888534Y110655D01*
G01X-892771Y113481D02*
X-893391Y113941D01*
X-893701Y114478D01*
X-893804Y115091D01*
X-893597Y115858D01*
X-893081Y116395D01*
X-892461Y116548D01*
X-891841Y116471D01*
X-891324Y116165D01*
X-890291Y114631D01*
X-889567Y113941D01*
X-888534Y113481D01*
X-887604Y113328D01*
Y116548D01*
G01X-888534Y119451D02*
X-888017Y119911D01*
X-887707Y120448D01*
X-887604Y121138D01*
X-887811Y121828D01*
X-888224Y122365D01*
X-888947Y122748D01*
X-889774Y122825D01*
X-890601Y122671D01*
X-891117Y122288D01*
X-891531Y121751D01*
X-891634Y121215D01*
X-891531Y120678D01*
X-891117Y119988D01*
X-893804Y120218D01*
Y122288D01*
G01X-888327Y126035D02*
X-887811Y126571D01*
X-887604Y127185D01*
X-887811Y127798D01*
X-888430Y128335D01*
X-889361Y128718D01*
X-890291Y128871D01*
X-891427D01*
X-892357Y128718D01*
X-893184Y128335D01*
X-893597Y127875D01*
X-893804Y127338D01*
X-893597Y126725D01*
X-893184Y126265D01*
X-892564Y125958D01*
X-891737Y125805D01*
X-891014Y125958D01*
X-890291Y126341D01*
X-889877Y126801D01*
X-889774Y127338D01*
X-889981Y127951D01*
X-890497Y128411D01*
X-891427Y128871D01*
G01X-886537Y128938D02*
Y135138D01*
X-884621D01*
X-884007Y134828D01*
X-883624Y134415D01*
X-883471Y133588D01*
X-883624Y132761D01*
X-884084Y132245D01*
X-884621Y131935D01*
X-886537D01*
G01X-884621D02*
X-883471Y128938D01*
G01X-880261Y134105D02*
X-879801Y134725D01*
X-879264Y135035D01*
X-878651Y135138D01*
X-877884Y134931D01*
X-877347Y134415D01*
X-877194Y133795D01*
X-877271Y133175D01*
X-877577Y132658D01*
X-879111Y131625D01*
X-879801Y130901D01*
X-880261Y129868D01*
X-880414Y128938D01*
X-877194D01*
G01X-874291Y129868D02*
X-873831Y129351D01*
X-873294Y129041D01*
X-872604Y128938D01*
X-871914Y129145D01*
X-871377Y129558D01*
X-870994Y130281D01*
X-870917Y131108D01*
X-871071Y131935D01*
X-871454Y132451D01*
X-871991Y132865D01*
X-872527Y132968D01*
X-873064Y132865D01*
X-873754Y132451D01*
X-873524Y135138D01*
X-871454D01*
G01X-865484Y128938D02*
Y135138D01*
X-868321Y130695D01*
X-864487D01*
G01X-887244Y205505D02*
X-886624Y205888D01*
X-886211Y206348D01*
X-886004Y206885D01*
X-886211Y207498D01*
X-886624Y207958D01*
X-887244Y208418D01*
X-888071Y208571D01*
X-892204D01*
G01X-886004Y213238D02*
X-892204D01*
X-890964Y212318D01*
G01X-886004D02*
Y214158D01*
G01Y220358D02*
X-892204D01*
X-887761Y217521D01*
Y221355D01*
G01X-892017Y313921D02*
X-892477Y314231D01*
X-893014Y314438D01*
X-893627D01*
X-894317Y314128D01*
X-894854Y313611D01*
X-895237Y312991D01*
X-895544Y311958D01*
X-895621Y311028D01*
X-895467Y310098D01*
X-895237Y309478D01*
X-894777Y308858D01*
X-894241Y308445D01*
X-893704Y308238D01*
X-893167D01*
X-892631Y308445D01*
X-892171Y308755D01*
X-891787Y309168D01*
G01X-893004Y347138D02*
Y340938D01*
G01X-894767Y347138D02*
X-891241D01*
G01X-888337Y340938D02*
Y347138D01*
X-886497D01*
X-885884Y346828D01*
X-885424Y346105D01*
X-885271Y345278D01*
X-885424Y344451D01*
X-885807Y343831D01*
X-886497Y343521D01*
X-888337D01*
G01X-879684Y340938D02*
Y347138D01*
X-882521Y342695D01*
X-878687D01*
G01X-876091Y342178D02*
X-875631Y341455D01*
X-875017Y341041D01*
X-874327Y340938D01*
X-873714Y341041D01*
X-873101Y341558D01*
X-872717Y342178D01*
X-872641Y342798D01*
X-872794Y343521D01*
X-873331Y344038D01*
X-873867Y344245D01*
X-874557D01*
G01X-873867D02*
X-873407Y344555D01*
X-873024Y345071D01*
X-872871Y345691D01*
X-873024Y346311D01*
X-873407Y346828D01*
X-874097Y347138D01*
X-874787Y347035D01*
X-875477Y346621D01*
G01X-888917Y365421D02*
X-889377Y365731D01*
X-889914Y365938D01*
X-890527D01*
X-891217Y365628D01*
X-891754Y365111D01*
X-892137Y364491D01*
X-892444Y363458D01*
X-892521Y362528D01*
X-892367Y361598D01*
X-892137Y360978D01*
X-891677Y360358D01*
X-891141Y359945D01*
X-890604Y359738D01*
X-890067D01*
X-889531Y359945D01*
X-889071Y360255D01*
X-888687Y360668D01*
G01X-885861Y364905D02*
X-885401Y365525D01*
X-884864Y365835D01*
X-884251Y365938D01*
X-883484Y365731D01*
X-882947Y365215D01*
X-882794Y364595D01*
X-882871Y363975D01*
X-883177Y363458D01*
X-884711Y362425D01*
X-885401Y361701D01*
X-885861Y360668D01*
X-886014Y359738D01*
X-882794D01*
G01X-879665Y411773D02*
X-879129Y411257D01*
X-878515Y411050D01*
X-877902Y411257D01*
X-877365Y411876D01*
X-876982Y412807D01*
X-876829Y413737D01*
Y414873D01*
X-876982Y415803D01*
X-877365Y416630D01*
X-877825Y417043D01*
X-878362Y417250D01*
X-878975Y417043D01*
X-879435Y416630D01*
X-879742Y416010D01*
X-879895Y415183D01*
X-879742Y414460D01*
X-879359Y413737D01*
X-878899Y413323D01*
X-878362Y413220D01*
X-877749Y413427D01*
X-877289Y413943D01*
X-876829Y414873D01*
G01X-873352Y462805D02*
X-879552D01*
Y464339D01*
X-879242Y464952D01*
X-878829Y465412D01*
X-878209Y465795D01*
X-877485Y466102D01*
X-876452Y466179D01*
X-875419Y466102D01*
X-874695Y465795D01*
X-874075Y465412D01*
X-873662Y464952D01*
X-873352Y464339D01*
Y462805D01*
G01X-874178Y469082D02*
X-873662Y469695D01*
X-873352Y470385D01*
Y470999D01*
X-873662Y471612D01*
X-874178Y472072D01*
X-874902Y472302D01*
X-875625Y472149D01*
X-876245Y471765D01*
X-876659Y471075D01*
X-876865Y470155D01*
X-877279Y469619D01*
X-878002Y469389D01*
X-878725Y469542D01*
X-879242Y469925D01*
X-879552Y470462D01*
Y470999D01*
X-879345Y471535D01*
X-878829Y471995D01*
G01X-873352Y476892D02*
X-873455Y477429D01*
X-873765Y478042D01*
X-874282Y478425D01*
X-875005Y478579D01*
X-875729Y478425D01*
X-876349Y477965D01*
X-876659Y477275D01*
Y476509D01*
X-876865Y476049D01*
X-877382Y475665D01*
X-878105Y475512D01*
X-878829Y475742D01*
X-879345Y476279D01*
X-879552Y476892D01*
X-879345Y477505D01*
X-878829Y478042D01*
X-878105Y478272D01*
X-877382Y478119D01*
X-876865Y477735D01*
X-876659Y477275D01*
Y476509D01*
X-876349Y475819D01*
X-875729Y475359D01*
X-875005Y475205D01*
X-874282Y475359D01*
X-873765Y475742D01*
X-873455Y476355D01*
X-873352Y476892D01*
G01X-892017Y486621D02*
X-892477Y486931D01*
X-893014Y487138D01*
X-893627D01*
X-894317Y486828D01*
X-894854Y486311D01*
X-895237Y485691D01*
X-895544Y484658D01*
X-895621Y483728D01*
X-895467Y482798D01*
X-895237Y482178D01*
X-894777Y481558D01*
X-894241Y481145D01*
X-893704Y480938D01*
X-893167D01*
X-892631Y481145D01*
X-892171Y481455D01*
X-891787Y481868D01*
G01X-873352Y490363D02*
X-879552D01*
Y491897D01*
X-879242Y492510D01*
X-878829Y492970D01*
X-878209Y493353D01*
X-877485Y493660D01*
X-876452Y493737D01*
X-875419Y493660D01*
X-874695Y493353D01*
X-874075Y492970D01*
X-873662Y492510D01*
X-873352Y491897D01*
Y490363D01*
G01X-874178Y496640D02*
X-873662Y497253D01*
X-873352Y497943D01*
Y498557D01*
X-873662Y499170D01*
X-874178Y499630D01*
X-874902Y499860D01*
X-875625Y499707D01*
X-876245Y499323D01*
X-876659Y498633D01*
X-876865Y497713D01*
X-877279Y497177D01*
X-878002Y496947D01*
X-878725Y497100D01*
X-879242Y497483D01*
X-879552Y498020D01*
Y498557D01*
X-879345Y499093D01*
X-878829Y499553D01*
G01X-874592Y502763D02*
X-873869Y503223D01*
X-873455Y503837D01*
X-873352Y504527D01*
X-873455Y505140D01*
X-873972Y505753D01*
X-874592Y506137D01*
X-875212Y506213D01*
X-875935Y506060D01*
X-876452Y505523D01*
X-876659Y504987D01*
Y504297D01*
G01Y504987D02*
X-876969Y505447D01*
X-877485Y505830D01*
X-878105Y505983D01*
X-878725Y505830D01*
X-879242Y505447D01*
X-879552Y504757D01*
X-879449Y504067D01*
X-879035Y503377D01*
G01X-862317Y-229279D02*
X-862777Y-228969D01*
X-863314Y-228762D01*
X-863927D01*
X-864617Y-229072D01*
X-865154Y-229589D01*
X-865537Y-230209D01*
X-865844Y-231242D01*
X-865921Y-232172D01*
X-865767Y-233102D01*
X-865537Y-233722D01*
X-865077Y-234342D01*
X-864541Y-234755D01*
X-864004Y-234962D01*
X-863467D01*
X-862931Y-234755D01*
X-862471Y-234445D01*
X-862087Y-234032D01*
G01X-859261Y-229795D02*
X-858801Y-229175D01*
X-858264Y-228865D01*
X-857651Y-228762D01*
X-856884Y-228969D01*
X-856347Y-229485D01*
X-856194Y-230105D01*
X-856271Y-230725D01*
X-856577Y-231242D01*
X-858111Y-232275D01*
X-858801Y-232999D01*
X-859261Y-234032D01*
X-859414Y-234962D01*
X-856194D01*
G01X-853291Y-233722D02*
X-852831Y-234445D01*
X-852217Y-234859D01*
X-851527Y-234962D01*
X-850914Y-234859D01*
X-850301Y-234342D01*
X-849917Y-233722D01*
X-849841Y-233102D01*
X-849994Y-232379D01*
X-850531Y-231862D01*
X-851067Y-231655D01*
X-851757D01*
G01X-851067D02*
X-850607Y-231345D01*
X-850224Y-230829D01*
X-850071Y-230209D01*
X-850224Y-229589D01*
X-850607Y-229072D01*
X-851297Y-228762D01*
X-851987Y-228865D01*
X-852677Y-229279D01*
G01X-845404Y-234962D02*
Y-228762D01*
X-846324Y-230002D01*
G01Y-234962D02*
X-844484D01*
G01X-871161Y-224379D02*
X-870624Y-223655D01*
X-870164Y-223242D01*
X-869551Y-223035D01*
X-869014Y-223242D01*
X-868631Y-223655D01*
X-868324Y-224275D01*
X-868247Y-224999D01*
X-868324Y-225619D01*
X-868631Y-226239D01*
X-869091Y-226755D01*
X-869627Y-226962D01*
X-870241Y-226755D01*
X-870777Y-226136D01*
X-871084Y-225205D01*
X-871161Y-224172D01*
X-871007Y-222829D01*
X-870777Y-222105D01*
X-870394Y-221382D01*
X-869857Y-220865D01*
X-869321Y-220762D01*
X-868784Y-220969D01*
X-868401Y-221485D01*
G01X-870804Y-206962D02*
Y-200762D01*
X-871724Y-202002D01*
G01Y-206962D02*
X-869884D01*
G01X-864604Y-200762D02*
X-865217Y-200969D01*
X-865677Y-201485D01*
X-865984Y-202105D01*
X-866214Y-202932D01*
X-866291Y-203862D01*
X-866214Y-204792D01*
X-865984Y-205619D01*
X-865677Y-206239D01*
X-865217Y-206755D01*
X-864604Y-206962D01*
X-863991Y-206755D01*
X-863531Y-206239D01*
X-863224Y-205619D01*
X-862994Y-204792D01*
X-862917Y-203862D01*
X-862994Y-202932D01*
X-863224Y-202105D01*
X-863531Y-201485D01*
X-863991Y-200969D01*
X-864604Y-200762D01*
G01X-873804Y-166695D02*
X-867604D01*
Y-163629D01*
G01Y-158962D02*
X-873804D01*
X-872564Y-159882D01*
G01X-867604D02*
Y-158042D01*
G01X-868844Y-154449D02*
X-868121Y-153989D01*
X-867707Y-153375D01*
X-867604Y-152685D01*
X-867707Y-152072D01*
X-868224Y-151459D01*
X-868844Y-151075D01*
X-869464Y-150999D01*
X-870187Y-151152D01*
X-870704Y-151689D01*
X-870911Y-152225D01*
Y-152915D01*
G01Y-152225D02*
X-871221Y-151765D01*
X-871737Y-151382D01*
X-872357Y-151229D01*
X-872977Y-151382D01*
X-873494Y-151765D01*
X-873804Y-152455D01*
X-873701Y-153145D01*
X-873287Y-153835D01*
G01X-861004Y-152862D02*
Y-159062D01*
G01X-862767Y-152862D02*
X-859241D01*
G01X-856337Y-159062D02*
Y-152862D01*
X-854497D01*
X-853884Y-153172D01*
X-853424Y-153895D01*
X-853271Y-154722D01*
X-853424Y-155549D01*
X-853807Y-156169D01*
X-854497Y-156479D01*
X-856337D01*
G01X-847684Y-159062D02*
Y-152862D01*
X-850521Y-157305D01*
X-846687D01*
G01X-842404Y-159062D02*
Y-152862D01*
X-843324Y-154102D01*
G01Y-159062D02*
X-841484D01*
G01X-861287Y65425D02*
X-861597Y64965D01*
X-861804Y64428D01*
Y63815D01*
X-861494Y63125D01*
X-860977Y62588D01*
X-860357Y62205D01*
X-859324Y61898D01*
X-858394Y61821D01*
X-857464Y61975D01*
X-856844Y62205D01*
X-856224Y62665D01*
X-855811Y63201D01*
X-855604Y63738D01*
Y64275D01*
X-855811Y64811D01*
X-856121Y65271D01*
X-856534Y65655D01*
G01X-860771Y68481D02*
X-861391Y68941D01*
X-861701Y69478D01*
X-861804Y70091D01*
X-861597Y70858D01*
X-861081Y71395D01*
X-860461Y71548D01*
X-859841Y71471D01*
X-859324Y71165D01*
X-858291Y69631D01*
X-857567Y68941D01*
X-856534Y68481D01*
X-855604Y68328D01*
Y71548D01*
G01X-856534Y74451D02*
X-856017Y74911D01*
X-855707Y75448D01*
X-855604Y76138D01*
X-855811Y76828D01*
X-856224Y77365D01*
X-856947Y77748D01*
X-857774Y77825D01*
X-858601Y77671D01*
X-859117Y77288D01*
X-859531Y76751D01*
X-859634Y76215D01*
X-859531Y75678D01*
X-859117Y74988D01*
X-861804Y75218D01*
Y77288D01*
G01X-855604Y82185D02*
X-856947Y82338D01*
X-858084Y82568D01*
X-859117Y82875D01*
X-860254Y83258D01*
X-861804Y83871D01*
Y80805D01*
G01X-873287Y67425D02*
X-873597Y66965D01*
X-873804Y66428D01*
Y65815D01*
X-873494Y65125D01*
X-872977Y64588D01*
X-872357Y64205D01*
X-871324Y63898D01*
X-870394Y63821D01*
X-869464Y63975D01*
X-868844Y64205D01*
X-868224Y64665D01*
X-867811Y65201D01*
X-867604Y65738D01*
Y66275D01*
X-867811Y66811D01*
X-868121Y67271D01*
X-868534Y67655D01*
G01X-872771Y70481D02*
X-873391Y70941D01*
X-873701Y71478D01*
X-873804Y72091D01*
X-873597Y72858D01*
X-873081Y73395D01*
X-872461Y73548D01*
X-871841Y73471D01*
X-871324Y73165D01*
X-870291Y71631D01*
X-869567Y70941D01*
X-868534Y70481D01*
X-867604Y70328D01*
Y73548D01*
G01X-870187Y76681D02*
X-870911Y77218D01*
X-871324Y77678D01*
X-871531Y78291D01*
X-871324Y78828D01*
X-870911Y79211D01*
X-870291Y79518D01*
X-869567Y79595D01*
X-868947Y79518D01*
X-868327Y79211D01*
X-867811Y78751D01*
X-867604Y78215D01*
X-867811Y77601D01*
X-868430Y77065D01*
X-869361Y76758D01*
X-870394Y76681D01*
X-871737Y76835D01*
X-872461Y77065D01*
X-873184Y77448D01*
X-873701Y77985D01*
X-873804Y78521D01*
X-873597Y79058D01*
X-873081Y79441D01*
G01X-872771Y82881D02*
X-873391Y83341D01*
X-873701Y83878D01*
X-873804Y84491D01*
X-873597Y85258D01*
X-873081Y85795D01*
X-872461Y85948D01*
X-871841Y85871D01*
X-871324Y85565D01*
X-870291Y84031D01*
X-869567Y83341D01*
X-868534Y82881D01*
X-867604Y82728D01*
Y85948D01*
G01X-867537Y95038D02*
Y101238D01*
X-865621D01*
X-865007Y100928D01*
X-864624Y100515D01*
X-864471Y99688D01*
X-864624Y98861D01*
X-865084Y98345D01*
X-865621Y98035D01*
X-867537D01*
G01X-865621D02*
X-864471Y95038D01*
G01X-861261Y100205D02*
X-860801Y100825D01*
X-860264Y101135D01*
X-859651Y101238D01*
X-858884Y101031D01*
X-858347Y100515D01*
X-858194Y99895D01*
X-858271Y99275D01*
X-858577Y98758D01*
X-860111Y97725D01*
X-860801Y97001D01*
X-861261Y95968D01*
X-861414Y95038D01*
X-858194D01*
G01X-852684D02*
Y101238D01*
X-855521Y96795D01*
X-851687D01*
G01X-847404Y95038D02*
X-846867Y95141D01*
X-846254Y95451D01*
X-845871Y95968D01*
X-845717Y96691D01*
X-845871Y97415D01*
X-846331Y98035D01*
X-847021Y98345D01*
X-847787D01*
X-848247Y98551D01*
X-848631Y99068D01*
X-848784Y99791D01*
X-848554Y100515D01*
X-848017Y101031D01*
X-847404Y101238D01*
X-846791Y101031D01*
X-846254Y100515D01*
X-846024Y99791D01*
X-846177Y99068D01*
X-846561Y98551D01*
X-847021Y98345D01*
X-847787D01*
X-848477Y98035D01*
X-848937Y97415D01*
X-849091Y96691D01*
X-848937Y95968D01*
X-848554Y95451D01*
X-847941Y95141D01*
X-847404Y95038D01*
G01X-856804Y107205D02*
X-863004D01*
Y109121D01*
X-862694Y109735D01*
X-862281Y110118D01*
X-861454Y110271D01*
X-860627Y110118D01*
X-860111Y109658D01*
X-859801Y109121D01*
Y107205D01*
G01Y109121D02*
X-856804Y110271D01*
G01X-861971Y113481D02*
X-862591Y113941D01*
X-862901Y114478D01*
X-863004Y115091D01*
X-862797Y115858D01*
X-862281Y116395D01*
X-861661Y116548D01*
X-861041Y116471D01*
X-860524Y116165D01*
X-859491Y114631D01*
X-858767Y113941D01*
X-857734Y113481D01*
X-856804Y113328D01*
Y116548D01*
G01X-857734Y119451D02*
X-857217Y119911D01*
X-856907Y120448D01*
X-856804Y121138D01*
X-857011Y121828D01*
X-857424Y122365D01*
X-858147Y122748D01*
X-858974Y122825D01*
X-859801Y122671D01*
X-860317Y122288D01*
X-860731Y121751D01*
X-860834Y121215D01*
X-860731Y120678D01*
X-860317Y119988D01*
X-863004Y120218D01*
Y122288D01*
G01X-857734Y125651D02*
X-857217Y126111D01*
X-856907Y126648D01*
X-856804Y127338D01*
X-857011Y128028D01*
X-857424Y128565D01*
X-858147Y128948D01*
X-858974Y129025D01*
X-859801Y128871D01*
X-860317Y128488D01*
X-860731Y127951D01*
X-860834Y127415D01*
X-860731Y126878D01*
X-860317Y126188D01*
X-863004Y126418D01*
Y128488D01*
G01X-873287Y106425D02*
X-873597Y105965D01*
X-873804Y105428D01*
Y104815D01*
X-873494Y104125D01*
X-872977Y103588D01*
X-872357Y103205D01*
X-871324Y102898D01*
X-870394Y102821D01*
X-869464Y102975D01*
X-868844Y103205D01*
X-868224Y103665D01*
X-867811Y104201D01*
X-867604Y104738D01*
Y105275D01*
X-867811Y105811D01*
X-868121Y106271D01*
X-868534Y106655D01*
G01X-872771Y109481D02*
X-873391Y109941D01*
X-873701Y110478D01*
X-873804Y111091D01*
X-873597Y111858D01*
X-873081Y112395D01*
X-872461Y112548D01*
X-871841Y112471D01*
X-871324Y112165D01*
X-870291Y110631D01*
X-869567Y109941D01*
X-868534Y109481D01*
X-867604Y109328D01*
Y112548D01*
G01X-870187Y115681D02*
X-870911Y116218D01*
X-871324Y116678D01*
X-871531Y117291D01*
X-871324Y117828D01*
X-870911Y118211D01*
X-870291Y118518D01*
X-869567Y118595D01*
X-868947Y118518D01*
X-868327Y118211D01*
X-867811Y117751D01*
X-867604Y117215D01*
X-867811Y116601D01*
X-868430Y116065D01*
X-869361Y115758D01*
X-870394Y115681D01*
X-871737Y115835D01*
X-872461Y116065D01*
X-873184Y116448D01*
X-873701Y116985D01*
X-873804Y117521D01*
X-873597Y118058D01*
X-873081Y118441D01*
G01X-867604Y123185D02*
X-868947Y123338D01*
X-870084Y123568D01*
X-871117Y123875D01*
X-872254Y124258D01*
X-873804Y124871D01*
Y121805D01*
G01X-864004Y145138D02*
Y138938D01*
G01X-865767Y145138D02*
X-862241D01*
G01X-859337Y138938D02*
Y145138D01*
X-857497D01*
X-856884Y144828D01*
X-856424Y144105D01*
X-856271Y143278D01*
X-856424Y142451D01*
X-856807Y141831D01*
X-857497Y141521D01*
X-859337D01*
G01X-853291Y140178D02*
X-852831Y139455D01*
X-852217Y139041D01*
X-851527Y138938D01*
X-850914Y139041D01*
X-850301Y139558D01*
X-849917Y140178D01*
X-849841Y140798D01*
X-849994Y141521D01*
X-850531Y142038D01*
X-851067Y142245D01*
X-851757D01*
G01X-851067D02*
X-850607Y142555D01*
X-850224Y143071D01*
X-850071Y143691D01*
X-850224Y144311D01*
X-850607Y144828D01*
X-851297Y145138D01*
X-851987Y145035D01*
X-852677Y144621D01*
G01X-846707Y139661D02*
X-846171Y139145D01*
X-845557Y138938D01*
X-844944Y139145D01*
X-844407Y139764D01*
X-844024Y140695D01*
X-843871Y141625D01*
Y142761D01*
X-844024Y143691D01*
X-844407Y144518D01*
X-844867Y144931D01*
X-845404Y145138D01*
X-846017Y144931D01*
X-846477Y144518D01*
X-846784Y143898D01*
X-846937Y143071D01*
X-846784Y142348D01*
X-846401Y141625D01*
X-845941Y141211D01*
X-845404Y141108D01*
X-844791Y141315D01*
X-844331Y141831D01*
X-843871Y142761D01*
G01X-867137Y339338D02*
Y345538D01*
X-865221D01*
X-864607Y345228D01*
X-864224Y344815D01*
X-864071Y343988D01*
X-864224Y343161D01*
X-864684Y342645D01*
X-865221Y342335D01*
X-867137D01*
G01X-865221D02*
X-864071Y339338D01*
G01X-858484D02*
Y345538D01*
X-861321Y341095D01*
X-857487D01*
G01X-867137Y349338D02*
Y355538D01*
X-865221D01*
X-864607Y355228D01*
X-864224Y354815D01*
X-864071Y353988D01*
X-864224Y353161D01*
X-864684Y352645D01*
X-865221Y352335D01*
X-867137D01*
G01X-865221D02*
X-864071Y349338D01*
G01X-861091Y350268D02*
X-860631Y349751D01*
X-860094Y349441D01*
X-859404Y349338D01*
X-858714Y349545D01*
X-858177Y349958D01*
X-857794Y350681D01*
X-857717Y351508D01*
X-857871Y352335D01*
X-858254Y352851D01*
X-858791Y353265D01*
X-859327Y353368D01*
X-859864Y353265D01*
X-860554Y352851D01*
X-860324Y355538D01*
X-858254D01*
G01X-863917Y365021D02*
X-864377Y365331D01*
X-864914Y365538D01*
X-865527D01*
X-866217Y365228D01*
X-866754Y364711D01*
X-867137Y364091D01*
X-867444Y363058D01*
X-867521Y362128D01*
X-867367Y361198D01*
X-867137Y360578D01*
X-866677Y359958D01*
X-866141Y359545D01*
X-865604Y359338D01*
X-865067D01*
X-864531Y359545D01*
X-864071Y359855D01*
X-863687Y360268D01*
G01X-861091Y360578D02*
X-860631Y359855D01*
X-860017Y359441D01*
X-859327Y359338D01*
X-858714Y359441D01*
X-858101Y359958D01*
X-857717Y360578D01*
X-857641Y361198D01*
X-857794Y361921D01*
X-858331Y362438D01*
X-858867Y362645D01*
X-859557D01*
G01X-858867D02*
X-858407Y362955D01*
X-858024Y363471D01*
X-857871Y364091D01*
X-858024Y364711D01*
X-858407Y365228D01*
X-859097Y365538D01*
X-859787Y365435D01*
X-860477Y365021D01*
G01X-867137Y369338D02*
Y375538D01*
X-865221D01*
X-864607Y375228D01*
X-864224Y374815D01*
X-864071Y373988D01*
X-864224Y373161D01*
X-864684Y372645D01*
X-865221Y372335D01*
X-867137D01*
G01X-865221D02*
X-864071Y369338D01*
G01X-859557D02*
X-859404Y370681D01*
X-859174Y371818D01*
X-858867Y372851D01*
X-858484Y373988D01*
X-857871Y375538D01*
X-860937D01*
G01X-867137Y379338D02*
Y385538D01*
X-865221D01*
X-864607Y385228D01*
X-864224Y384815D01*
X-864071Y383988D01*
X-864224Y383161D01*
X-864684Y382645D01*
X-865221Y382335D01*
X-867137D01*
G01X-865221D02*
X-864071Y379338D01*
G01X-859404D02*
X-858867Y379441D01*
X-858254Y379751D01*
X-857871Y380268D01*
X-857717Y380991D01*
X-857871Y381715D01*
X-858331Y382335D01*
X-859021Y382645D01*
X-859787D01*
X-860247Y382851D01*
X-860631Y383368D01*
X-860784Y384091D01*
X-860554Y384815D01*
X-860017Y385331D01*
X-859404Y385538D01*
X-858791Y385331D01*
X-858254Y384815D01*
X-858024Y384091D01*
X-858177Y383368D01*
X-858561Y382851D01*
X-859021Y382645D01*
X-859787D01*
X-860477Y382335D01*
X-860937Y381715D01*
X-861091Y380991D01*
X-860937Y380268D01*
X-860554Y379751D01*
X-859941Y379441D01*
X-859404Y379338D01*
G01X-867917Y394021D02*
X-868377Y394331D01*
X-868914Y394538D01*
X-869527D01*
X-870217Y394228D01*
X-870754Y393711D01*
X-871137Y393091D01*
X-871444Y392058D01*
X-871521Y391128D01*
X-871367Y390198D01*
X-871137Y389578D01*
X-870677Y388958D01*
X-870141Y388545D01*
X-869604Y388338D01*
X-869067D01*
X-868531Y388545D01*
X-868071Y388855D01*
X-867687Y389268D01*
G01X-862484Y388338D02*
Y394538D01*
X-865321Y390095D01*
X-861487D01*
G01X-870237Y397338D02*
Y403538D01*
X-868321D01*
X-867707Y403228D01*
X-867324Y402815D01*
X-867171Y401988D01*
X-867324Y401161D01*
X-867784Y400645D01*
X-868321Y400335D01*
X-870237D01*
G01X-868321D02*
X-867171Y397338D01*
G01X-861584D02*
Y403538D01*
X-864421Y399095D01*
X-860587D01*
G01X-857761Y399921D02*
X-857224Y400645D01*
X-856764Y401058D01*
X-856151Y401265D01*
X-855614Y401058D01*
X-855231Y400645D01*
X-854924Y400025D01*
X-854847Y399301D01*
X-854924Y398681D01*
X-855231Y398061D01*
X-855691Y397545D01*
X-856227Y397338D01*
X-856841Y397545D01*
X-857377Y398164D01*
X-857684Y399095D01*
X-857761Y400128D01*
X-857607Y401471D01*
X-857377Y402195D01*
X-856994Y402918D01*
X-856457Y403435D01*
X-855921Y403538D01*
X-855384Y403331D01*
X-855001Y402815D01*
G01X-863917Y413021D02*
X-864377Y413331D01*
X-864914Y413538D01*
X-865527D01*
X-866217Y413228D01*
X-866754Y412711D01*
X-867137Y412091D01*
X-867444Y411058D01*
X-867521Y410128D01*
X-867367Y409198D01*
X-867137Y408578D01*
X-866677Y407958D01*
X-866141Y407545D01*
X-865604Y407338D01*
X-865067D01*
X-864531Y407545D01*
X-864071Y407855D01*
X-863687Y408268D01*
G01X-861091D02*
X-860631Y407751D01*
X-860094Y407441D01*
X-859404Y407338D01*
X-858714Y407545D01*
X-858177Y407958D01*
X-857794Y408681D01*
X-857717Y409508D01*
X-857871Y410335D01*
X-858254Y410851D01*
X-858791Y411265D01*
X-859327Y411368D01*
X-859864Y411265D01*
X-860554Y410851D01*
X-860324Y413538D01*
X-858254D01*
G01X-863917Y423021D02*
X-864377Y423331D01*
X-864914Y423538D01*
X-865527D01*
X-866217Y423228D01*
X-866754Y422711D01*
X-867137Y422091D01*
X-867444Y421058D01*
X-867521Y420128D01*
X-867367Y419198D01*
X-867137Y418578D01*
X-866677Y417958D01*
X-866141Y417545D01*
X-865604Y417338D01*
X-865067D01*
X-864531Y417545D01*
X-864071Y417855D01*
X-863687Y418268D01*
G01X-859557Y417338D02*
X-859404Y418681D01*
X-859174Y419818D01*
X-858867Y420851D01*
X-858484Y421988D01*
X-857871Y423538D01*
X-860937D01*
G01X-875238Y445220D02*
Y439020D01*
G01X-877001Y445220D02*
X-873475D01*
G01X-870571Y439020D02*
Y445220D01*
X-868731D01*
X-868118Y444910D01*
X-867658Y444187D01*
X-867505Y443360D01*
X-867658Y442533D01*
X-868041Y441913D01*
X-868731Y441603D01*
X-870571D01*
G01X-864525Y440260D02*
X-864065Y439537D01*
X-863451Y439123D01*
X-862761Y439020D01*
X-862148Y439123D01*
X-861535Y439640D01*
X-861151Y440260D01*
X-861075Y440880D01*
X-861228Y441603D01*
X-861765Y442120D01*
X-862301Y442327D01*
X-862991D01*
G01X-862301D02*
X-861841Y442637D01*
X-861458Y443153D01*
X-861305Y443773D01*
X-861458Y444393D01*
X-861841Y444910D01*
X-862531Y445220D01*
X-863221Y445117D01*
X-863911Y444703D01*
G01X-856791Y439020D02*
X-856638Y440363D01*
X-856408Y441500D01*
X-856101Y442533D01*
X-855718Y443670D01*
X-855105Y445220D01*
X-858171D01*
G01X-870237Y427338D02*
Y433538D01*
X-868321D01*
X-867707Y433228D01*
X-867324Y432815D01*
X-867171Y431988D01*
X-867324Y431161D01*
X-867784Y430645D01*
X-868321Y430335D01*
X-870237D01*
G01X-868321D02*
X-867171Y427338D01*
G01X-862504D02*
Y433538D01*
X-863424Y432298D01*
G01Y427338D02*
X-861584D01*
G01X-857991Y428268D02*
X-857531Y427751D01*
X-856994Y427441D01*
X-856304Y427338D01*
X-855614Y427545D01*
X-855077Y427958D01*
X-854694Y428681D01*
X-854617Y429508D01*
X-854771Y430335D01*
X-855154Y430851D01*
X-855691Y431265D01*
X-856227Y431368D01*
X-856764Y431265D01*
X-857454Y430851D01*
X-857224Y433538D01*
X-855154D01*
G01X-868017Y459621D02*
X-868477Y459931D01*
X-869014Y460138D01*
X-869627D01*
X-870317Y459828D01*
X-870854Y459311D01*
X-871237Y458691D01*
X-871544Y457658D01*
X-871621Y456728D01*
X-871467Y455798D01*
X-871237Y455178D01*
X-870777Y454558D01*
X-870241Y454145D01*
X-869704Y453938D01*
X-869167D01*
X-868631Y454145D01*
X-868171Y454455D01*
X-867787Y454868D01*
G01X-872769Y479692D02*
X-870852Y485892D01*
X-868935Y479692D01*
G01X-869625Y481862D02*
X-872079D01*
G01X-867017Y493621D02*
X-867477Y493931D01*
X-868014Y494138D01*
X-868627D01*
X-869317Y493828D01*
X-869854Y493311D01*
X-870237Y492691D01*
X-870544Y491658D01*
X-870621Y490728D01*
X-870467Y489798D01*
X-870237Y489178D01*
X-869777Y488558D01*
X-869241Y488145D01*
X-868704Y487938D01*
X-868167D01*
X-867631Y488145D01*
X-867171Y488455D01*
X-866787Y488868D01*
G01X-877621Y509938D02*
X-875704Y516138D01*
X-873787Y509938D01*
G01X-874477Y512108D02*
X-876931D01*
G01X-858887Y-222775D02*
X-859197Y-223235D01*
X-859404Y-223772D01*
Y-224385D01*
X-859094Y-225075D01*
X-858577Y-225612D01*
X-857957Y-225995D01*
X-856924Y-226302D01*
X-855994Y-226379D01*
X-855064Y-226225D01*
X-854444Y-225995D01*
X-853824Y-225535D01*
X-853411Y-224999D01*
X-853204Y-224462D01*
Y-223925D01*
X-853411Y-223389D01*
X-853721Y-222929D01*
X-854134Y-222545D01*
G01X-858371Y-219719D02*
X-858991Y-219259D01*
X-859301Y-218722D01*
X-859404Y-218109D01*
X-859197Y-217342D01*
X-858681Y-216805D01*
X-858061Y-216652D01*
X-857441Y-216729D01*
X-856924Y-217035D01*
X-855891Y-218569D01*
X-855167Y-219259D01*
X-854134Y-219719D01*
X-853204Y-219872D01*
Y-216652D01*
G01X-858371Y-213519D02*
X-858991Y-213059D01*
X-859301Y-212522D01*
X-859404Y-211909D01*
X-859197Y-211142D01*
X-858681Y-210605D01*
X-858061Y-210452D01*
X-857441Y-210529D01*
X-856924Y-210835D01*
X-855891Y-212369D01*
X-855167Y-213059D01*
X-854134Y-213519D01*
X-853204Y-213672D01*
Y-210452D01*
G01Y-206015D02*
X-854547Y-205862D01*
X-855684Y-205632D01*
X-856717Y-205325D01*
X-857854Y-204942D01*
X-859404Y-204329D01*
Y-207395D01*
G01X-852704Y-200795D02*
X-858904D01*
Y-198879D01*
X-858594Y-198265D01*
X-858181Y-197882D01*
X-857354Y-197729D01*
X-856527Y-197882D01*
X-856011Y-198342D01*
X-855701Y-198879D01*
Y-200795D01*
G01Y-198879D02*
X-852704Y-197729D01*
G01X-857871Y-194519D02*
X-858491Y-194059D01*
X-858801Y-193522D01*
X-858904Y-192909D01*
X-858697Y-192142D01*
X-858181Y-191605D01*
X-857561Y-191452D01*
X-856941Y-191529D01*
X-856424Y-191835D01*
X-855391Y-193369D01*
X-854667Y-194059D01*
X-853634Y-194519D01*
X-852704Y-194672D01*
Y-191452D01*
G01X-857871Y-188319D02*
X-858491Y-187859D01*
X-858801Y-187322D01*
X-858904Y-186709D01*
X-858697Y-185942D01*
X-858181Y-185405D01*
X-857561Y-185252D01*
X-856941Y-185329D01*
X-856424Y-185635D01*
X-855391Y-187169D01*
X-854667Y-187859D01*
X-853634Y-188319D01*
X-852704Y-188472D01*
Y-185252D01*
G01Y-180662D02*
X-852807Y-180125D01*
X-853117Y-179512D01*
X-853634Y-179129D01*
X-854357Y-178975D01*
X-855081Y-179129D01*
X-855701Y-179589D01*
X-856011Y-180279D01*
Y-181045D01*
X-856217Y-181505D01*
X-856734Y-181889D01*
X-857457Y-182042D01*
X-858181Y-181812D01*
X-858697Y-181275D01*
X-858904Y-180662D01*
X-858697Y-180049D01*
X-858181Y-179512D01*
X-857457Y-179282D01*
X-856734Y-179435D01*
X-856217Y-179819D01*
X-856011Y-180279D01*
Y-181045D01*
X-855701Y-181735D01*
X-855081Y-182195D01*
X-854357Y-182349D01*
X-853634Y-182195D01*
X-853117Y-181812D01*
X-852807Y-181199D01*
X-852704Y-180662D01*
G01X-858838Y-138180D02*
Y-144380D01*
G01X-860601Y-138180D02*
X-857075D01*
G01X-854171Y-144380D02*
Y-138180D01*
X-852331D01*
X-851718Y-138490D01*
X-851258Y-139213D01*
X-851105Y-140040D01*
X-851258Y-140867D01*
X-851641Y-141487D01*
X-852331Y-141797D01*
X-854171D01*
G01X-847895Y-139213D02*
X-847435Y-138593D01*
X-846898Y-138283D01*
X-846285Y-138180D01*
X-845518Y-138387D01*
X-844981Y-138903D01*
X-844828Y-139523D01*
X-844905Y-140143D01*
X-845211Y-140660D01*
X-846745Y-141693D01*
X-847435Y-142417D01*
X-847895Y-143450D01*
X-848048Y-144380D01*
X-844828D01*
G01X-841695Y-139213D02*
X-841235Y-138593D01*
X-840698Y-138283D01*
X-840085Y-138180D01*
X-839318Y-138387D01*
X-838781Y-138903D01*
X-838628Y-139523D01*
X-838705Y-140143D01*
X-839011Y-140660D01*
X-840545Y-141693D01*
X-841235Y-142417D01*
X-841695Y-143450D01*
X-841848Y-144380D01*
X-838628D01*
G01X-848004Y20138D02*
Y13938D01*
G01X-849767Y20138D02*
X-846241D01*
G01X-843337Y13938D02*
Y20138D01*
X-841497D01*
X-840884Y19828D01*
X-840424Y19105D01*
X-840271Y18278D01*
X-840424Y17451D01*
X-840807Y16831D01*
X-841497Y16521D01*
X-843337D01*
G01X-837061Y19105D02*
X-836601Y19725D01*
X-836064Y20035D01*
X-835451Y20138D01*
X-834684Y19931D01*
X-834147Y19415D01*
X-833994Y18795D01*
X-834071Y18175D01*
X-834377Y17658D01*
X-835911Y16625D01*
X-836601Y15901D01*
X-837061Y14868D01*
X-837214Y13938D01*
X-833994D01*
G01X-829557D02*
X-829404Y15281D01*
X-829174Y16418D01*
X-828867Y17451D01*
X-828484Y18588D01*
X-827871Y20138D01*
X-830937D01*
G01X-853704Y170038D02*
Y176238D01*
X-854624Y174998D01*
G01Y170038D02*
X-852784D01*
G01X-857007Y250761D02*
X-856471Y250245D01*
X-855857Y250038D01*
X-855244Y250245D01*
X-854707Y250864D01*
X-854324Y251795D01*
X-854171Y252725D01*
Y253861D01*
X-854324Y254791D01*
X-854707Y255618D01*
X-855167Y256031D01*
X-855704Y256238D01*
X-856317Y256031D01*
X-856777Y255618D01*
X-857084Y254998D01*
X-857237Y254171D01*
X-857084Y253448D01*
X-856701Y252725D01*
X-856241Y252311D01*
X-855704Y252208D01*
X-855091Y252415D01*
X-854631Y252931D01*
X-854171Y253861D01*
G01X-851743Y459375D02*
X-852203Y459685D01*
X-852740Y459892D01*
X-853353D01*
X-854043Y459582D01*
X-854580Y459065D01*
X-854963Y458445D01*
X-855270Y457412D01*
X-855347Y456482D01*
X-855193Y455552D01*
X-854963Y454932D01*
X-854503Y454312D01*
X-853967Y453899D01*
X-853430Y453692D01*
X-852893D01*
X-852357Y453899D01*
X-851897Y454209D01*
X-851513Y454622D01*
G01X-849730Y462805D02*
X-855930D01*
Y464339D01*
X-855620Y464952D01*
X-855207Y465412D01*
X-854587Y465795D01*
X-853863Y466102D01*
X-852830Y466179D01*
X-851797Y466102D01*
X-851073Y465795D01*
X-850453Y465412D01*
X-850040Y464952D01*
X-849730Y464339D01*
Y462805D01*
G01X-850556Y469082D02*
X-850040Y469695D01*
X-849730Y470385D01*
Y470999D01*
X-850040Y471612D01*
X-850556Y472072D01*
X-851280Y472302D01*
X-852003Y472149D01*
X-852623Y471765D01*
X-853037Y471075D01*
X-853243Y470155D01*
X-853657Y469619D01*
X-854380Y469389D01*
X-855103Y469542D01*
X-855620Y469925D01*
X-855930Y470462D01*
Y470999D01*
X-855723Y471535D01*
X-855207Y471995D01*
G01X-850660Y475205D02*
X-850143Y475665D01*
X-849833Y476202D01*
X-849730Y476892D01*
X-849937Y477582D01*
X-850350Y478119D01*
X-851073Y478502D01*
X-851900Y478579D01*
X-852727Y478425D01*
X-853243Y478042D01*
X-853657Y477505D01*
X-853760Y476969D01*
X-853657Y476432D01*
X-853243Y475742D01*
X-855930Y475972D01*
Y478042D01*
G01X-849621Y479938D02*
X-847704Y486138D01*
X-845787Y479938D01*
G01X-846477Y482108D02*
X-848931D01*
G01X-842017Y494621D02*
X-842477Y494931D01*
X-843014Y495138D01*
X-843627D01*
X-844317Y494828D01*
X-844854Y494311D01*
X-845237Y493691D01*
X-845544Y492658D01*
X-845621Y491728D01*
X-845467Y490798D01*
X-845237Y490178D01*
X-844777Y489558D01*
X-844241Y489145D01*
X-843704Y488938D01*
X-843167D01*
X-842631Y489145D01*
X-842171Y489455D01*
X-841787Y489868D01*
G01X-849730Y490363D02*
X-855930D01*
Y491897D01*
X-855620Y492510D01*
X-855207Y492970D01*
X-854587Y493353D01*
X-853863Y493660D01*
X-852830Y493737D01*
X-851797Y493660D01*
X-851073Y493353D01*
X-850453Y492970D01*
X-850040Y492510D01*
X-849730Y491897D01*
Y490363D01*
G01X-850556Y496640D02*
X-850040Y497253D01*
X-849730Y497943D01*
Y498557D01*
X-850040Y499170D01*
X-850556Y499630D01*
X-851280Y499860D01*
X-852003Y499707D01*
X-852623Y499323D01*
X-853037Y498633D01*
X-853243Y497713D01*
X-853657Y497177D01*
X-854380Y496947D01*
X-855103Y497100D01*
X-855620Y497483D01*
X-855930Y498020D01*
Y498557D01*
X-855723Y499093D01*
X-855207Y499553D01*
G01X-849730Y505370D02*
X-855930D01*
X-851487Y502533D01*
Y506367D01*
G01X-854999Y508848D02*
X-853082Y515048D01*
X-851165Y508848D01*
G01X-851855Y511018D02*
X-854309D01*
G01X-831537Y-161062D02*
Y-154862D01*
X-829621D01*
X-829007Y-155172D01*
X-828624Y-155585D01*
X-828471Y-156412D01*
X-828624Y-157239D01*
X-829084Y-157755D01*
X-829621Y-158065D01*
X-831537D01*
G01X-829621D02*
X-828471Y-161062D01*
G01X-822884D02*
Y-154862D01*
X-825721Y-159305D01*
X-821887D01*
G01X-819061Y-155895D02*
X-818601Y-155275D01*
X-818064Y-154965D01*
X-817451Y-154862D01*
X-816684Y-155069D01*
X-816147Y-155585D01*
X-815994Y-156205D01*
X-816071Y-156825D01*
X-816377Y-157342D01*
X-817911Y-158375D01*
X-818601Y-159099D01*
X-819061Y-160132D01*
X-819214Y-161062D01*
X-815994D01*
G01X-813091Y-159822D02*
X-812631Y-160545D01*
X-812017Y-160959D01*
X-811327Y-161062D01*
X-810714Y-160959D01*
X-810101Y-160442D01*
X-809717Y-159822D01*
X-809641Y-159202D01*
X-809794Y-158479D01*
X-810331Y-157962D01*
X-810867Y-157755D01*
X-811557D01*
G01X-810867D02*
X-810407Y-157445D01*
X-810024Y-156929D01*
X-809871Y-156309D01*
X-810024Y-155689D01*
X-810407Y-155172D01*
X-811097Y-154862D01*
X-811787Y-154965D01*
X-812477Y-155379D01*
G01X-831437Y-149062D02*
Y-142862D01*
X-829521D01*
X-828907Y-143172D01*
X-828524Y-143585D01*
X-828371Y-144412D01*
X-828524Y-145239D01*
X-828984Y-145755D01*
X-829521Y-146065D01*
X-831437D01*
G01X-829521D02*
X-828371Y-149062D01*
G01X-825161Y-143895D02*
X-824701Y-143275D01*
X-824164Y-142965D01*
X-823551Y-142862D01*
X-822784Y-143069D01*
X-822247Y-143585D01*
X-822094Y-144205D01*
X-822171Y-144825D01*
X-822477Y-145342D01*
X-824011Y-146375D01*
X-824701Y-147099D01*
X-825161Y-148132D01*
X-825314Y-149062D01*
X-822094D01*
G01X-817504D02*
Y-142862D01*
X-818424Y-144102D01*
G01Y-149062D02*
X-816584D01*
G01X-832537Y-138062D02*
Y-131862D01*
X-830621D01*
X-830007Y-132172D01*
X-829624Y-132585D01*
X-829471Y-133412D01*
X-829624Y-134239D01*
X-830084Y-134755D01*
X-830621Y-135065D01*
X-832537D01*
G01X-830621D02*
X-829471Y-138062D01*
G01X-823884D02*
Y-131862D01*
X-826721Y-136305D01*
X-822887D01*
G01X-818604Y-131862D02*
X-819217Y-132069D01*
X-819677Y-132585D01*
X-819984Y-133205D01*
X-820214Y-134032D01*
X-820291Y-134962D01*
X-820214Y-135892D01*
X-819984Y-136719D01*
X-819677Y-137339D01*
X-819217Y-137855D01*
X-818604Y-138062D01*
X-817991Y-137855D01*
X-817531Y-137339D01*
X-817224Y-136719D01*
X-816994Y-135892D01*
X-816917Y-134962D01*
X-816994Y-134032D01*
X-817224Y-133205D01*
X-817531Y-132585D01*
X-817991Y-132069D01*
X-818604Y-131862D01*
G01X-812557Y-138062D02*
X-812404Y-136719D01*
X-812174Y-135582D01*
X-811867Y-134549D01*
X-811484Y-133412D01*
X-810871Y-131862D01*
X-813937D01*
G01X-832437Y-128062D02*
Y-121862D01*
X-830521D01*
X-829907Y-122172D01*
X-829524Y-122585D01*
X-829371Y-123412D01*
X-829524Y-124239D01*
X-829984Y-124755D01*
X-830521Y-125065D01*
X-832437D01*
G01X-830521D02*
X-829371Y-128062D01*
G01X-826161Y-122895D02*
X-825701Y-122275D01*
X-825164Y-121965D01*
X-824551Y-121862D01*
X-823784Y-122069D01*
X-823247Y-122585D01*
X-823094Y-123205D01*
X-823171Y-123825D01*
X-823477Y-124342D01*
X-825011Y-125375D01*
X-825701Y-126099D01*
X-826161Y-127132D01*
X-826314Y-128062D01*
X-823094D01*
G01X-818504Y-121862D02*
X-819117Y-122069D01*
X-819577Y-122585D01*
X-819884Y-123205D01*
X-820114Y-124032D01*
X-820191Y-124962D01*
X-820114Y-125892D01*
X-819884Y-126719D01*
X-819577Y-127339D01*
X-819117Y-127855D01*
X-818504Y-128062D01*
X-817891Y-127855D01*
X-817431Y-127339D01*
X-817124Y-126719D01*
X-816894Y-125892D01*
X-816817Y-124962D01*
X-816894Y-124032D01*
X-817124Y-123205D01*
X-817431Y-122585D01*
X-817891Y-122069D01*
X-818504Y-121862D01*
G01X-824804Y-115062D02*
Y-108862D01*
X-825724Y-110102D01*
G01Y-115062D02*
X-823884D01*
G01X-820061Y-109895D02*
X-819601Y-109275D01*
X-819064Y-108965D01*
X-818451Y-108862D01*
X-817684Y-109069D01*
X-817147Y-109585D01*
X-816994Y-110205D01*
X-817071Y-110825D01*
X-817377Y-111342D01*
X-818911Y-112375D01*
X-819601Y-113099D01*
X-820061Y-114132D01*
X-820214Y-115062D01*
X-816994D01*
G01X-823800Y27235D02*
X-830000D01*
Y29151D01*
X-829690Y29765D01*
X-829277Y30148D01*
X-828450Y30301D01*
X-827623Y30148D01*
X-827107Y29688D01*
X-826797Y29151D01*
Y27235D01*
G01Y29151D02*
X-823800Y30301D01*
G01X-826383Y33511D02*
X-827107Y34048D01*
X-827520Y34508D01*
X-827727Y35121D01*
X-827520Y35658D01*
X-827107Y36041D01*
X-826487Y36348D01*
X-825763Y36425D01*
X-825143Y36348D01*
X-824523Y36041D01*
X-824007Y35581D01*
X-823800Y35045D01*
X-824007Y34431D01*
X-824626Y33895D01*
X-825557Y33588D01*
X-826590Y33511D01*
X-827933Y33665D01*
X-828657Y33895D01*
X-829380Y34278D01*
X-829897Y34815D01*
X-830000Y35351D01*
X-829793Y35888D01*
X-829277Y36271D01*
G01X-826383Y39711D02*
X-827107Y40248D01*
X-827520Y40708D01*
X-827727Y41321D01*
X-827520Y41858D01*
X-827107Y42241D01*
X-826487Y42548D01*
X-825763Y42625D01*
X-825143Y42548D01*
X-824523Y42241D01*
X-824007Y41781D01*
X-823800Y41245D01*
X-824007Y40631D01*
X-824626Y40095D01*
X-825557Y39788D01*
X-826590Y39711D01*
X-827933Y39865D01*
X-828657Y40095D01*
X-829380Y40478D01*
X-829897Y41015D01*
X-830000Y41551D01*
X-829793Y42088D01*
X-829277Y42471D01*
G01X-824704Y81938D02*
X-824167Y82041D01*
X-823554Y82351D01*
X-823171Y82868D01*
X-823017Y83591D01*
X-823171Y84315D01*
X-823631Y84935D01*
X-824321Y85245D01*
X-825087D01*
X-825547Y85451D01*
X-825931Y85968D01*
X-826084Y86691D01*
X-825854Y87415D01*
X-825317Y87931D01*
X-824704Y88138D01*
X-824091Y87931D01*
X-823554Y87415D01*
X-823324Y86691D01*
X-823477Y85968D01*
X-823861Y85451D01*
X-824321Y85245D01*
X-825087D01*
X-825777Y84935D01*
X-826237Y84315D01*
X-826391Y83591D01*
X-826237Y82868D01*
X-825854Y82351D01*
X-825241Y82041D01*
X-824704Y81938D01*
G01X-837431Y93738D02*
Y99938D01*
X-835515D01*
X-834901Y99628D01*
X-834518Y99215D01*
X-834365Y98388D01*
X-834518Y97561D01*
X-834978Y97045D01*
X-835515Y96735D01*
X-837431D01*
G01X-835515D02*
X-834365Y93738D01*
G01X-831155Y98905D02*
X-830695Y99525D01*
X-830158Y99835D01*
X-829545Y99938D01*
X-828778Y99731D01*
X-828241Y99215D01*
X-828088Y98595D01*
X-828165Y97975D01*
X-828471Y97458D01*
X-830005Y96425D01*
X-830695Y95701D01*
X-831155Y94668D01*
X-831308Y93738D01*
X-828088D01*
G01X-824801Y94461D02*
X-824265Y93945D01*
X-823651Y93738D01*
X-823038Y93945D01*
X-822501Y94564D01*
X-822118Y95495D01*
X-821965Y96425D01*
Y97561D01*
X-822118Y98491D01*
X-822501Y99318D01*
X-822961Y99731D01*
X-823498Y99938D01*
X-824111Y99731D01*
X-824571Y99318D01*
X-824878Y98698D01*
X-825031Y97871D01*
X-824878Y97148D01*
X-824495Y96425D01*
X-824035Y96011D01*
X-823498Y95908D01*
X-822885Y96115D01*
X-822425Y96631D01*
X-821965Y97561D01*
G01X-818755Y96321D02*
X-818218Y97045D01*
X-817758Y97458D01*
X-817145Y97665D01*
X-816608Y97458D01*
X-816225Y97045D01*
X-815918Y96425D01*
X-815841Y95701D01*
X-815918Y95081D01*
X-816225Y94461D01*
X-816685Y93945D01*
X-817221Y93738D01*
X-817835Y93945D01*
X-818371Y94564D01*
X-818678Y95495D01*
X-818755Y96528D01*
X-818601Y97871D01*
X-818371Y98595D01*
X-817988Y99318D01*
X-817451Y99835D01*
X-816915Y99938D01*
X-816378Y99731D01*
X-815995Y99215D01*
G01X-837431Y111938D02*
Y118138D01*
X-835515D01*
X-834901Y117828D01*
X-834518Y117415D01*
X-834365Y116588D01*
X-834518Y115761D01*
X-834978Y115245D01*
X-835515Y114935D01*
X-837431D01*
G01X-835515D02*
X-834365Y111938D01*
G01X-831155Y117105D02*
X-830695Y117725D01*
X-830158Y118035D01*
X-829545Y118138D01*
X-828778Y117931D01*
X-828241Y117415D01*
X-828088Y116795D01*
X-828165Y116175D01*
X-828471Y115658D01*
X-830005Y114625D01*
X-830695Y113901D01*
X-831155Y112868D01*
X-831308Y111938D01*
X-828088D01*
G01X-824801Y112661D02*
X-824265Y112145D01*
X-823651Y111938D01*
X-823038Y112145D01*
X-822501Y112764D01*
X-822118Y113695D01*
X-821965Y114625D01*
Y115761D01*
X-822118Y116691D01*
X-822501Y117518D01*
X-822961Y117931D01*
X-823498Y118138D01*
X-824111Y117931D01*
X-824571Y117518D01*
X-824878Y116898D01*
X-825031Y116071D01*
X-824878Y115348D01*
X-824495Y114625D01*
X-824035Y114211D01*
X-823498Y114108D01*
X-822885Y114315D01*
X-822425Y114831D01*
X-821965Y115761D01*
G01X-817298Y111938D02*
X-816761Y112041D01*
X-816148Y112351D01*
X-815765Y112868D01*
X-815611Y113591D01*
X-815765Y114315D01*
X-816225Y114935D01*
X-816915Y115245D01*
X-817681D01*
X-818141Y115451D01*
X-818525Y115968D01*
X-818678Y116691D01*
X-818448Y117415D01*
X-817911Y117931D01*
X-817298Y118138D01*
X-816685Y117931D01*
X-816148Y117415D01*
X-815918Y116691D01*
X-816071Y115968D01*
X-816455Y115451D01*
X-816915Y115245D01*
X-817681D01*
X-818371Y114935D01*
X-818831Y114315D01*
X-818985Y113591D01*
X-818831Y112868D01*
X-818448Y112351D01*
X-817835Y112041D01*
X-817298Y111938D01*
G01X-837431Y102742D02*
Y108942D01*
X-835515D01*
X-834901Y108632D01*
X-834518Y108219D01*
X-834365Y107392D01*
X-834518Y106565D01*
X-834978Y106049D01*
X-835515Y105739D01*
X-837431D01*
G01X-835515D02*
X-834365Y102742D01*
G01X-831155Y107909D02*
X-830695Y108529D01*
X-830158Y108839D01*
X-829545Y108942D01*
X-828778Y108735D01*
X-828241Y108219D01*
X-828088Y107599D01*
X-828165Y106979D01*
X-828471Y106462D01*
X-830005Y105429D01*
X-830695Y104705D01*
X-831155Y103672D01*
X-831308Y102742D01*
X-828088D01*
G01X-824801Y103465D02*
X-824265Y102949D01*
X-823651Y102742D01*
X-823038Y102949D01*
X-822501Y103568D01*
X-822118Y104499D01*
X-821965Y105429D01*
Y106565D01*
X-822118Y107495D01*
X-822501Y108322D01*
X-822961Y108735D01*
X-823498Y108942D01*
X-824111Y108735D01*
X-824571Y108322D01*
X-824878Y107702D01*
X-825031Y106875D01*
X-824878Y106152D01*
X-824495Y105429D01*
X-824035Y105015D01*
X-823498Y104912D01*
X-822885Y105119D01*
X-822425Y105635D01*
X-821965Y106565D01*
G01X-817451Y102742D02*
X-817298Y104085D01*
X-817068Y105222D01*
X-816761Y106255D01*
X-816378Y107392D01*
X-815765Y108942D01*
X-818831D01*
G01X-827838Y130220D02*
Y124020D01*
G01X-829601Y130220D02*
X-826075D01*
G01X-823171Y124020D02*
Y130220D01*
X-821331D01*
X-820718Y129910D01*
X-820258Y129187D01*
X-820105Y128360D01*
X-820258Y127533D01*
X-820641Y126913D01*
X-821331Y126603D01*
X-823171D01*
G01X-816895Y129187D02*
X-816435Y129807D01*
X-815898Y130117D01*
X-815285Y130220D01*
X-814518Y130013D01*
X-813981Y129497D01*
X-813828Y128877D01*
X-813905Y128257D01*
X-814211Y127740D01*
X-815745Y126707D01*
X-816435Y125983D01*
X-816895Y124950D01*
X-817048Y124020D01*
X-813828D01*
G01X-810695Y126603D02*
X-810158Y127327D01*
X-809698Y127740D01*
X-809085Y127947D01*
X-808548Y127740D01*
X-808165Y127327D01*
X-807858Y126707D01*
X-807781Y125983D01*
X-807858Y125363D01*
X-808165Y124743D01*
X-808625Y124227D01*
X-809161Y124020D01*
X-809775Y124227D01*
X-810311Y124846D01*
X-810618Y125777D01*
X-810695Y126810D01*
X-810541Y128153D01*
X-810311Y128877D01*
X-809928Y129600D01*
X-809391Y130117D01*
X-808855Y130220D01*
X-808318Y130013D01*
X-807935Y129497D01*
G01X-826161Y172105D02*
X-825701Y172725D01*
X-825164Y173035D01*
X-824551Y173138D01*
X-823784Y172931D01*
X-823247Y172415D01*
X-823094Y171795D01*
X-823171Y171175D01*
X-823477Y170658D01*
X-825011Y169625D01*
X-825701Y168901D01*
X-826161Y167868D01*
X-826314Y166938D01*
X-823094D01*
G01X-830804Y250038D02*
Y256238D01*
X-831724Y254998D01*
G01Y250038D02*
X-829884D01*
G01X-824604Y256238D02*
X-825217Y256031D01*
X-825677Y255515D01*
X-825984Y254895D01*
X-826214Y254068D01*
X-826291Y253138D01*
X-826214Y252208D01*
X-825984Y251381D01*
X-825677Y250761D01*
X-825217Y250245D01*
X-824604Y250038D01*
X-823991Y250245D01*
X-823531Y250761D01*
X-823224Y251381D01*
X-822994Y252208D01*
X-822917Y253138D01*
X-822994Y254068D01*
X-823224Y254895D01*
X-823531Y255515D01*
X-823991Y256031D01*
X-824604Y256238D01*
G01X-835023Y295711D02*
X-834486Y296435D01*
X-834026Y296848D01*
X-833413Y297055D01*
X-832876Y296848D01*
X-832493Y296435D01*
X-832186Y295815D01*
X-832109Y295091D01*
X-832186Y294471D01*
X-832493Y293851D01*
X-832953Y293335D01*
X-833489Y293128D01*
X-834103Y293335D01*
X-834639Y293954D01*
X-834946Y294885D01*
X-835023Y295918D01*
X-834869Y297261D01*
X-834639Y297985D01*
X-834256Y298708D01*
X-833719Y299225D01*
X-833183Y299328D01*
X-832646Y299121D01*
X-832263Y298605D01*
G01X-830664Y408620D02*
Y414820D01*
X-833501Y410377D01*
X-829667D01*
G01X-828172Y459705D02*
X-834372D01*
Y461239D01*
X-834062Y461852D01*
X-833649Y462312D01*
X-833029Y462695D01*
X-832305Y463002D01*
X-831272Y463079D01*
X-830239Y463002D01*
X-829515Y462695D01*
X-828895Y462312D01*
X-828482Y461852D01*
X-828172Y461239D01*
Y459705D01*
G01X-828998Y465982D02*
X-828482Y466595D01*
X-828172Y467285D01*
Y467899D01*
X-828482Y468512D01*
X-828998Y468972D01*
X-829722Y469202D01*
X-830445Y469049D01*
X-831065Y468665D01*
X-831479Y467975D01*
X-831685Y467055D01*
X-832099Y466519D01*
X-832822Y466289D01*
X-833545Y466442D01*
X-834062Y466825D01*
X-834372Y467362D01*
Y467899D01*
X-834165Y468435D01*
X-833649Y468895D01*
G01X-828172Y473792D02*
X-834372D01*
X-833132Y472872D01*
G01X-828172D02*
Y474712D01*
G01X-828895Y478689D02*
X-828379Y479225D01*
X-828172Y479839D01*
X-828379Y480452D01*
X-828998Y480989D01*
X-829929Y481372D01*
X-830859Y481525D01*
X-831995D01*
X-832925Y481372D01*
X-833752Y480989D01*
X-834165Y480529D01*
X-834372Y479992D01*
X-834165Y479379D01*
X-833752Y478919D01*
X-833132Y478612D01*
X-832305Y478459D01*
X-831582Y478612D01*
X-830859Y478995D01*
X-830445Y479455D01*
X-830342Y479992D01*
X-830549Y480605D01*
X-831065Y481065D01*
X-831995Y481525D01*
G01X-827542Y484175D02*
X-833742Y486092D01*
X-827542Y488009D01*
G01X-829712Y487319D02*
Y484865D01*
G01X-819161Y21105D02*
X-818701Y21725D01*
X-818164Y22035D01*
X-817551Y22138D01*
X-816784Y21931D01*
X-816247Y21415D01*
X-816094Y20795D01*
X-816171Y20175D01*
X-816477Y19658D01*
X-818011Y18625D01*
X-818701Y17901D01*
X-819161Y16868D01*
X-819314Y15938D01*
X-816094D01*
G01X-804604Y25205D02*
X-810804D01*
Y27121D01*
X-810494Y27735D01*
X-810081Y28118D01*
X-809254Y28271D01*
X-808427Y28118D01*
X-807911Y27658D01*
X-807601Y27121D01*
Y25205D01*
G01Y27121D02*
X-804604Y28271D01*
G01X-809771Y31481D02*
X-810391Y31941D01*
X-810701Y32478D01*
X-810804Y33091D01*
X-810597Y33858D01*
X-810081Y34395D01*
X-809461Y34548D01*
X-808841Y34471D01*
X-808324Y34165D01*
X-807291Y32631D01*
X-806567Y31941D01*
X-805534Y31481D01*
X-804604Y31328D01*
Y34548D01*
G01X-805327Y37835D02*
X-804811Y38371D01*
X-804604Y38985D01*
X-804811Y39598D01*
X-805430Y40135D01*
X-806361Y40518D01*
X-807291Y40671D01*
X-808427D01*
X-809357Y40518D01*
X-810184Y40135D01*
X-810597Y39675D01*
X-810804Y39138D01*
X-810597Y38525D01*
X-810184Y38065D01*
X-809564Y37758D01*
X-808737Y37605D01*
X-808014Y37758D01*
X-807291Y38141D01*
X-806877Y38601D01*
X-806774Y39138D01*
X-806981Y39751D01*
X-807497Y40211D01*
X-808427Y40671D01*
G01X-805327Y44035D02*
X-804811Y44571D01*
X-804604Y45185D01*
X-804811Y45798D01*
X-805430Y46335D01*
X-806361Y46718D01*
X-807291Y46871D01*
X-808427D01*
X-809357Y46718D01*
X-810184Y46335D01*
X-810597Y45875D01*
X-810804Y45338D01*
X-810597Y44725D01*
X-810184Y44265D01*
X-809564Y43958D01*
X-808737Y43805D01*
X-808014Y43958D01*
X-807291Y44341D01*
X-806877Y44801D01*
X-806774Y45338D01*
X-806981Y45951D01*
X-807497Y46411D01*
X-808427Y46871D01*
G01X-813800Y27235D02*
X-820000D01*
Y29151D01*
X-819690Y29765D01*
X-819277Y30148D01*
X-818450Y30301D01*
X-817623Y30148D01*
X-817107Y29688D01*
X-816797Y29151D01*
Y27235D01*
G01Y29151D02*
X-813800Y30301D01*
G01X-816383Y33511D02*
X-817107Y34048D01*
X-817520Y34508D01*
X-817727Y35121D01*
X-817520Y35658D01*
X-817107Y36041D01*
X-816487Y36348D01*
X-815763Y36425D01*
X-815143Y36348D01*
X-814523Y36041D01*
X-814007Y35581D01*
X-813800Y35045D01*
X-814007Y34431D01*
X-814626Y33895D01*
X-815557Y33588D01*
X-816590Y33511D01*
X-817933Y33665D01*
X-818657Y33895D01*
X-819380Y34278D01*
X-819897Y34815D01*
X-820000Y35351D01*
X-819793Y35888D01*
X-819277Y36271D01*
G01X-813800Y41168D02*
X-813903Y41705D01*
X-814213Y42318D01*
X-814730Y42701D01*
X-815453Y42855D01*
X-816177Y42701D01*
X-816797Y42241D01*
X-817107Y41551D01*
Y40785D01*
X-817313Y40325D01*
X-817830Y39941D01*
X-818553Y39788D01*
X-819277Y40018D01*
X-819793Y40555D01*
X-820000Y41168D01*
X-819793Y41781D01*
X-819277Y42318D01*
X-818553Y42548D01*
X-817830Y42395D01*
X-817313Y42011D01*
X-817107Y41551D01*
Y40785D01*
X-816797Y40095D01*
X-816177Y39635D01*
X-815453Y39481D01*
X-814730Y39635D01*
X-814213Y40018D01*
X-813903Y40631D01*
X-813800Y41168D01*
G01X-820591Y70138D02*
Y65695D01*
X-820284Y64764D01*
X-819671Y64145D01*
X-818904Y63938D01*
X-818137Y64145D01*
X-817524Y64764D01*
X-817217Y65695D01*
Y70138D01*
G01X-814161Y69105D02*
X-813701Y69725D01*
X-813164Y70035D01*
X-812551Y70138D01*
X-811784Y69931D01*
X-811247Y69415D01*
X-811094Y68795D01*
X-811171Y68175D01*
X-811477Y67658D01*
X-813011Y66625D01*
X-813701Y65901D01*
X-814161Y64868D01*
X-814314Y63938D01*
X-811094D01*
G01X-806657D02*
X-806504Y65281D01*
X-806274Y66418D01*
X-805967Y67451D01*
X-805584Y68588D01*
X-804971Y70138D01*
X-808037D01*
G01X-808317Y96621D02*
X-808777Y96931D01*
X-809314Y97138D01*
X-809927D01*
X-810617Y96828D01*
X-811154Y96311D01*
X-811537Y95691D01*
X-811844Y94658D01*
X-811921Y93728D01*
X-811767Y92798D01*
X-811537Y92178D01*
X-811077Y91558D01*
X-810541Y91145D01*
X-810004Y90938D01*
X-809467D01*
X-808931Y91145D01*
X-808471Y91455D01*
X-808087Y91868D01*
G01X-805261Y96105D02*
X-804801Y96725D01*
X-804264Y97035D01*
X-803651Y97138D01*
X-802884Y96931D01*
X-802347Y96415D01*
X-802194Y95795D01*
X-802271Y95175D01*
X-802577Y94658D01*
X-804111Y93625D01*
X-804801Y92901D01*
X-805261Y91868D01*
X-805414Y90938D01*
X-802194D01*
G01X-797757D02*
X-797604Y92281D01*
X-797374Y93418D01*
X-797067Y94451D01*
X-796684Y95588D01*
X-796071Y97138D01*
X-799137D01*
G01X-790484Y90938D02*
Y97138D01*
X-793321Y92695D01*
X-789487D01*
G01X-808317Y105621D02*
X-808777Y105931D01*
X-809314Y106138D01*
X-809927D01*
X-810617Y105828D01*
X-811154Y105311D01*
X-811537Y104691D01*
X-811844Y103658D01*
X-811921Y102728D01*
X-811767Y101798D01*
X-811537Y101178D01*
X-811077Y100558D01*
X-810541Y100145D01*
X-810004Y99938D01*
X-809467D01*
X-808931Y100145D01*
X-808471Y100455D01*
X-808087Y100868D01*
G01X-805261Y105105D02*
X-804801Y105725D01*
X-804264Y106035D01*
X-803651Y106138D01*
X-802884Y105931D01*
X-802347Y105415D01*
X-802194Y104795D01*
X-802271Y104175D01*
X-802577Y103658D01*
X-804111Y102625D01*
X-804801Y101901D01*
X-805261Y100868D01*
X-805414Y99938D01*
X-802194D01*
G01X-797757D02*
X-797604Y101281D01*
X-797374Y102418D01*
X-797067Y103451D01*
X-796684Y104588D01*
X-796071Y106138D01*
X-799137D01*
G01X-793091Y100868D02*
X-792631Y100351D01*
X-792094Y100041D01*
X-791404Y99938D01*
X-790714Y100145D01*
X-790177Y100558D01*
X-789794Y101281D01*
X-789717Y102108D01*
X-789871Y102935D01*
X-790254Y103451D01*
X-790791Y103865D01*
X-791327Y103968D01*
X-791864Y103865D01*
X-792554Y103451D01*
X-792324Y106138D01*
X-790254D01*
G01X-821017Y458621D02*
X-821477Y458931D01*
X-822014Y459138D01*
X-822627D01*
X-823317Y458828D01*
X-823854Y458311D01*
X-824237Y457691D01*
X-824544Y456658D01*
X-824621Y455728D01*
X-824467Y454798D01*
X-824237Y454178D01*
X-823777Y453558D01*
X-823241Y453145D01*
X-822704Y452938D01*
X-822167D01*
X-821631Y453145D01*
X-821171Y453455D01*
X-820787Y453868D01*
G01X-815621Y475938D02*
X-813704Y482138D01*
X-811787Y475938D01*
G01X-812477Y478108D02*
X-814931D01*
G01X-789584Y-154562D02*
Y-148362D01*
X-792421Y-152805D01*
X-788587D01*
G01X-793800Y27235D02*
X-800000D01*
Y29151D01*
X-799690Y29765D01*
X-799277Y30148D01*
X-798450Y30301D01*
X-797623Y30148D01*
X-797107Y29688D01*
X-796797Y29151D01*
Y27235D01*
G01Y29151D02*
X-793800Y30301D01*
G01X-796383Y33511D02*
X-797107Y34048D01*
X-797520Y34508D01*
X-797727Y35121D01*
X-797520Y35658D01*
X-797107Y36041D01*
X-796487Y36348D01*
X-795763Y36425D01*
X-795143Y36348D01*
X-794523Y36041D01*
X-794007Y35581D01*
X-793800Y35045D01*
X-794007Y34431D01*
X-794626Y33895D01*
X-795557Y33588D01*
X-796590Y33511D01*
X-797933Y33665D01*
X-798657Y33895D01*
X-799380Y34278D01*
X-799897Y34815D01*
X-800000Y35351D01*
X-799793Y35888D01*
X-799277Y36271D01*
G01X-793800Y41015D02*
X-795143Y41168D01*
X-796280Y41398D01*
X-797313Y41705D01*
X-798450Y42088D01*
X-800000Y42701D01*
Y39635D01*
G01X-796784Y47938D02*
Y54138D01*
X-799621Y49695D01*
X-795787D01*
G01X-803391Y80868D02*
X-802931Y80351D01*
X-802394Y80041D01*
X-801704Y79938D01*
X-801014Y80145D01*
X-800477Y80558D01*
X-800094Y81281D01*
X-800017Y82108D01*
X-800171Y82935D01*
X-800554Y83451D01*
X-801091Y83865D01*
X-801627Y83968D01*
X-802164Y83865D01*
X-802854Y83451D01*
X-802624Y86138D01*
X-800554D01*
G01X-806437Y117970D02*
Y111770D01*
X-803371D01*
G01X-798704D02*
Y117970D01*
X-799624Y116730D01*
G01Y111770D02*
X-797784D01*
G01X-792657D02*
X-792504Y113113D01*
X-792274Y114250D01*
X-791967Y115283D01*
X-791584Y116420D01*
X-790971Y117970D01*
X-794037D01*
G01X-800743Y293388D02*
X-800283Y292665D01*
X-799669Y292251D01*
X-798979Y292148D01*
X-798366Y292251D01*
X-797753Y292768D01*
X-797369Y293388D01*
X-797293Y294008D01*
X-797446Y294731D01*
X-797983Y295248D01*
X-798519Y295455D01*
X-799209D01*
G01X-798519D02*
X-798059Y295765D01*
X-797676Y296281D01*
X-797523Y296901D01*
X-797676Y297521D01*
X-798059Y298038D01*
X-798749Y298348D01*
X-799439Y298245D01*
X-800129Y297831D01*
G01X-796340Y407394D02*
Y413594D01*
X-797260Y412354D01*
G01Y407394D02*
X-795420D01*
G01X-803017Y455621D02*
X-803477Y455931D01*
X-804014Y456138D01*
X-804627D01*
X-805317Y455828D01*
X-805854Y455311D01*
X-806237Y454691D01*
X-806544Y453658D01*
X-806621Y452728D01*
X-806467Y451798D01*
X-806237Y451178D01*
X-805777Y450558D01*
X-805241Y450145D01*
X-804704Y449938D01*
X-804167D01*
X-803631Y450145D01*
X-803171Y450455D01*
X-802787Y450868D01*
G01X-802604Y461051D02*
X-808804D01*
Y462585D01*
X-808494Y463198D01*
X-808081Y463658D01*
X-807461Y464041D01*
X-806737Y464348D01*
X-805704Y464425D01*
X-804671Y464348D01*
X-803947Y464041D01*
X-803327Y463658D01*
X-802914Y463198D01*
X-802604Y462585D01*
Y461051D01*
G01X-803430Y467328D02*
X-802914Y467941D01*
X-802604Y468631D01*
Y469245D01*
X-802914Y469858D01*
X-803430Y470318D01*
X-804154Y470548D01*
X-804877Y470395D01*
X-805497Y470011D01*
X-805911Y469321D01*
X-806117Y468401D01*
X-806531Y467865D01*
X-807254Y467635D01*
X-807977Y467788D01*
X-808494Y468171D01*
X-808804Y468708D01*
Y469245D01*
X-808597Y469781D01*
X-808081Y470241D01*
G01X-807771Y473681D02*
X-808391Y474141D01*
X-808701Y474678D01*
X-808804Y475291D01*
X-808597Y476058D01*
X-808081Y476595D01*
X-807461Y476748D01*
X-806841Y476671D01*
X-806324Y476365D01*
X-805291Y474831D01*
X-804567Y474141D01*
X-803534Y473681D01*
X-802604Y473528D01*
Y476748D01*
G01X-808804Y481338D02*
X-808597Y480725D01*
X-808081Y480265D01*
X-807461Y479958D01*
X-806634Y479728D01*
X-805704Y479651D01*
X-804774Y479728D01*
X-803947Y479958D01*
X-803327Y480265D01*
X-802811Y480725D01*
X-802604Y481338D01*
X-802811Y481951D01*
X-803327Y482411D01*
X-803947Y482718D01*
X-804774Y482948D01*
X-805704Y483025D01*
X-806634Y482948D01*
X-807461Y482718D01*
X-808081Y482411D01*
X-808597Y481951D01*
X-808804Y481338D01*
G01X-802604Y488051D02*
X-808804D01*
Y489585D01*
X-808494Y490198D01*
X-808081Y490658D01*
X-807461Y491041D01*
X-806737Y491348D01*
X-805704Y491425D01*
X-804671Y491348D01*
X-803947Y491041D01*
X-803327Y490658D01*
X-802914Y490198D01*
X-802604Y489585D01*
Y488051D01*
G01X-803430Y494328D02*
X-802914Y494941D01*
X-802604Y495631D01*
Y496245D01*
X-802914Y496858D01*
X-803430Y497318D01*
X-804154Y497548D01*
X-804877Y497395D01*
X-805497Y497011D01*
X-805911Y496321D01*
X-806117Y495401D01*
X-806531Y494865D01*
X-807254Y494635D01*
X-807977Y494788D01*
X-808494Y495171D01*
X-808804Y495708D01*
Y496245D01*
X-808597Y496781D01*
X-808081Y497241D01*
G01X-802604Y502138D02*
X-808804D01*
X-807564Y501218D01*
G01X-802604D02*
Y503058D01*
G01X-808804Y508338D02*
X-808597Y507725D01*
X-808081Y507265D01*
X-807461Y506958D01*
X-806634Y506728D01*
X-805704Y506651D01*
X-804774Y506728D01*
X-803947Y506958D01*
X-803327Y507265D01*
X-802811Y507725D01*
X-802604Y508338D01*
X-802811Y508951D01*
X-803327Y509411D01*
X-803947Y509718D01*
X-804774Y509948D01*
X-805704Y510025D01*
X-806634Y509948D01*
X-807461Y509718D01*
X-808081Y509411D01*
X-808597Y508951D01*
X-808804Y508338D01*
G01X-796017Y494621D02*
X-796477Y494931D01*
X-797014Y495138D01*
X-797627D01*
X-798317Y494828D01*
X-798854Y494311D01*
X-799237Y493691D01*
X-799544Y492658D01*
X-799621Y491728D01*
X-799467Y490798D01*
X-799237Y490178D01*
X-798777Y489558D01*
X-798241Y489145D01*
X-797704Y488938D01*
X-797167D01*
X-796631Y489145D01*
X-796171Y489455D01*
X-795787Y489868D01*
G01X-808621Y513938D02*
X-806704Y520138D01*
X-804787Y513938D01*
G01X-805477Y516108D02*
X-807931D01*
G01X-783591Y-138862D02*
Y-143305D01*
X-783284Y-144236D01*
X-782671Y-144855D01*
X-781904Y-145062D01*
X-781137Y-144855D01*
X-780524Y-144236D01*
X-780217Y-143305D01*
Y-138862D01*
G01X-777391Y-143822D02*
X-776931Y-144545D01*
X-776317Y-144959D01*
X-775627Y-145062D01*
X-775014Y-144959D01*
X-774401Y-144442D01*
X-774017Y-143822D01*
X-773941Y-143202D01*
X-774094Y-142479D01*
X-774631Y-141962D01*
X-775167Y-141755D01*
X-775857D01*
G01X-775167D02*
X-774707Y-141445D01*
X-774324Y-140929D01*
X-774171Y-140309D01*
X-774324Y-139689D01*
X-774707Y-139172D01*
X-775397Y-138862D01*
X-776087Y-138965D01*
X-776777Y-139379D01*
G01X-770961Y-142479D02*
X-770424Y-141755D01*
X-769964Y-141342D01*
X-769351Y-141135D01*
X-768814Y-141342D01*
X-768431Y-141755D01*
X-768124Y-142375D01*
X-768047Y-143099D01*
X-768124Y-143719D01*
X-768431Y-144339D01*
X-768891Y-144855D01*
X-769427Y-145062D01*
X-770041Y-144855D01*
X-770577Y-144236D01*
X-770884Y-143305D01*
X-770961Y-142272D01*
X-770807Y-140929D01*
X-770577Y-140205D01*
X-770194Y-139482D01*
X-769657Y-138965D01*
X-769121Y-138862D01*
X-768584Y-139069D01*
X-768201Y-139585D01*
G01X-773804Y-116062D02*
Y-109862D01*
X-774724Y-111102D01*
G01Y-116062D02*
X-772884D01*
G01X-767604D02*
Y-109862D01*
X-768524Y-111102D01*
G01Y-116062D02*
X-766684D01*
G01X-773704Y17938D02*
Y24138D01*
X-774624Y22898D01*
G01Y17938D02*
X-772784D01*
G01X-785087Y104325D02*
X-785397Y103865D01*
X-785604Y103328D01*
Y102715D01*
X-785294Y102025D01*
X-784777Y101488D01*
X-784157Y101105D01*
X-783124Y100798D01*
X-782194Y100721D01*
X-781264Y100875D01*
X-780644Y101105D01*
X-780024Y101565D01*
X-779611Y102101D01*
X-779404Y102638D01*
Y103175D01*
X-779611Y103711D01*
X-779921Y104171D01*
X-780334Y104555D01*
G01X-779404Y109758D02*
X-785604D01*
X-781161Y106921D01*
Y110755D01*
G01X-785604Y115038D02*
X-785397Y114425D01*
X-784881Y113965D01*
X-784261Y113658D01*
X-783434Y113428D01*
X-782504Y113351D01*
X-781574Y113428D01*
X-780747Y113658D01*
X-780127Y113965D01*
X-779611Y114425D01*
X-779404Y115038D01*
X-779611Y115651D01*
X-780127Y116111D01*
X-780747Y116418D01*
X-781574Y116648D01*
X-782504Y116725D01*
X-783434Y116648D01*
X-784261Y116418D01*
X-784881Y116111D01*
X-785397Y115651D01*
X-785604Y115038D01*
G01X-784644Y204305D02*
X-784024Y204688D01*
X-783611Y205148D01*
X-783404Y205685D01*
X-783611Y206298D01*
X-784024Y206758D01*
X-784644Y207218D01*
X-785471Y207371D01*
X-789604D01*
G01X-783404Y212038D02*
X-789604D01*
X-788364Y211118D01*
G01X-783404D02*
Y212958D01*
G01X-789604Y218238D02*
X-789397Y217625D01*
X-788881Y217165D01*
X-788261Y216858D01*
X-787434Y216628D01*
X-786504Y216551D01*
X-785574Y216628D01*
X-784747Y216858D01*
X-784127Y217165D01*
X-783611Y217625D01*
X-783404Y218238D01*
X-783611Y218851D01*
X-784127Y219311D01*
X-784747Y219618D01*
X-785574Y219848D01*
X-786504Y219925D01*
X-787434Y219848D01*
X-788261Y219618D01*
X-788881Y219311D01*
X-789397Y218851D01*
X-789604Y218238D01*
G01X-784770Y346373D02*
X-790970D01*
Y348213D01*
X-790660Y348826D01*
X-789937Y349286D01*
X-789110Y349439D01*
X-788283Y349286D01*
X-787663Y348903D01*
X-787353Y348213D01*
Y346373D01*
G01X-786010Y352419D02*
X-785287Y352879D01*
X-784873Y353493D01*
X-784770Y354183D01*
X-784873Y354796D01*
X-785390Y355409D01*
X-786010Y355793D01*
X-786630Y355869D01*
X-787353Y355716D01*
X-787870Y355179D01*
X-788077Y354643D01*
Y353953D01*
G01Y354643D02*
X-788387Y355103D01*
X-788903Y355486D01*
X-789523Y355639D01*
X-790143Y355486D01*
X-790660Y355103D01*
X-790970Y354413D01*
X-790867Y353723D01*
X-790453Y353033D01*
G01X-778604Y460051D02*
X-784804D01*
Y461585D01*
X-784494Y462198D01*
X-784081Y462658D01*
X-783461Y463041D01*
X-782737Y463348D01*
X-781704Y463425D01*
X-780671Y463348D01*
X-779947Y463041D01*
X-779327Y462658D01*
X-778914Y462198D01*
X-778604Y461585D01*
Y460051D01*
G01X-779430Y466328D02*
X-778914Y466941D01*
X-778604Y467631D01*
Y468245D01*
X-778914Y468858D01*
X-779430Y469318D01*
X-780154Y469548D01*
X-780877Y469395D01*
X-781497Y469011D01*
X-781911Y468321D01*
X-782117Y467401D01*
X-782531Y466865D01*
X-783254Y466635D01*
X-783977Y466788D01*
X-784494Y467171D01*
X-784804Y467708D01*
Y468245D01*
X-784597Y468781D01*
X-784081Y469241D01*
G01X-778604Y474138D02*
X-784804D01*
X-783564Y473218D01*
G01X-778604D02*
Y475058D01*
G01X-783771Y478881D02*
X-784391Y479341D01*
X-784701Y479878D01*
X-784804Y480491D01*
X-784597Y481258D01*
X-784081Y481795D01*
X-783461Y481948D01*
X-782841Y481871D01*
X-782324Y481565D01*
X-781291Y480031D01*
X-780567Y479341D01*
X-779534Y478881D01*
X-778604Y478728D01*
Y481948D01*
G01X-790621Y474938D02*
X-788704Y481138D01*
X-786787Y474938D01*
G01X-787477Y477108D02*
X-789931D01*
G01X-778604Y488051D02*
X-784804D01*
Y489585D01*
X-784494Y490198D01*
X-784081Y490658D01*
X-783461Y491041D01*
X-782737Y491348D01*
X-781704Y491425D01*
X-780671Y491348D01*
X-779947Y491041D01*
X-779327Y490658D01*
X-778914Y490198D01*
X-778604Y489585D01*
Y488051D01*
G01X-779430Y494328D02*
X-778914Y494941D01*
X-778604Y495631D01*
Y496245D01*
X-778914Y496858D01*
X-779430Y497318D01*
X-780154Y497548D01*
X-780877Y497395D01*
X-781497Y497011D01*
X-781911Y496321D01*
X-782117Y495401D01*
X-782531Y494865D01*
X-783254Y494635D01*
X-783977Y494788D01*
X-784494Y495171D01*
X-784804Y495708D01*
Y496245D01*
X-784597Y496781D01*
X-784081Y497241D01*
G01X-778604Y502138D02*
X-784804D01*
X-783564Y501218D01*
G01X-778604D02*
Y503058D01*
G01Y508338D02*
X-784804D01*
X-783564Y507418D01*
G01X-778604D02*
Y509258D01*
G01X-771017Y491621D02*
X-771477Y491931D01*
X-772014Y492138D01*
X-772627D01*
X-773317Y491828D01*
X-773854Y491311D01*
X-774237Y490691D01*
X-774544Y489658D01*
X-774621Y488728D01*
X-774467Y487798D01*
X-774237Y487178D01*
X-773777Y486558D01*
X-773241Y486145D01*
X-772704Y485938D01*
X-772167D01*
X-771631Y486145D01*
X-771171Y486455D01*
X-770787Y486868D01*
G01X-782621Y512938D02*
X-780704Y519138D01*
X-778787Y512938D01*
G01X-779477Y515108D02*
X-781931D01*
G01X-760361Y-152342D02*
X-759901Y-152859D01*
X-759364Y-153169D01*
X-758674Y-153272D01*
X-757984Y-153065D01*
X-757447Y-152652D01*
X-757064Y-151929D01*
X-756987Y-151102D01*
X-757141Y-150275D01*
X-757524Y-149759D01*
X-758061Y-149345D01*
X-758597Y-149242D01*
X-759134Y-149345D01*
X-759824Y-149759D01*
X-759594Y-147072D01*
X-757524D01*
G01X-758674Y-137272D02*
X-758137Y-137169D01*
X-757524Y-136859D01*
X-757141Y-136342D01*
X-756987Y-135619D01*
X-757141Y-134895D01*
X-757601Y-134275D01*
X-758291Y-133965D01*
X-759057D01*
X-759517Y-133759D01*
X-759901Y-133242D01*
X-760054Y-132519D01*
X-759824Y-131795D01*
X-759287Y-131279D01*
X-758674Y-131072D01*
X-758061Y-131279D01*
X-757524Y-131795D01*
X-757294Y-132519D01*
X-757447Y-133242D01*
X-757831Y-133759D01*
X-758291Y-133965D01*
X-759057D01*
X-759747Y-134275D01*
X-760207Y-134895D01*
X-760361Y-135619D01*
X-760207Y-136342D01*
X-759824Y-136859D01*
X-759211Y-137169D01*
X-758674Y-137272D01*
G01X-763337Y-49822D02*
X-762954Y-50442D01*
X-762494Y-50855D01*
X-761957Y-51062D01*
X-761344Y-50855D01*
X-760884Y-50442D01*
X-760424Y-49822D01*
X-760271Y-48995D01*
Y-44862D01*
G01X-757291Y-50132D02*
X-756831Y-50649D01*
X-756294Y-50959D01*
X-755604Y-51062D01*
X-754914Y-50855D01*
X-754377Y-50442D01*
X-753994Y-49719D01*
X-753917Y-48892D01*
X-754071Y-48065D01*
X-754454Y-47549D01*
X-754991Y-47135D01*
X-755527Y-47032D01*
X-756064Y-47135D01*
X-756754Y-47549D01*
X-756524Y-44862D01*
X-754454D01*
G01X-768287Y45273D02*
X-768597Y44813D01*
X-768804Y44276D01*
Y43663D01*
X-768494Y42973D01*
X-767977Y42436D01*
X-767357Y42053D01*
X-766324Y41746D01*
X-765394Y41669D01*
X-764464Y41823D01*
X-763844Y42053D01*
X-763224Y42513D01*
X-762811Y43049D01*
X-762604Y43586D01*
Y44123D01*
X-762811Y44659D01*
X-763121Y45119D01*
X-763534Y45503D01*
G01X-765187Y48329D02*
X-765911Y48866D01*
X-766324Y49326D01*
X-766531Y49939D01*
X-766324Y50476D01*
X-765911Y50859D01*
X-765291Y51166D01*
X-764567Y51243D01*
X-763947Y51166D01*
X-763327Y50859D01*
X-762811Y50399D01*
X-762604Y49863D01*
X-762811Y49249D01*
X-763430Y48713D01*
X-764361Y48406D01*
X-765394Y48329D01*
X-766737Y48483D01*
X-767461Y48713D01*
X-768184Y49096D01*
X-768701Y49633D01*
X-768804Y50169D01*
X-768597Y50706D01*
X-768081Y51089D01*
G01X-762604Y55986D02*
X-768804D01*
X-767564Y55066D01*
G01X-762604D02*
Y56906D01*
G01X-763606Y78706D02*
Y84906D01*
X-766443Y80463D01*
X-762609D01*
G01X-759826Y95919D02*
X-755383D01*
X-754452Y96226D01*
X-753833Y96839D01*
X-753626Y97606D01*
X-753833Y98373D01*
X-754452Y98986D01*
X-755383Y99293D01*
X-759826D01*
G01X-754349Y102503D02*
X-753833Y103039D01*
X-753626Y103653D01*
X-753833Y104266D01*
X-754452Y104803D01*
X-755383Y105186D01*
X-756313Y105339D01*
X-757449D01*
X-758379Y105186D01*
X-759206Y104803D01*
X-759619Y104343D01*
X-759826Y103806D01*
X-759619Y103193D01*
X-759206Y102733D01*
X-758586Y102426D01*
X-757759Y102273D01*
X-757036Y102426D01*
X-756313Y102809D01*
X-755899Y103269D01*
X-755796Y103806D01*
X-756003Y104419D01*
X-756519Y104879D01*
X-757449Y105339D01*
G01X-767391Y119026D02*
X-766931Y118303D01*
X-766317Y117889D01*
X-765627Y117786D01*
X-765014Y117889D01*
X-764401Y118406D01*
X-764017Y119026D01*
X-763941Y119646D01*
X-764094Y120369D01*
X-764631Y120886D01*
X-765167Y121093D01*
X-765857D01*
G01X-765167D02*
X-764707Y121403D01*
X-764324Y121919D01*
X-764171Y122539D01*
X-764324Y123159D01*
X-764707Y123676D01*
X-765397Y123986D01*
X-766087Y123883D01*
X-766777Y123469D01*
G01X-770017Y458621D02*
X-770477Y458931D01*
X-771014Y459138D01*
X-771627D01*
X-772317Y458828D01*
X-772854Y458311D01*
X-773237Y457691D01*
X-773544Y456658D01*
X-773621Y455728D01*
X-773467Y454798D01*
X-773237Y454178D01*
X-772777Y453558D01*
X-772241Y453145D01*
X-771704Y452938D01*
X-771167D01*
X-770631Y453145D01*
X-770171Y453455D01*
X-769787Y453868D01*
G01X-741919Y-223354D02*
Y-217154D01*
X-739926Y-222321D01*
X-737933Y-217154D01*
Y-223354D01*
G01X-732193D02*
X-735259D01*
Y-217154D01*
X-732193D01*
G01X-733419Y-220151D02*
X-735259D01*
G01X-727526Y-223354D02*
Y-217154D01*
X-728446Y-218394D01*
G01Y-223354D02*
X-726606D01*
G01X-722783Y-218187D02*
X-722323Y-217567D01*
X-721786Y-217257D01*
X-721173Y-217154D01*
X-720406Y-217361D01*
X-719869Y-217877D01*
X-719716Y-218497D01*
X-719793Y-219117D01*
X-720099Y-219634D01*
X-721633Y-220667D01*
X-722323Y-221391D01*
X-722783Y-222424D01*
X-722936Y-223354D01*
X-719716D01*
G01X-741537Y-150062D02*
Y-143862D01*
X-739621D01*
X-739007Y-144172D01*
X-738624Y-144585D01*
X-738471Y-145412D01*
X-738624Y-146239D01*
X-739084Y-146755D01*
X-739621Y-147065D01*
X-741537D01*
G01X-739621D02*
X-738471Y-150062D01*
G01X-732884D02*
Y-143862D01*
X-735721Y-148305D01*
X-731887D01*
G01X-727604Y-150062D02*
Y-143862D01*
X-728524Y-145102D01*
G01Y-150062D02*
X-726684D01*
G01X-720484D02*
Y-143862D01*
X-723321Y-148305D01*
X-719487D01*
G01X-741537Y-158998D02*
Y-152798D01*
X-739621D01*
X-739007Y-153108D01*
X-738624Y-153521D01*
X-738471Y-154348D01*
X-738624Y-155175D01*
X-739084Y-155691D01*
X-739621Y-156001D01*
X-741537D01*
G01X-739621D02*
X-738471Y-158998D01*
G01X-732884D02*
Y-152798D01*
X-735721Y-157241D01*
X-731887D01*
G01X-727604Y-158998D02*
Y-152798D01*
X-728524Y-154038D01*
G01Y-158998D02*
X-726684D01*
G01X-721404Y-152798D02*
X-722017Y-153005D01*
X-722477Y-153521D01*
X-722784Y-154141D01*
X-723014Y-154968D01*
X-723091Y-155898D01*
X-723014Y-156828D01*
X-722784Y-157655D01*
X-722477Y-158275D01*
X-722017Y-158791D01*
X-721404Y-158998D01*
X-720791Y-158791D01*
X-720331Y-158275D01*
X-720024Y-157655D01*
X-719794Y-156828D01*
X-719717Y-155898D01*
X-719794Y-154968D01*
X-720024Y-154141D01*
X-720331Y-153521D01*
X-720791Y-153005D01*
X-721404Y-152798D01*
G01X-741537Y-138062D02*
Y-131862D01*
X-739621D01*
X-739007Y-132172D01*
X-738624Y-132585D01*
X-738471Y-133412D01*
X-738624Y-134239D01*
X-739084Y-134755D01*
X-739621Y-135065D01*
X-741537D01*
G01X-739621D02*
X-738471Y-138062D01*
G01X-732884D02*
Y-131862D01*
X-735721Y-136305D01*
X-731887D01*
G01X-727604Y-138062D02*
Y-131862D01*
X-728524Y-133102D01*
G01Y-138062D02*
X-726684D01*
G01X-722707Y-137339D02*
X-722171Y-137855D01*
X-721557Y-138062D01*
X-720944Y-137855D01*
X-720407Y-137236D01*
X-720024Y-136305D01*
X-719871Y-135375D01*
Y-134239D01*
X-720024Y-133309D01*
X-720407Y-132482D01*
X-720867Y-132069D01*
X-721404Y-131862D01*
X-722017Y-132069D01*
X-722477Y-132482D01*
X-722784Y-133102D01*
X-722937Y-133929D01*
X-722784Y-134652D01*
X-722401Y-135375D01*
X-721941Y-135789D01*
X-721404Y-135892D01*
X-720791Y-135685D01*
X-720331Y-135169D01*
X-719871Y-134239D01*
G01X-738317Y-121379D02*
X-738777Y-121069D01*
X-739314Y-120862D01*
X-739927D01*
X-740617Y-121172D01*
X-741154Y-121689D01*
X-741537Y-122309D01*
X-741844Y-123342D01*
X-741921Y-124272D01*
X-741767Y-125202D01*
X-741537Y-125822D01*
X-741077Y-126442D01*
X-740541Y-126855D01*
X-740004Y-127062D01*
X-739467D01*
X-738931Y-126855D01*
X-738471Y-126545D01*
X-738087Y-126132D01*
G01X-735491Y-125822D02*
X-735031Y-126545D01*
X-734417Y-126959D01*
X-733727Y-127062D01*
X-733114Y-126959D01*
X-732501Y-126442D01*
X-732117Y-125822D01*
X-732041Y-125202D01*
X-732194Y-124479D01*
X-732731Y-123962D01*
X-733267Y-123755D01*
X-733957D01*
G01X-733267D02*
X-732807Y-123445D01*
X-732424Y-122929D01*
X-732271Y-122309D01*
X-732424Y-121689D01*
X-732807Y-121172D01*
X-733497Y-120862D01*
X-734187Y-120965D01*
X-734877Y-121379D01*
G01X-727604Y-120862D02*
X-728217Y-121069D01*
X-728677Y-121585D01*
X-728984Y-122205D01*
X-729214Y-123032D01*
X-729291Y-123962D01*
X-729214Y-124892D01*
X-728984Y-125719D01*
X-728677Y-126339D01*
X-728217Y-126855D01*
X-727604Y-127062D01*
X-726991Y-126855D01*
X-726531Y-126339D01*
X-726224Y-125719D01*
X-725994Y-124892D01*
X-725917Y-123962D01*
X-725994Y-123032D01*
X-726224Y-122205D01*
X-726531Y-121585D01*
X-726991Y-121069D01*
X-727604Y-120862D01*
G01X-723091Y-126132D02*
X-722631Y-126649D01*
X-722094Y-126959D01*
X-721404Y-127062D01*
X-720714Y-126855D01*
X-720177Y-126442D01*
X-719794Y-125719D01*
X-719717Y-124892D01*
X-719871Y-124065D01*
X-720254Y-123549D01*
X-720791Y-123135D01*
X-721327Y-123032D01*
X-721864Y-123135D01*
X-722554Y-123549D01*
X-722324Y-120862D01*
X-720254D01*
G01X-755487Y42873D02*
X-755797Y42413D01*
X-756004Y41876D01*
Y41263D01*
X-755694Y40573D01*
X-755177Y40036D01*
X-754557Y39653D01*
X-753524Y39346D01*
X-752594Y39269D01*
X-751664Y39423D01*
X-751044Y39653D01*
X-750424Y40113D01*
X-750011Y40649D01*
X-749804Y41186D01*
Y41723D01*
X-750011Y42259D01*
X-750321Y42719D01*
X-750734Y43103D01*
G01X-752387Y45929D02*
X-753111Y46466D01*
X-753524Y46926D01*
X-753731Y47539D01*
X-753524Y48076D01*
X-753111Y48459D01*
X-752491Y48766D01*
X-751767Y48843D01*
X-751147Y48766D01*
X-750527Y48459D01*
X-750011Y47999D01*
X-749804Y47463D01*
X-750011Y46849D01*
X-750630Y46313D01*
X-751561Y46006D01*
X-752594Y45929D01*
X-753937Y46083D01*
X-754661Y46313D01*
X-755384Y46696D01*
X-755901Y47233D01*
X-756004Y47769D01*
X-755797Y48306D01*
X-755281Y48689D01*
G01X-751044Y51899D02*
X-750321Y52359D01*
X-749907Y52973D01*
X-749804Y53663D01*
X-749907Y54276D01*
X-750424Y54889D01*
X-751044Y55273D01*
X-751664Y55349D01*
X-752387Y55196D01*
X-752904Y54659D01*
X-753111Y54123D01*
Y53433D01*
G01Y54123D02*
X-753421Y54583D01*
X-753937Y54966D01*
X-754557Y55119D01*
X-755177Y54966D01*
X-755694Y54583D01*
X-756004Y53893D01*
X-755901Y53203D01*
X-755487Y52513D01*
G01X-736636Y43244D02*
Y44777D01*
X-734776D01*
X-734156Y44317D01*
X-733743Y43781D01*
X-733536Y43014D01*
X-733743Y42247D01*
X-734156Y41711D01*
X-734776Y41251D01*
X-735499Y40944D01*
X-736326Y40791D01*
X-737049D01*
X-737669Y40944D01*
X-738393Y41251D01*
X-739013Y41711D01*
X-739426Y42171D01*
X-739736Y42784D01*
Y43321D01*
X-739529Y43934D01*
X-739116Y44394D01*
G01X-733536Y47374D02*
X-739736D01*
G01Y50594D02*
X-733536D01*
G01X-736636D02*
Y47374D01*
G01X-733536Y55184D02*
X-739736D01*
X-738496Y54264D01*
G01X-733536D02*
Y56104D01*
G01X-735604Y60038D02*
X-741804D01*
X-740564Y59118D01*
G01X-735604D02*
Y60958D01*
G01X-750783Y81689D02*
X-750246Y82413D01*
X-749786Y82826D01*
X-749173Y83033D01*
X-748636Y82826D01*
X-748253Y82413D01*
X-747946Y81793D01*
X-747869Y81069D01*
X-747946Y80449D01*
X-748253Y79829D01*
X-748713Y79313D01*
X-749249Y79106D01*
X-749863Y79313D01*
X-750399Y79932D01*
X-750706Y80863D01*
X-750783Y81896D01*
X-750629Y83239D01*
X-750399Y83963D01*
X-750016Y84686D01*
X-749479Y85203D01*
X-748943Y85306D01*
X-748406Y85099D01*
X-748023Y84583D01*
G01X-736192Y80661D02*
X-735675Y81121D01*
X-735365Y81658D01*
X-735262Y82348D01*
X-735469Y83038D01*
X-735882Y83575D01*
X-736605Y83958D01*
X-737432Y84035D01*
X-738259Y83881D01*
X-738775Y83498D01*
X-739189Y82961D01*
X-739292Y82425D01*
X-739189Y81888D01*
X-738775Y81198D01*
X-741462Y81428D01*
Y83498D01*
G01X-746704Y166938D02*
Y173138D01*
X-747624Y171898D01*
G01Y166938D02*
X-745784D01*
G01X-748007Y250661D02*
X-747471Y250145D01*
X-746857Y249938D01*
X-746244Y250145D01*
X-745707Y250764D01*
X-745324Y251695D01*
X-745171Y252625D01*
Y253761D01*
X-745324Y254691D01*
X-745707Y255518D01*
X-746167Y255931D01*
X-746704Y256138D01*
X-747317Y255931D01*
X-747777Y255518D01*
X-748084Y254898D01*
X-748237Y254071D01*
X-748084Y253348D01*
X-747701Y252625D01*
X-747241Y252211D01*
X-746704Y252108D01*
X-746091Y252315D01*
X-745631Y252831D01*
X-745171Y253761D01*
G01X-741919Y481608D02*
Y487808D01*
X-739926Y482641D01*
X-737933Y487808D01*
Y481608D01*
G01X-732193D02*
X-735259D01*
Y487808D01*
X-732193D01*
G01X-733419Y484811D02*
X-735259D01*
G01X-727526Y481608D02*
Y487808D01*
X-728446Y486568D01*
G01Y481608D02*
X-726606D01*
G01X-721326D02*
Y487808D01*
X-722246Y486568D01*
G01Y481608D02*
X-720406D01*
G01X-735704Y90298D02*
Y91831D01*
X-733844D01*
X-733224Y91371D01*
X-732811Y90835D01*
X-732604Y90068D01*
X-732811Y89301D01*
X-733224Y88765D01*
X-733844Y88305D01*
X-734567Y87998D01*
X-735394Y87845D01*
X-736117D01*
X-736737Y87998D01*
X-737461Y88305D01*
X-738081Y88765D01*
X-738494Y89225D01*
X-738804Y89838D01*
Y90375D01*
X-738597Y90988D01*
X-738184Y91448D01*
G01X-732604Y94428D02*
X-738804D01*
G01Y97648D02*
X-732604D01*
G01X-735704D02*
Y94428D01*
G01X-737771Y100781D02*
X-738391Y101241D01*
X-738701Y101778D01*
X-738804Y102391D01*
X-738597Y103158D01*
X-738081Y103695D01*
X-737461Y103848D01*
X-736841Y103771D01*
X-736324Y103465D01*
X-735291Y101931D01*
X-734567Y101241D01*
X-733534Y100781D01*
X-732604Y100628D01*
Y103848D01*
G01X-702804Y24046D02*
Y25579D01*
X-700944D01*
X-700324Y25119D01*
X-699911Y24583D01*
X-699704Y23816D01*
X-699911Y23049D01*
X-700324Y22513D01*
X-700944Y22053D01*
X-701667Y21746D01*
X-702494Y21593D01*
X-703217D01*
X-703837Y21746D01*
X-704561Y22053D01*
X-705181Y22513D01*
X-705594Y22973D01*
X-705904Y23586D01*
Y24123D01*
X-705697Y24736D01*
X-705284Y25196D01*
G01X-699704Y28176D02*
X-705904D01*
G01Y31396D02*
X-699704D01*
G01X-702804D02*
Y28176D01*
G01X-700944Y34299D02*
X-700221Y34759D01*
X-699807Y35373D01*
X-699704Y36063D01*
X-699807Y36676D01*
X-700324Y37289D01*
X-700944Y37673D01*
X-701564Y37749D01*
X-702287Y37596D01*
X-702804Y37059D01*
X-703011Y36523D01*
Y35833D01*
G01Y36523D02*
X-703321Y36983D01*
X-703837Y37366D01*
X-704457Y37519D01*
X-705077Y37366D01*
X-705594Y36983D01*
X-705904Y36293D01*
X-705801Y35603D01*
X-705387Y34913D01*
G01X-716310Y63353D02*
X-715690Y63736D01*
X-715277Y64196D01*
X-715070Y64733D01*
X-715277Y65346D01*
X-715690Y65806D01*
X-716310Y66266D01*
X-717137Y66419D01*
X-721270D01*
G01X-715070Y71086D02*
X-721270D01*
X-720030Y70166D01*
G01X-715070D02*
Y72006D01*
G01Y77286D02*
X-721270D01*
X-720030Y76366D01*
G01X-715070D02*
Y78206D01*
G01X-703804Y107046D02*
Y108579D01*
X-701944D01*
X-701324Y108119D01*
X-700911Y107583D01*
X-700704Y106816D01*
X-700911Y106049D01*
X-701324Y105513D01*
X-701944Y105053D01*
X-702667Y104746D01*
X-703494Y104593D01*
X-704217D01*
X-704837Y104746D01*
X-705561Y105053D01*
X-706181Y105513D01*
X-706594Y105973D01*
X-706904Y106586D01*
Y107123D01*
X-706697Y107736D01*
X-706284Y108196D01*
G01X-700704Y111176D02*
X-706904D01*
G01Y114396D02*
X-700704D01*
G01X-703804D02*
Y111176D01*
G01X-700704Y119906D02*
X-706904D01*
X-702461Y117069D01*
Y120903D01*
G01X-696072Y61456D02*
Y62989D01*
X-694212D01*
X-693592Y62529D01*
X-693179Y61993D01*
X-692972Y61226D01*
X-693179Y60459D01*
X-693592Y59923D01*
X-694212Y59463D01*
X-694935Y59156D01*
X-695762Y59003D01*
X-696485D01*
X-697105Y59156D01*
X-697829Y59463D01*
X-698449Y59923D01*
X-698862Y60383D01*
X-699172Y60996D01*
Y61533D01*
X-698965Y62146D01*
X-698552Y62606D01*
G01X-692972Y67196D02*
X-699172D01*
X-697932Y66276D01*
G01X-692972D02*
Y68116D01*
G01X-696218Y77496D02*
Y79029D01*
X-694358D01*
X-693738Y78569D01*
X-693325Y78033D01*
X-693118Y77266D01*
X-693325Y76499D01*
X-693738Y75963D01*
X-694358Y75503D01*
X-695081Y75196D01*
X-695908Y75043D01*
X-696631D01*
X-697251Y75196D01*
X-697975Y75503D01*
X-698595Y75963D01*
X-699008Y76423D01*
X-699318Y77036D01*
Y77573D01*
X-699111Y78186D01*
X-698698Y78646D01*
G01X-698285Y81779D02*
X-698905Y82239D01*
X-699215Y82776D01*
X-699318Y83389D01*
X-699111Y84156D01*
X-698595Y84693D01*
X-697975Y84846D01*
X-697355Y84769D01*
X-696838Y84463D01*
X-695805Y82929D01*
X-695081Y82239D01*
X-694048Y81779D01*
X-693118Y81626D01*
Y84846D01*
G01X59745Y-183562D02*
Y-177362D01*
X61661D01*
X62275Y-177672D01*
X62658Y-178085D01*
X62811Y-178912D01*
X62658Y-179739D01*
X62198Y-180255D01*
X61661Y-180565D01*
X59745D01*
G01X61661D02*
X62811Y-183562D01*
G01X68398D02*
Y-177362D01*
X65561Y-181805D01*
X69395D01*
G01X73678Y-183562D02*
Y-177362D01*
X72758Y-178602D01*
G01Y-183562D02*
X74598D01*
G01X79878D02*
Y-177362D01*
X78958Y-178602D01*
G01Y-183562D02*
X80798D01*
G01X59745Y-170498D02*
Y-164298D01*
X61661D01*
X62275Y-164608D01*
X62658Y-165021D01*
X62811Y-165848D01*
X62658Y-166675D01*
X62198Y-167191D01*
X61661Y-167501D01*
X59745D01*
G01X61661D02*
X62811Y-170498D01*
G01X68398D02*
Y-164298D01*
X65561Y-168741D01*
X69395D01*
G01X73678Y-170498D02*
Y-164298D01*
X72758Y-165538D01*
G01Y-170498D02*
X74598D01*
G01X78191Y-169568D02*
X78651Y-170085D01*
X79188Y-170395D01*
X79878Y-170498D01*
X80568Y-170291D01*
X81105Y-169878D01*
X81488Y-169155D01*
X81565Y-168328D01*
X81411Y-167501D01*
X81028Y-166985D01*
X80491Y-166571D01*
X79955Y-166468D01*
X79418Y-166571D01*
X78728Y-166985D01*
X78958Y-164298D01*
X81028D01*
G01X59745Y-158498D02*
Y-152298D01*
X61661D01*
X62275Y-152608D01*
X62658Y-153021D01*
X62811Y-153848D01*
X62658Y-154675D01*
X62198Y-155191D01*
X61661Y-155501D01*
X59745D01*
G01X61661D02*
X62811Y-158498D01*
G01X68398D02*
Y-152298D01*
X65561Y-156741D01*
X69395D01*
G01X73678Y-158498D02*
Y-152298D01*
X72758Y-153538D01*
G01Y-158498D02*
X74598D01*
G01X79725D02*
X79878Y-157155D01*
X80108Y-156018D01*
X80415Y-154985D01*
X80798Y-153848D01*
X81411Y-152298D01*
X78345D01*
G01X102678Y13453D02*
X96478D01*
Y15369D01*
X96788Y15983D01*
X97201Y16366D01*
X98028Y16519D01*
X98855Y16366D01*
X99371Y15906D01*
X99681Y15369D01*
Y13453D01*
G01Y15369D02*
X102678Y16519D01*
G01Y21186D02*
X96478D01*
X97718Y20266D01*
G01X102678D02*
Y22106D01*
G01X96478Y27386D02*
X96685Y26773D01*
X97201Y26313D01*
X97821Y26006D01*
X98648Y25776D01*
X99578Y25699D01*
X100508Y25776D01*
X101335Y26006D01*
X101955Y26313D01*
X102471Y26773D01*
X102678Y27386D01*
X102471Y27999D01*
X101955Y28459D01*
X101335Y28766D01*
X100508Y28996D01*
X99578Y29073D01*
X98648Y28996D01*
X97821Y28766D01*
X97201Y28459D01*
X96685Y27999D01*
X96478Y27386D01*
G01X97511Y32129D02*
X96891Y32589D01*
X96581Y33126D01*
X96478Y33739D01*
X96685Y34506D01*
X97201Y35043D01*
X97821Y35196D01*
X98441Y35119D01*
X98958Y34813D01*
X99991Y33279D01*
X100715Y32589D01*
X101748Y32129D01*
X102678Y31976D01*
Y35196D01*
G01X93678Y13453D02*
X87478D01*
Y15369D01*
X87788Y15983D01*
X88201Y16366D01*
X89028Y16519D01*
X89855Y16366D01*
X90371Y15906D01*
X90681Y15369D01*
Y13453D01*
G01Y15369D02*
X93678Y16519D01*
G01Y21186D02*
X87478D01*
X88718Y20266D01*
G01X93678D02*
Y22106D01*
G01X87478Y27386D02*
X87685Y26773D01*
X88201Y26313D01*
X88821Y26006D01*
X89648Y25776D01*
X90578Y25699D01*
X91508Y25776D01*
X92335Y26006D01*
X92955Y26313D01*
X93471Y26773D01*
X93678Y27386D01*
X93471Y27999D01*
X92955Y28459D01*
X92335Y28766D01*
X91508Y28996D01*
X90578Y29073D01*
X89648Y28996D01*
X88821Y28766D01*
X88201Y28459D01*
X87685Y27999D01*
X87478Y27386D01*
G01X93678Y33586D02*
X87478D01*
X88718Y32666D01*
G01X93678D02*
Y34506D01*
G01X118678Y-100295D02*
X112478D01*
Y-98379D01*
X112788Y-97765D01*
X113201Y-97382D01*
X114028Y-97229D01*
X114855Y-97382D01*
X115371Y-97842D01*
X115681Y-98379D01*
Y-100295D01*
G01Y-98379D02*
X118678Y-97229D01*
G01X117438Y-94249D02*
X118161Y-93789D01*
X118575Y-93175D01*
X118678Y-92485D01*
X118575Y-91872D01*
X118058Y-91259D01*
X117438Y-90875D01*
X116818Y-90799D01*
X116095Y-90952D01*
X115578Y-91489D01*
X115371Y-92025D01*
Y-92715D01*
G01Y-92025D02*
X115061Y-91565D01*
X114545Y-91182D01*
X113925Y-91029D01*
X113305Y-91182D01*
X112788Y-91565D01*
X112478Y-92255D01*
X112581Y-92945D01*
X112995Y-93635D01*
G01X113511Y-87819D02*
X112891Y-87359D01*
X112581Y-86822D01*
X112478Y-86209D01*
X112685Y-85442D01*
X113201Y-84905D01*
X113821Y-84752D01*
X114441Y-84829D01*
X114958Y-85135D01*
X115991Y-86669D01*
X116715Y-87359D01*
X117748Y-87819D01*
X118678Y-87972D01*
Y-84752D01*
G01X117955Y-81465D02*
X118471Y-80929D01*
X118678Y-80315D01*
X118471Y-79702D01*
X117852Y-79165D01*
X116921Y-78782D01*
X115991Y-78629D01*
X114855D01*
X113925Y-78782D01*
X113098Y-79165D01*
X112685Y-79625D01*
X112478Y-80162D01*
X112685Y-80775D01*
X113098Y-81235D01*
X113718Y-81542D01*
X114545Y-81695D01*
X115268Y-81542D01*
X115991Y-81159D01*
X116405Y-80699D01*
X116508Y-80162D01*
X116301Y-79549D01*
X115785Y-79089D01*
X114855Y-78629D01*
G01X118678Y-77295D02*
X112478D01*
Y-75379D01*
X112788Y-74765D01*
X113201Y-74382D01*
X114028Y-74229D01*
X114855Y-74382D01*
X115371Y-74842D01*
X115681Y-75379D01*
Y-77295D01*
G01Y-75379D02*
X118678Y-74229D01*
G01Y-68642D02*
X112478D01*
X116921Y-71479D01*
Y-67645D01*
G01X113511Y-64819D02*
X112891Y-64359D01*
X112581Y-63822D01*
X112478Y-63209D01*
X112685Y-62442D01*
X113201Y-61905D01*
X113821Y-61752D01*
X114441Y-61829D01*
X114958Y-62135D01*
X115991Y-63669D01*
X116715Y-64359D01*
X117748Y-64819D01*
X118678Y-64972D01*
Y-61752D01*
G01Y-57162D02*
X118575Y-56625D01*
X118265Y-56012D01*
X117748Y-55629D01*
X117025Y-55475D01*
X116301Y-55629D01*
X115681Y-56089D01*
X115371Y-56779D01*
Y-57545D01*
X115165Y-58005D01*
X114648Y-58389D01*
X113925Y-58542D01*
X113201Y-58312D01*
X112685Y-57775D01*
X112478Y-57162D01*
X112685Y-56549D01*
X113201Y-56012D01*
X113925Y-55782D01*
X114648Y-55935D01*
X115165Y-56319D01*
X115371Y-56779D01*
Y-57545D01*
X115681Y-58235D01*
X116301Y-58695D01*
X117025Y-58849D01*
X117748Y-58695D01*
X118265Y-58312D01*
X118575Y-57699D01*
X118678Y-57162D01*
G01X119678Y-52295D02*
X113478D01*
Y-50379D01*
X113788Y-49765D01*
X114201Y-49382D01*
X115028Y-49229D01*
X115855Y-49382D01*
X116371Y-49842D01*
X116681Y-50379D01*
Y-52295D01*
G01Y-50379D02*
X119678Y-49229D01*
G01Y-43642D02*
X113478D01*
X117921Y-46479D01*
Y-42645D01*
G01X114511Y-39819D02*
X113891Y-39359D01*
X113581Y-38822D01*
X113478Y-38209D01*
X113685Y-37442D01*
X114201Y-36905D01*
X114821Y-36752D01*
X115441Y-36829D01*
X115958Y-37135D01*
X116991Y-38669D01*
X117715Y-39359D01*
X118748Y-39819D01*
X119678Y-39972D01*
Y-36752D01*
G01X118955Y-33465D02*
X119471Y-32929D01*
X119678Y-32315D01*
X119471Y-31702D01*
X118852Y-31165D01*
X117921Y-30782D01*
X116991Y-30629D01*
X115855D01*
X114925Y-30782D01*
X114098Y-31165D01*
X113685Y-31625D01*
X113478Y-32162D01*
X113685Y-32775D01*
X114098Y-33235D01*
X114718Y-33542D01*
X115545Y-33695D01*
X116268Y-33542D01*
X116991Y-33159D01*
X117405Y-32699D01*
X117508Y-32162D01*
X117301Y-31549D01*
X116785Y-31089D01*
X115855Y-30629D01*
G01X111678Y13453D02*
X105478D01*
Y15369D01*
X105788Y15983D01*
X106201Y16366D01*
X107028Y16519D01*
X107855Y16366D01*
X108371Y15906D01*
X108681Y15369D01*
Y13453D01*
G01Y15369D02*
X111678Y16519D01*
G01Y21186D02*
X105478D01*
X106718Y20266D01*
G01X111678D02*
Y22106D01*
G01X105478Y27386D02*
X105685Y26773D01*
X106201Y26313D01*
X106821Y26006D01*
X107648Y25776D01*
X108578Y25699D01*
X109508Y25776D01*
X110335Y26006D01*
X110955Y26313D01*
X111471Y26773D01*
X111678Y27386D01*
X111471Y27999D01*
X110955Y28459D01*
X110335Y28766D01*
X109508Y28996D01*
X108578Y29073D01*
X107648Y28996D01*
X106821Y28766D01*
X106201Y28459D01*
X105685Y27999D01*
X105478Y27386D01*
G01X110438Y31899D02*
X111161Y32359D01*
X111575Y32973D01*
X111678Y33663D01*
X111575Y34276D01*
X111058Y34889D01*
X110438Y35273D01*
X109818Y35349D01*
X109095Y35196D01*
X108578Y34659D01*
X108371Y34123D01*
Y33433D01*
G01Y34123D02*
X108061Y34583D01*
X107545Y34966D01*
X106925Y35119D01*
X106305Y34966D01*
X105788Y34583D01*
X105478Y33893D01*
X105581Y33203D01*
X105995Y32513D01*
G01X121678Y-27295D02*
X115478D01*
Y-25379D01*
X115788Y-24765D01*
X116201Y-24382D01*
X117028Y-24229D01*
X117855Y-24382D01*
X118371Y-24842D01*
X118681Y-25379D01*
Y-27295D01*
G01Y-25379D02*
X121678Y-24229D01*
G01Y-18642D02*
X115478D01*
X119921Y-21479D01*
Y-17645D01*
G01X120438Y-15049D02*
X121161Y-14589D01*
X121575Y-13975D01*
X121678Y-13285D01*
X121575Y-12672D01*
X121058Y-12059D01*
X120438Y-11675D01*
X119818Y-11599D01*
X119095Y-11752D01*
X118578Y-12289D01*
X118371Y-12825D01*
Y-13515D01*
G01Y-12825D02*
X118061Y-12365D01*
X117545Y-11982D01*
X116925Y-11829D01*
X116305Y-11982D01*
X115788Y-12365D01*
X115478Y-13055D01*
X115581Y-13745D01*
X115995Y-14435D01*
G01X115478Y-7162D02*
X115685Y-7775D01*
X116201Y-8235D01*
X116821Y-8542D01*
X117648Y-8772D01*
X118578Y-8849D01*
X119508Y-8772D01*
X120335Y-8542D01*
X120955Y-8235D01*
X121471Y-7775D01*
X121678Y-7162D01*
X121471Y-6549D01*
X120955Y-6089D01*
X120335Y-5782D01*
X119508Y-5552D01*
X118578Y-5475D01*
X117648Y-5552D01*
X116821Y-5782D01*
X116201Y-6089D01*
X115685Y-6549D01*
X115478Y-7162D01*
G01X124678Y438705D02*
X118478D01*
Y440621D01*
X118788Y441235D01*
X119201Y441618D01*
X120028Y441771D01*
X120855Y441618D01*
X121371Y441158D01*
X121681Y440621D01*
Y438705D01*
G01Y440621D02*
X124678Y441771D01*
G01Y446438D02*
X118478D01*
X119718Y445518D01*
G01X124678D02*
Y447358D01*
G01X122095Y451181D02*
X121371Y451718D01*
X120958Y452178D01*
X120751Y452791D01*
X120958Y453328D01*
X121371Y453711D01*
X121991Y454018D01*
X122715Y454095D01*
X123335Y454018D01*
X123955Y453711D01*
X124471Y453251D01*
X124678Y452715D01*
X124471Y452101D01*
X123852Y451565D01*
X122921Y451258D01*
X121888Y451181D01*
X120545Y451335D01*
X119821Y451565D01*
X119098Y451948D01*
X118581Y452485D01*
X118478Y453021D01*
X118685Y453558D01*
X119201Y453941D01*
G01X123955Y457535D02*
X124471Y458071D01*
X124678Y458685D01*
X124471Y459298D01*
X123852Y459835D01*
X122921Y460218D01*
X121991Y460371D01*
X120855D01*
X119925Y460218D01*
X119098Y459835D01*
X118685Y459375D01*
X118478Y458838D01*
X118685Y458225D01*
X119098Y457765D01*
X119718Y457458D01*
X120545Y457305D01*
X121268Y457458D01*
X121991Y457841D01*
X122405Y458301D01*
X122508Y458838D01*
X122301Y459451D01*
X121785Y459911D01*
X120855Y460371D01*
G01X125678Y463705D02*
X119478D01*
Y465621D01*
X119788Y466235D01*
X120201Y466618D01*
X121028Y466771D01*
X121855Y466618D01*
X122371Y466158D01*
X122681Y465621D01*
Y463705D01*
G01Y465621D02*
X125678Y466771D01*
G01X120511Y469981D02*
X119891Y470441D01*
X119581Y470978D01*
X119478Y471591D01*
X119685Y472358D01*
X120201Y472895D01*
X120821Y473048D01*
X121441Y472971D01*
X121958Y472665D01*
X122991Y471131D01*
X123715Y470441D01*
X124748Y469981D01*
X125678Y469828D01*
Y473048D01*
G01Y477638D02*
X125575Y478175D01*
X125265Y478788D01*
X124748Y479171D01*
X124025Y479325D01*
X123301Y479171D01*
X122681Y478711D01*
X122371Y478021D01*
Y477255D01*
X122165Y476795D01*
X121648Y476411D01*
X120925Y476258D01*
X120201Y476488D01*
X119685Y477025D01*
X119478Y477638D01*
X119685Y478251D01*
X120201Y478788D01*
X120925Y479018D01*
X121648Y478865D01*
X122165Y478481D01*
X122371Y478021D01*
Y477255D01*
X122681Y476565D01*
X123301Y476105D01*
X124025Y475951D01*
X124748Y476105D01*
X125265Y476488D01*
X125575Y477101D01*
X125678Y477638D01*
G01X119478Y483838D02*
X119685Y483225D01*
X120201Y482765D01*
X120821Y482458D01*
X121648Y482228D01*
X122578Y482151D01*
X123508Y482228D01*
X124335Y482458D01*
X124955Y482765D01*
X125471Y483225D01*
X125678Y483838D01*
X125471Y484451D01*
X124955Y484911D01*
X124335Y485218D01*
X123508Y485448D01*
X122578Y485525D01*
X121648Y485448D01*
X120821Y485218D01*
X120201Y484911D01*
X119685Y484451D01*
X119478Y483838D01*
G01X149874Y1635D02*
X143674D01*
Y3551D01*
X143984Y4165D01*
X144397Y4548D01*
X145224Y4701D01*
X146051Y4548D01*
X146567Y4088D01*
X146877Y3551D01*
Y1635D01*
G01Y3551D02*
X149874Y4701D01*
G01X148634Y7681D02*
X149357Y8141D01*
X149771Y8755D01*
X149874Y9445D01*
X149771Y10058D01*
X149254Y10671D01*
X148634Y11055D01*
X148014Y11131D01*
X147291Y10978D01*
X146774Y10441D01*
X146567Y9905D01*
Y9215D01*
G01Y9905D02*
X146257Y10365D01*
X145741Y10748D01*
X145121Y10901D01*
X144501Y10748D01*
X143984Y10365D01*
X143674Y9675D01*
X143777Y8985D01*
X144191Y8295D01*
G01X143674Y15568D02*
X143881Y14955D01*
X144397Y14495D01*
X145017Y14188D01*
X145844Y13958D01*
X146774Y13881D01*
X147704Y13958D01*
X148531Y14188D01*
X149151Y14495D01*
X149667Y14955D01*
X149874Y15568D01*
X149667Y16181D01*
X149151Y16641D01*
X148531Y16948D01*
X147704Y17178D01*
X146774Y17255D01*
X145844Y17178D01*
X145017Y16948D01*
X144397Y16641D01*
X143881Y16181D01*
X143674Y15568D01*
G01Y21768D02*
X143881Y21155D01*
X144397Y20695D01*
X145017Y20388D01*
X145844Y20158D01*
X146774Y20081D01*
X147704Y20158D01*
X148531Y20388D01*
X149151Y20695D01*
X149667Y21155D01*
X149874Y21768D01*
X149667Y22381D01*
X149151Y22841D01*
X148531Y23148D01*
X147704Y23378D01*
X146774Y23455D01*
X145844Y23378D01*
X145017Y23148D01*
X144397Y22841D01*
X143881Y22381D01*
X143674Y21768D01*
G01X139874Y4735D02*
X133674D01*
Y6651D01*
X133984Y7265D01*
X134397Y7648D01*
X135224Y7801D01*
X136051Y7648D01*
X136567Y7188D01*
X136877Y6651D01*
Y4735D01*
G01Y6651D02*
X139874Y7801D01*
G01X137291Y11011D02*
X136567Y11548D01*
X136154Y12008D01*
X135947Y12621D01*
X136154Y13158D01*
X136567Y13541D01*
X137187Y13848D01*
X137911Y13925D01*
X138531Y13848D01*
X139151Y13541D01*
X139667Y13081D01*
X139874Y12545D01*
X139667Y11931D01*
X139048Y11395D01*
X138117Y11088D01*
X137084Y11011D01*
X135741Y11165D01*
X135017Y11395D01*
X134294Y11778D01*
X133777Y12315D01*
X133674Y12851D01*
X133881Y13388D01*
X134397Y13771D01*
G01X138944Y16981D02*
X139461Y17441D01*
X139771Y17978D01*
X139874Y18668D01*
X139667Y19358D01*
X139254Y19895D01*
X138531Y20278D01*
X137704Y20355D01*
X136877Y20201D01*
X136361Y19818D01*
X135947Y19281D01*
X135844Y18745D01*
X135947Y18208D01*
X136361Y17518D01*
X133674Y17748D01*
Y19818D01*
G01X139845Y148502D02*
Y154702D01*
X141761D01*
X142375Y154392D01*
X142758Y153979D01*
X142911Y153152D01*
X142758Y152325D01*
X142298Y151809D01*
X141761Y151499D01*
X139845D01*
G01X141761D02*
X142911Y148502D01*
G01X147578D02*
X148115Y148605D01*
X148728Y148915D01*
X149111Y149432D01*
X149265Y150155D01*
X149111Y150879D01*
X148651Y151499D01*
X147961Y151809D01*
X147195D01*
X146735Y152015D01*
X146351Y152532D01*
X146198Y153255D01*
X146428Y153979D01*
X146965Y154495D01*
X147578Y154702D01*
X148191Y154495D01*
X148728Y153979D01*
X148958Y153255D01*
X148805Y152532D01*
X148421Y152015D01*
X147961Y151809D01*
X147195D01*
X146505Y151499D01*
X146045Y150879D01*
X145891Y150155D01*
X146045Y149432D01*
X146428Y148915D01*
X147041Y148605D01*
X147578Y148502D01*
G01X153778D02*
Y154702D01*
X152858Y153462D01*
G01Y148502D02*
X154698D01*
G01X139845Y183502D02*
Y189702D01*
X141761D01*
X142375Y189392D01*
X142758Y188979D01*
X142911Y188152D01*
X142758Y187325D01*
X142298Y186809D01*
X141761Y186499D01*
X139845D01*
G01X141761D02*
X142911Y183502D01*
G01X147578D02*
X148115Y183605D01*
X148728Y183915D01*
X149111Y184432D01*
X149265Y185155D01*
X149111Y185879D01*
X148651Y186499D01*
X147961Y186809D01*
X147195D01*
X146735Y187015D01*
X146351Y187532D01*
X146198Y188255D01*
X146428Y188979D01*
X146965Y189495D01*
X147578Y189702D01*
X148191Y189495D01*
X148728Y188979D01*
X148958Y188255D01*
X148805Y187532D01*
X148421Y187015D01*
X147961Y186809D01*
X147195D01*
X146505Y186499D01*
X146045Y185879D01*
X145891Y185155D01*
X146045Y184432D01*
X146428Y183915D01*
X147041Y183605D01*
X147578Y183502D01*
G01X152321Y188669D02*
X152781Y189289D01*
X153318Y189599D01*
X153931Y189702D01*
X154698Y189495D01*
X155235Y188979D01*
X155388Y188359D01*
X155311Y187739D01*
X155005Y187222D01*
X153471Y186189D01*
X152781Y185465D01*
X152321Y184432D01*
X152168Y183502D01*
X155388D01*
G01X148678Y437705D02*
X142478D01*
Y439621D01*
X142788Y440235D01*
X143201Y440618D01*
X144028Y440771D01*
X144855Y440618D01*
X145371Y440158D01*
X145681Y439621D01*
Y437705D01*
G01Y439621D02*
X148678Y440771D01*
G01Y445438D02*
X142478D01*
X143718Y444518D01*
G01X148678D02*
Y446358D01*
G01Y451638D02*
X142478D01*
X143718Y450718D01*
G01X148678D02*
Y452558D01*
G01X147955Y456535D02*
X148471Y457071D01*
X148678Y457685D01*
X148471Y458298D01*
X147852Y458835D01*
X146921Y459218D01*
X145991Y459371D01*
X144855D01*
X143925Y459218D01*
X143098Y458835D01*
X142685Y458375D01*
X142478Y457838D01*
X142685Y457225D01*
X143098Y456765D01*
X143718Y456458D01*
X144545Y456305D01*
X145268Y456458D01*
X145991Y456841D01*
X146405Y457301D01*
X146508Y457838D01*
X146301Y458451D01*
X145785Y458911D01*
X144855Y459371D01*
G01X148278Y463705D02*
X142078D01*
Y465621D01*
X142388Y466235D01*
X142801Y466618D01*
X143628Y466771D01*
X144455Y466618D01*
X144971Y466158D01*
X145281Y465621D01*
Y463705D01*
G01Y465621D02*
X148278Y466771D01*
G01X143111Y469981D02*
X142491Y470441D01*
X142181Y470978D01*
X142078Y471591D01*
X142285Y472358D01*
X142801Y472895D01*
X143421Y473048D01*
X144041Y472971D01*
X144558Y472665D01*
X145591Y471131D01*
X146315Y470441D01*
X147348Y469981D01*
X148278Y469828D01*
Y473048D01*
G01Y477485D02*
X146935Y477638D01*
X145798Y477868D01*
X144765Y478175D01*
X143628Y478558D01*
X142078Y479171D01*
Y476105D01*
G01X147555Y482535D02*
X148071Y483071D01*
X148278Y483685D01*
X148071Y484298D01*
X147452Y484835D01*
X146521Y485218D01*
X145591Y485371D01*
X144455D01*
X143525Y485218D01*
X142698Y484835D01*
X142285Y484375D01*
X142078Y483838D01*
X142285Y483225D01*
X142698Y482765D01*
X143318Y482458D01*
X144145Y482305D01*
X144868Y482458D01*
X145591Y482841D01*
X146005Y483301D01*
X146108Y483838D01*
X145901Y484451D01*
X145385Y484911D01*
X144455Y485371D01*
G01X157678Y-100295D02*
X151478D01*
Y-98379D01*
X151788Y-97765D01*
X152201Y-97382D01*
X153028Y-97229D01*
X153855Y-97382D01*
X154371Y-97842D01*
X154681Y-98379D01*
Y-100295D01*
G01Y-98379D02*
X157678Y-97229D01*
G01Y-91642D02*
X151478D01*
X155921Y-94479D01*
Y-90645D01*
G01X156438Y-88049D02*
X157161Y-87589D01*
X157575Y-86975D01*
X157678Y-86285D01*
X157575Y-85672D01*
X157058Y-85059D01*
X156438Y-84675D01*
X155818Y-84599D01*
X155095Y-84752D01*
X154578Y-85289D01*
X154371Y-85825D01*
Y-86515D01*
G01Y-85825D02*
X154061Y-85365D01*
X153545Y-84982D01*
X152925Y-84829D01*
X152305Y-84982D01*
X151788Y-85365D01*
X151478Y-86055D01*
X151581Y-86745D01*
X151995Y-87435D01*
G01X157678Y-80162D02*
X151478D01*
X152718Y-81082D01*
G01X157678D02*
Y-79242D01*
G01Y-75295D02*
X151478D01*
Y-73379D01*
X151788Y-72765D01*
X152201Y-72382D01*
X153028Y-72229D01*
X153855Y-72382D01*
X154371Y-72842D01*
X154681Y-73379D01*
Y-75295D01*
G01Y-73379D02*
X157678Y-72229D01*
G01Y-66642D02*
X151478D01*
X155921Y-69479D01*
Y-65645D01*
G01X156438Y-63049D02*
X157161Y-62589D01*
X157575Y-61975D01*
X157678Y-61285D01*
X157575Y-60672D01*
X157058Y-60059D01*
X156438Y-59675D01*
X155818Y-59599D01*
X155095Y-59752D01*
X154578Y-60289D01*
X154371Y-60825D01*
Y-61515D01*
G01Y-60825D02*
X154061Y-60365D01*
X153545Y-59982D01*
X152925Y-59829D01*
X152305Y-59982D01*
X151788Y-60365D01*
X151478Y-61055D01*
X151581Y-61745D01*
X151995Y-62435D01*
G01X152511Y-56619D02*
X151891Y-56159D01*
X151581Y-55622D01*
X151478Y-55009D01*
X151685Y-54242D01*
X152201Y-53705D01*
X152821Y-53552D01*
X153441Y-53629D01*
X153958Y-53935D01*
X154991Y-55469D01*
X155715Y-56159D01*
X156748Y-56619D01*
X157678Y-56772D01*
Y-53552D01*
G01Y-50295D02*
X151478D01*
Y-48379D01*
X151788Y-47765D01*
X152201Y-47382D01*
X153028Y-47229D01*
X153855Y-47382D01*
X154371Y-47842D01*
X154681Y-48379D01*
Y-50295D01*
G01Y-48379D02*
X157678Y-47229D01*
G01Y-41642D02*
X151478D01*
X155921Y-44479D01*
Y-40645D01*
G01X156438Y-38049D02*
X157161Y-37589D01*
X157575Y-36975D01*
X157678Y-36285D01*
X157575Y-35672D01*
X157058Y-35059D01*
X156438Y-34675D01*
X155818Y-34599D01*
X155095Y-34752D01*
X154578Y-35289D01*
X154371Y-35825D01*
Y-36515D01*
G01Y-35825D02*
X154061Y-35365D01*
X153545Y-34982D01*
X152925Y-34829D01*
X152305Y-34982D01*
X151788Y-35365D01*
X151478Y-36055D01*
X151581Y-36745D01*
X151995Y-37435D01*
G01X156438Y-31849D02*
X157161Y-31389D01*
X157575Y-30775D01*
X157678Y-30085D01*
X157575Y-29472D01*
X157058Y-28859D01*
X156438Y-28475D01*
X155818Y-28399D01*
X155095Y-28552D01*
X154578Y-29089D01*
X154371Y-29625D01*
Y-30315D01*
G01Y-29625D02*
X154061Y-29165D01*
X153545Y-28782D01*
X152925Y-28629D01*
X152305Y-28782D01*
X151788Y-29165D01*
X151478Y-29855D01*
X151581Y-30545D01*
X151995Y-31235D01*
G01X157678Y-26295D02*
X151478D01*
Y-24379D01*
X151788Y-23765D01*
X152201Y-23382D01*
X153028Y-23229D01*
X153855Y-23382D01*
X154371Y-23842D01*
X154681Y-24379D01*
Y-26295D01*
G01Y-24379D02*
X157678Y-23229D01*
G01Y-17642D02*
X151478D01*
X155921Y-20479D01*
Y-16645D01*
G01X156438Y-14049D02*
X157161Y-13589D01*
X157575Y-12975D01*
X157678Y-12285D01*
X157575Y-11672D01*
X157058Y-11059D01*
X156438Y-10675D01*
X155818Y-10599D01*
X155095Y-10752D01*
X154578Y-11289D01*
X154371Y-11825D01*
Y-12515D01*
G01Y-11825D02*
X154061Y-11365D01*
X153545Y-10982D01*
X152925Y-10829D01*
X152305Y-10982D01*
X151788Y-11365D01*
X151478Y-12055D01*
X151581Y-12745D01*
X151995Y-13435D01*
G01X157678Y-5242D02*
X151478D01*
X155921Y-8079D01*
Y-4245D01*
G01X169874Y4735D02*
X163674D01*
Y6651D01*
X163984Y7265D01*
X164397Y7648D01*
X165224Y7801D01*
X166051Y7648D01*
X166567Y7188D01*
X166877Y6651D01*
Y4735D01*
G01Y6651D02*
X169874Y7801D01*
G01X167291Y11011D02*
X166567Y11548D01*
X166154Y12008D01*
X165947Y12621D01*
X166154Y13158D01*
X166567Y13541D01*
X167187Y13848D01*
X167911Y13925D01*
X168531Y13848D01*
X169151Y13541D01*
X169667Y13081D01*
X169874Y12545D01*
X169667Y11931D01*
X169048Y11395D01*
X168117Y11088D01*
X167084Y11011D01*
X165741Y11165D01*
X165017Y11395D01*
X164294Y11778D01*
X163777Y12315D01*
X163674Y12851D01*
X163881Y13388D01*
X164397Y13771D01*
G01X169874Y19588D02*
X163674D01*
X168117Y16751D01*
Y20585D01*
G01X159874Y4735D02*
X153674D01*
Y6651D01*
X153984Y7265D01*
X154397Y7648D01*
X155224Y7801D01*
X156051Y7648D01*
X156567Y7188D01*
X156877Y6651D01*
Y4735D01*
G01Y6651D02*
X159874Y7801D01*
G01X157291Y11011D02*
X156567Y11548D01*
X156154Y12008D01*
X155947Y12621D01*
X156154Y13158D01*
X156567Y13541D01*
X157187Y13848D01*
X157911Y13925D01*
X158531Y13848D01*
X159151Y13541D01*
X159667Y13081D01*
X159874Y12545D01*
X159667Y11931D01*
X159048Y11395D01*
X158117Y11088D01*
X157084Y11011D01*
X155741Y11165D01*
X155017Y11395D01*
X154294Y11778D01*
X153777Y12315D01*
X153674Y12851D01*
X153881Y13388D01*
X154397Y13771D01*
G01X159151Y17365D02*
X159667Y17901D01*
X159874Y18515D01*
X159667Y19128D01*
X159048Y19665D01*
X158117Y20048D01*
X157187Y20201D01*
X156051D01*
X155121Y20048D01*
X154294Y19665D01*
X153881Y19205D01*
X153674Y18668D01*
X153881Y18055D01*
X154294Y17595D01*
X154914Y17288D01*
X155741Y17135D01*
X156464Y17288D01*
X157187Y17671D01*
X157601Y18131D01*
X157704Y18668D01*
X157497Y19281D01*
X156981Y19741D01*
X156051Y20201D01*
G01X171678Y437705D02*
X165478D01*
Y439621D01*
X165788Y440235D01*
X166201Y440618D01*
X167028Y440771D01*
X167855Y440618D01*
X168371Y440158D01*
X168681Y439621D01*
Y437705D01*
G01Y439621D02*
X171678Y440771D01*
G01Y445438D02*
X165478D01*
X166718Y444518D01*
G01X171678D02*
Y446358D01*
G01Y451638D02*
X165478D01*
X166718Y450718D01*
G01X171678D02*
Y452558D01*
G01Y457838D02*
X171575Y458375D01*
X171265Y458988D01*
X170748Y459371D01*
X170025Y459525D01*
X169301Y459371D01*
X168681Y458911D01*
X168371Y458221D01*
Y457455D01*
X168165Y456995D01*
X167648Y456611D01*
X166925Y456458D01*
X166201Y456688D01*
X165685Y457225D01*
X165478Y457838D01*
X165685Y458451D01*
X166201Y458988D01*
X166925Y459218D01*
X167648Y459065D01*
X168165Y458681D01*
X168371Y458221D01*
Y457455D01*
X168681Y456765D01*
X169301Y456305D01*
X170025Y456151D01*
X170748Y456305D01*
X171265Y456688D01*
X171575Y457301D01*
X171678Y457838D01*
G01X182995Y-226075D02*
X182685Y-226535D01*
X182478Y-227072D01*
Y-227685D01*
X182788Y-228375D01*
X183305Y-228912D01*
X183925Y-229295D01*
X184958Y-229602D01*
X185888Y-229679D01*
X186818Y-229525D01*
X187438Y-229295D01*
X188058Y-228835D01*
X188471Y-228299D01*
X188678Y-227762D01*
Y-227225D01*
X188471Y-226689D01*
X188161Y-226229D01*
X187748Y-225845D01*
G01X183511Y-223019D02*
X182891Y-222559D01*
X182581Y-222022D01*
X182478Y-221409D01*
X182685Y-220642D01*
X183201Y-220105D01*
X183821Y-219952D01*
X184441Y-220029D01*
X184958Y-220335D01*
X185991Y-221869D01*
X186715Y-222559D01*
X187748Y-223019D01*
X188678Y-223172D01*
Y-219952D01*
G01X187955Y-216665D02*
X188471Y-216129D01*
X188678Y-215515D01*
X188471Y-214902D01*
X187852Y-214365D01*
X186921Y-213982D01*
X185991Y-213829D01*
X184855D01*
X183925Y-213982D01*
X183098Y-214365D01*
X182685Y-214825D01*
X182478Y-215362D01*
X182685Y-215975D01*
X183098Y-216435D01*
X183718Y-216742D01*
X184545Y-216895D01*
X185268Y-216742D01*
X185991Y-216359D01*
X186405Y-215899D01*
X186508Y-215362D01*
X186301Y-214749D01*
X185785Y-214289D01*
X184855Y-213829D01*
G01X187438Y-210849D02*
X188161Y-210389D01*
X188575Y-209775D01*
X188678Y-209085D01*
X188575Y-208472D01*
X188058Y-207859D01*
X187438Y-207475D01*
X186818Y-207399D01*
X186095Y-207552D01*
X185578Y-208089D01*
X185371Y-208625D01*
Y-209315D01*
G01Y-208625D02*
X185061Y-208165D01*
X184545Y-207782D01*
X183925Y-207629D01*
X183305Y-207782D01*
X182788Y-208165D01*
X182478Y-208855D01*
X182581Y-209545D01*
X182995Y-210235D01*
G01X181745Y438438D02*
Y444638D01*
X183661D01*
X184275Y444328D01*
X184658Y443915D01*
X184811Y443088D01*
X184658Y442261D01*
X184198Y441745D01*
X183661Y441435D01*
X181745D01*
G01X183661D02*
X184811Y438438D01*
G01X188021Y443605D02*
X188481Y444225D01*
X189018Y444535D01*
X189631Y444638D01*
X190398Y444431D01*
X190935Y443915D01*
X191088Y443295D01*
X191011Y442675D01*
X190705Y442158D01*
X189171Y441125D01*
X188481Y440401D01*
X188021Y439368D01*
X187868Y438438D01*
X191088D01*
G01X194221Y441021D02*
X194758Y441745D01*
X195218Y442158D01*
X195831Y442365D01*
X196368Y442158D01*
X196751Y441745D01*
X197058Y441125D01*
X197135Y440401D01*
X197058Y439781D01*
X196751Y439161D01*
X196291Y438645D01*
X195755Y438438D01*
X195141Y438645D01*
X194605Y439264D01*
X194298Y440195D01*
X194221Y441228D01*
X194375Y442571D01*
X194605Y443295D01*
X194988Y444018D01*
X195525Y444535D01*
X196061Y444638D01*
X196598Y444431D01*
X196981Y443915D01*
G01X200421Y443605D02*
X200881Y444225D01*
X201418Y444535D01*
X202031Y444638D01*
X202798Y444431D01*
X203335Y443915D01*
X203488Y443295D01*
X203411Y442675D01*
X203105Y442158D01*
X201571Y441125D01*
X200881Y440401D01*
X200421Y439368D01*
X200268Y438438D01*
X203488D01*
G01X181745Y447438D02*
Y453638D01*
X183661D01*
X184275Y453328D01*
X184658Y452915D01*
X184811Y452088D01*
X184658Y451261D01*
X184198Y450745D01*
X183661Y450435D01*
X181745D01*
G01X183661D02*
X184811Y447438D01*
G01X188021Y452605D02*
X188481Y453225D01*
X189018Y453535D01*
X189631Y453638D01*
X190398Y453431D01*
X190935Y452915D01*
X191088Y452295D01*
X191011Y451675D01*
X190705Y451158D01*
X189171Y450125D01*
X188481Y449401D01*
X188021Y448368D01*
X187868Y447438D01*
X191088D01*
G01X193991Y448368D02*
X194451Y447851D01*
X194988Y447541D01*
X195678Y447438D01*
X196368Y447645D01*
X196905Y448058D01*
X197288Y448781D01*
X197365Y449608D01*
X197211Y450435D01*
X196828Y450951D01*
X196291Y451365D01*
X195755Y451468D01*
X195218Y451365D01*
X194528Y450951D01*
X194758Y453638D01*
X196828D01*
G01X200421Y450021D02*
X200958Y450745D01*
X201418Y451158D01*
X202031Y451365D01*
X202568Y451158D01*
X202951Y450745D01*
X203258Y450125D01*
X203335Y449401D01*
X203258Y448781D01*
X202951Y448161D01*
X202491Y447645D01*
X201955Y447438D01*
X201341Y447645D01*
X200805Y448264D01*
X200498Y449195D01*
X200421Y450228D01*
X200575Y451571D01*
X200805Y452295D01*
X201188Y453018D01*
X201725Y453535D01*
X202261Y453638D01*
X202798Y453431D01*
X203181Y452915D01*
G01X199578Y-254295D02*
X193378D01*
Y-252379D01*
X193688Y-251765D01*
X194101Y-251382D01*
X194928Y-251229D01*
X195755Y-251382D01*
X196271Y-251842D01*
X196581Y-252379D01*
Y-254295D01*
G01Y-252379D02*
X199578Y-251229D01*
G01X194411Y-248019D02*
X193791Y-247559D01*
X193481Y-247022D01*
X193378Y-246409D01*
X193585Y-245642D01*
X194101Y-245105D01*
X194721Y-244952D01*
X195341Y-245029D01*
X195858Y-245335D01*
X196891Y-246869D01*
X197615Y-247559D01*
X198648Y-248019D01*
X199578Y-248172D01*
Y-244952D01*
G01X194411Y-241819D02*
X193791Y-241359D01*
X193481Y-240822D01*
X193378Y-240209D01*
X193585Y-239442D01*
X194101Y-238905D01*
X194721Y-238752D01*
X195341Y-238829D01*
X195858Y-239135D01*
X196891Y-240669D01*
X197615Y-241359D01*
X198648Y-241819D01*
X199578Y-241972D01*
Y-238752D01*
G01Y-234315D02*
X198235Y-234162D01*
X197098Y-233932D01*
X196065Y-233625D01*
X194928Y-233242D01*
X193378Y-232629D01*
Y-235695D01*
G01X198678Y-229295D02*
X192478D01*
Y-227379D01*
X192788Y-226765D01*
X193201Y-226382D01*
X194028Y-226229D01*
X194855Y-226382D01*
X195371Y-226842D01*
X195681Y-227379D01*
Y-229295D01*
G01Y-227379D02*
X198678Y-226229D01*
G01X193511Y-223019D02*
X192891Y-222559D01*
X192581Y-222022D01*
X192478Y-221409D01*
X192685Y-220642D01*
X193201Y-220105D01*
X193821Y-219952D01*
X194441Y-220029D01*
X194958Y-220335D01*
X195991Y-221869D01*
X196715Y-222559D01*
X197748Y-223019D01*
X198678Y-223172D01*
Y-219952D01*
G01X193511Y-216819D02*
X192891Y-216359D01*
X192581Y-215822D01*
X192478Y-215209D01*
X192685Y-214442D01*
X193201Y-213905D01*
X193821Y-213752D01*
X194441Y-213829D01*
X194958Y-214135D01*
X195991Y-215669D01*
X196715Y-216359D01*
X197748Y-216819D01*
X198678Y-216972D01*
Y-213752D01*
G01X197748Y-210849D02*
X198265Y-210389D01*
X198575Y-209852D01*
X198678Y-209162D01*
X198471Y-208472D01*
X198058Y-207935D01*
X197335Y-207552D01*
X196508Y-207475D01*
X195681Y-207629D01*
X195165Y-208012D01*
X194751Y-208549D01*
X194648Y-209085D01*
X194751Y-209622D01*
X195165Y-210312D01*
X192478Y-210082D01*
Y-208012D01*
G01X192745Y21538D02*
Y27738D01*
X194661D01*
X195275Y27428D01*
X195658Y27015D01*
X195811Y26188D01*
X195658Y25361D01*
X195198Y24845D01*
X194661Y24535D01*
X192745D01*
G01X194661D02*
X195811Y21538D01*
G01X199021Y26705D02*
X199481Y27325D01*
X200018Y27635D01*
X200631Y27738D01*
X201398Y27531D01*
X201935Y27015D01*
X202088Y26395D01*
X202011Y25775D01*
X201705Y25258D01*
X200171Y24225D01*
X199481Y23501D01*
X199021Y22468D01*
X198868Y21538D01*
X202088D01*
G01X204991Y22468D02*
X205451Y21951D01*
X205988Y21641D01*
X206678Y21538D01*
X207368Y21745D01*
X207905Y22158D01*
X208288Y22881D01*
X208365Y23708D01*
X208211Y24535D01*
X207828Y25051D01*
X207291Y25465D01*
X206755Y25568D01*
X206218Y25465D01*
X205528Y25051D01*
X205758Y27738D01*
X207828D01*
G01X211191Y22778D02*
X211651Y22055D01*
X212265Y21641D01*
X212955Y21538D01*
X213568Y21641D01*
X214181Y22158D01*
X214565Y22778D01*
X214641Y23398D01*
X214488Y24121D01*
X213951Y24638D01*
X213415Y24845D01*
X212725D01*
G01X213415D02*
X213875Y25155D01*
X214258Y25671D01*
X214411Y26291D01*
X214258Y26911D01*
X213875Y27428D01*
X213185Y27738D01*
X212495Y27635D01*
X211805Y27221D01*
G01X202878Y84705D02*
X196678D01*
Y86621D01*
X196988Y87235D01*
X197401Y87618D01*
X198228Y87771D01*
X199055Y87618D01*
X199571Y87158D01*
X199881Y86621D01*
Y84705D01*
G01Y86621D02*
X202878Y87771D01*
G01X197711Y90981D02*
X197091Y91441D01*
X196781Y91978D01*
X196678Y92591D01*
X196885Y93358D01*
X197401Y93895D01*
X198021Y94048D01*
X198641Y93971D01*
X199158Y93665D01*
X200191Y92131D01*
X200915Y91441D01*
X201948Y90981D01*
X202878Y90828D01*
Y94048D01*
G01X201948Y96951D02*
X202465Y97411D01*
X202775Y97948D01*
X202878Y98638D01*
X202671Y99328D01*
X202258Y99865D01*
X201535Y100248D01*
X200708Y100325D01*
X199881Y100171D01*
X199365Y99788D01*
X198951Y99251D01*
X198848Y98715D01*
X198951Y98178D01*
X199365Y97488D01*
X196678Y97718D01*
Y99788D01*
G01X202878Y104838D02*
X196678D01*
X197918Y103918D01*
G01X202878D02*
Y105758D01*
G01X201264Y174038D02*
Y180238D01*
X198427Y175795D01*
X202261D01*
G01X202264Y232038D02*
Y238238D01*
X199427Y233795D01*
X203261D01*
G01X194645Y406902D02*
Y413102D01*
X196561D01*
X197175Y412792D01*
X197558Y412379D01*
X197711Y411552D01*
X197558Y410725D01*
X197098Y410209D01*
X196561Y409899D01*
X194645D01*
G01X196561D02*
X197711Y406902D01*
G01X202378D02*
Y413102D01*
X201458Y411862D01*
G01Y406902D02*
X203298D01*
G01X207121Y409485D02*
X207658Y410209D01*
X208118Y410622D01*
X208731Y410829D01*
X209268Y410622D01*
X209651Y410209D01*
X209958Y409589D01*
X210035Y408865D01*
X209958Y408245D01*
X209651Y407625D01*
X209191Y407109D01*
X208655Y406902D01*
X208041Y407109D01*
X207505Y407728D01*
X207198Y408659D01*
X207121Y409692D01*
X207275Y411035D01*
X207505Y411759D01*
X207888Y412482D01*
X208425Y412999D01*
X208961Y413102D01*
X209498Y412895D01*
X209881Y412379D01*
G01X194645Y396902D02*
Y403102D01*
X196561D01*
X197175Y402792D01*
X197558Y402379D01*
X197711Y401552D01*
X197558Y400725D01*
X197098Y400209D01*
X196561Y399899D01*
X194645D01*
G01X196561D02*
X197711Y396902D01*
G01X202378D02*
Y403102D01*
X201458Y401862D01*
G01Y396902D02*
X203298D01*
G01X208578Y403102D02*
X207965Y402895D01*
X207505Y402379D01*
X207198Y401759D01*
X206968Y400932D01*
X206891Y400002D01*
X206968Y399072D01*
X207198Y398245D01*
X207505Y397625D01*
X207965Y397109D01*
X208578Y396902D01*
X209191Y397109D01*
X209651Y397625D01*
X209958Y398245D01*
X210188Y399072D01*
X210265Y400002D01*
X210188Y400932D01*
X209958Y401759D01*
X209651Y402379D01*
X209191Y402895D01*
X208578Y403102D01*
G01X195678Y463705D02*
X189478D01*
Y465621D01*
X189788Y466235D01*
X190201Y466618D01*
X191028Y466771D01*
X191855Y466618D01*
X192371Y466158D01*
X192681Y465621D01*
Y463705D01*
G01Y465621D02*
X195678Y466771D01*
G01X190511Y469981D02*
X189891Y470441D01*
X189581Y470978D01*
X189478Y471591D01*
X189685Y472358D01*
X190201Y472895D01*
X190821Y473048D01*
X191441Y472971D01*
X191958Y472665D01*
X192991Y471131D01*
X193715Y470441D01*
X194748Y469981D01*
X195678Y469828D01*
Y473048D01*
G01X193095Y476181D02*
X192371Y476718D01*
X191958Y477178D01*
X191751Y477791D01*
X191958Y478328D01*
X192371Y478711D01*
X192991Y479018D01*
X193715Y479095D01*
X194335Y479018D01*
X194955Y478711D01*
X195471Y478251D01*
X195678Y477715D01*
X195471Y477101D01*
X194852Y476565D01*
X193921Y476258D01*
X192888Y476181D01*
X191545Y476335D01*
X190821Y476565D01*
X190098Y476948D01*
X189581Y477485D01*
X189478Y478021D01*
X189685Y478558D01*
X190201Y478941D01*
G01X195678Y483838D02*
X189478D01*
X190718Y482918D01*
G01X195678D02*
Y484758D01*
G01X220965Y25121D02*
X220505Y25431D01*
X219968Y25638D01*
X219355D01*
X218665Y25328D01*
X218128Y24811D01*
X217745Y24191D01*
X217438Y23158D01*
X217361Y22228D01*
X217515Y21298D01*
X217745Y20678D01*
X218205Y20058D01*
X218741Y19645D01*
X219278Y19438D01*
X219815D01*
X220351Y19645D01*
X220811Y19955D01*
X221195Y20368D01*
G01X224021Y24605D02*
X224481Y25225D01*
X225018Y25535D01*
X225631Y25638D01*
X226398Y25431D01*
X226935Y24915D01*
X227088Y24295D01*
X227011Y23675D01*
X226705Y23158D01*
X225171Y22125D01*
X224481Y21401D01*
X224021Y20368D01*
X223868Y19438D01*
X227088D01*
G01X230221Y22021D02*
X230758Y22745D01*
X231218Y23158D01*
X231831Y23365D01*
X232368Y23158D01*
X232751Y22745D01*
X233058Y22125D01*
X233135Y21401D01*
X233058Y20781D01*
X232751Y20161D01*
X232291Y19645D01*
X231755Y19438D01*
X231141Y19645D01*
X230605Y20264D01*
X230298Y21195D01*
X230221Y22228D01*
X230375Y23571D01*
X230605Y24295D01*
X230988Y25018D01*
X231525Y25535D01*
X232061Y25638D01*
X232598Y25431D01*
X232981Y24915D01*
G01X236421Y22021D02*
X236958Y22745D01*
X237418Y23158D01*
X238031Y23365D01*
X238568Y23158D01*
X238951Y22745D01*
X239258Y22125D01*
X239335Y21401D01*
X239258Y20781D01*
X238951Y20161D01*
X238491Y19645D01*
X237955Y19438D01*
X237341Y19645D01*
X236805Y20264D01*
X236498Y21195D01*
X236421Y22228D01*
X236575Y23571D01*
X236805Y24295D01*
X237188Y25018D01*
X237725Y25535D01*
X238261Y25638D01*
X238798Y25431D01*
X239181Y24915D01*
G01X217013Y86867D02*
X216703Y86407D01*
X216496Y85870D01*
Y85257D01*
X216806Y84567D01*
X217323Y84030D01*
X217943Y83647D01*
X218976Y83340D01*
X219906Y83263D01*
X220836Y83417D01*
X221456Y83647D01*
X222076Y84107D01*
X222489Y84643D01*
X222696Y85180D01*
Y85717D01*
X222489Y86253D01*
X222179Y86713D01*
X221766Y87097D01*
G01X217529Y89923D02*
X216909Y90383D01*
X216599Y90920D01*
X216496Y91533D01*
X216703Y92300D01*
X217219Y92837D01*
X217839Y92990D01*
X218459Y92913D01*
X218976Y92607D01*
X220009Y91073D01*
X220733Y90383D01*
X221766Y89923D01*
X222696Y89770D01*
Y92990D01*
G01X220113Y96123D02*
X219389Y96660D01*
X218976Y97120D01*
X218769Y97733D01*
X218976Y98270D01*
X219389Y98653D01*
X220009Y98960D01*
X220733Y99037D01*
X221353Y98960D01*
X221973Y98653D01*
X222489Y98193D01*
X222696Y97657D01*
X222489Y97043D01*
X221870Y96507D01*
X220939Y96200D01*
X219906Y96123D01*
X218563Y96277D01*
X217839Y96507D01*
X217116Y96890D01*
X216599Y97427D01*
X216496Y97963D01*
X216703Y98500D01*
X217219Y98883D01*
G01X221456Y102093D02*
X222179Y102553D01*
X222593Y103167D01*
X222696Y103857D01*
X222593Y104470D01*
X222076Y105083D01*
X221456Y105467D01*
X220836Y105543D01*
X220113Y105390D01*
X219596Y104853D01*
X219389Y104317D01*
Y103627D01*
G01Y104317D02*
X219079Y104777D01*
X218563Y105160D01*
X217943Y105313D01*
X217323Y105160D01*
X216806Y104777D01*
X216496Y104087D01*
X216599Y103397D01*
X217013Y102707D01*
G01X213678Y84705D02*
X207478D01*
Y86621D01*
X207788Y87235D01*
X208201Y87618D01*
X209028Y87771D01*
X209855Y87618D01*
X210371Y87158D01*
X210681Y86621D01*
Y84705D01*
G01Y86621D02*
X213678Y87771D01*
G01X208511Y90981D02*
X207891Y91441D01*
X207581Y91978D01*
X207478Y92591D01*
X207685Y93358D01*
X208201Y93895D01*
X208821Y94048D01*
X209441Y93971D01*
X209958Y93665D01*
X210991Y92131D01*
X211715Y91441D01*
X212748Y90981D01*
X213678Y90828D01*
Y94048D01*
G01X212748Y96951D02*
X213265Y97411D01*
X213575Y97948D01*
X213678Y98638D01*
X213471Y99328D01*
X213058Y99865D01*
X212335Y100248D01*
X211508Y100325D01*
X210681Y100171D01*
X210165Y99788D01*
X209751Y99251D01*
X209648Y98715D01*
X209751Y98178D01*
X210165Y97488D01*
X207478Y97718D01*
Y99788D01*
G01X208511Y103381D02*
X207891Y103841D01*
X207581Y104378D01*
X207478Y104991D01*
X207685Y105758D01*
X208201Y106295D01*
X208821Y106448D01*
X209441Y106371D01*
X209958Y106065D01*
X210991Y104531D01*
X211715Y103841D01*
X212748Y103381D01*
X213678Y103228D01*
Y106448D01*
G01X213421Y150705D02*
X213881Y151325D01*
X214418Y151635D01*
X215031Y151738D01*
X215798Y151531D01*
X216335Y151015D01*
X216488Y150395D01*
X216411Y149775D01*
X216105Y149258D01*
X214571Y148225D01*
X213881Y147501D01*
X213421Y146468D01*
X213268Y145538D01*
X216488D01*
G01X206065Y167221D02*
X205605Y167531D01*
X205068Y167738D01*
X204455D01*
X203765Y167428D01*
X203228Y166911D01*
X202845Y166291D01*
X202538Y165258D01*
X202461Y164328D01*
X202615Y163398D01*
X202845Y162778D01*
X203305Y162158D01*
X203841Y161745D01*
X204378Y161538D01*
X204915D01*
X205451Y161745D01*
X205911Y162055D01*
X206295Y162468D01*
G01X209045Y161538D02*
Y167738D01*
X210961D01*
X211575Y167428D01*
X211958Y167015D01*
X212111Y166188D01*
X211958Y165361D01*
X211498Y164845D01*
X210961Y164535D01*
X209045D01*
G01X210961D02*
X212111Y161538D01*
G01X216625D02*
X216778Y162881D01*
X217008Y164018D01*
X217315Y165051D01*
X217698Y166188D01*
X218311Y167738D01*
X215245D01*
G01X213859Y175078D02*
X214319Y174355D01*
X214933Y173941D01*
X215623Y173838D01*
X216236Y173941D01*
X216849Y174458D01*
X217233Y175078D01*
X217309Y175698D01*
X217156Y176421D01*
X216619Y176938D01*
X216083Y177145D01*
X215393D01*
G01X216083D02*
X216543Y177455D01*
X216926Y177971D01*
X217079Y178591D01*
X216926Y179211D01*
X216543Y179728D01*
X215853Y180038D01*
X215163Y179935D01*
X214473Y179521D01*
G01X215421Y205705D02*
X215881Y206325D01*
X216418Y206635D01*
X217031Y206738D01*
X217798Y206531D01*
X218335Y206015D01*
X218488Y205395D01*
X218411Y204775D01*
X218105Y204258D01*
X216571Y203225D01*
X215881Y202501D01*
X215421Y201468D01*
X215268Y200538D01*
X218488D01*
G01X206395Y215225D02*
X206085Y214765D01*
X205878Y214228D01*
Y213615D01*
X206188Y212925D01*
X206705Y212388D01*
X207325Y212005D01*
X208358Y211698D01*
X209288Y211621D01*
X210218Y211775D01*
X210838Y212005D01*
X211458Y212465D01*
X211871Y213001D01*
X212078Y213538D01*
Y214075D01*
X211871Y214611D01*
X211561Y215071D01*
X211148Y215455D01*
G01X212078Y218205D02*
X205878D01*
Y220121D01*
X206188Y220735D01*
X206601Y221118D01*
X207428Y221271D01*
X208255Y221118D01*
X208771Y220658D01*
X209081Y220121D01*
Y218205D01*
G01Y220121D02*
X212078Y221271D01*
G01X209495Y224481D02*
X208771Y225018D01*
X208358Y225478D01*
X208151Y226091D01*
X208358Y226628D01*
X208771Y227011D01*
X209391Y227318D01*
X210115Y227395D01*
X210735Y227318D01*
X211355Y227011D01*
X211871Y226551D01*
X212078Y226015D01*
X211871Y225401D01*
X211252Y224865D01*
X210321Y224558D01*
X209288Y224481D01*
X207945Y224635D01*
X207221Y224865D01*
X206498Y225248D01*
X205981Y225785D01*
X205878Y226321D01*
X206085Y226858D01*
X206601Y227241D01*
G01X214859Y233078D02*
X215319Y232355D01*
X215933Y231941D01*
X216623Y231838D01*
X217236Y231941D01*
X217849Y232458D01*
X218233Y233078D01*
X218309Y233698D01*
X218156Y234421D01*
X217619Y234938D01*
X217083Y235145D01*
X216393D01*
G01X217083D02*
X217543Y235455D01*
X217926Y235971D01*
X218079Y236591D01*
X217926Y237211D01*
X217543Y237728D01*
X216853Y238038D01*
X216163Y237935D01*
X215473Y237521D01*
G01X218678Y436705D02*
X212478D01*
Y438621D01*
X212788Y439235D01*
X213201Y439618D01*
X214028Y439771D01*
X214855Y439618D01*
X215371Y439158D01*
X215681Y438621D01*
Y436705D01*
G01Y438621D02*
X218678Y439771D01*
G01Y444438D02*
X212478D01*
X213718Y443518D01*
G01X218678D02*
Y445358D01*
G01Y450638D02*
X218575Y451175D01*
X218265Y451788D01*
X217748Y452171D01*
X217025Y452325D01*
X216301Y452171D01*
X215681Y451711D01*
X215371Y451021D01*
Y450255D01*
X215165Y449795D01*
X214648Y449411D01*
X213925Y449258D01*
X213201Y449488D01*
X212685Y450025D01*
X212478Y450638D01*
X212685Y451251D01*
X213201Y451788D01*
X213925Y452018D01*
X214648Y451865D01*
X215165Y451481D01*
X215371Y451021D01*
Y450255D01*
X215681Y449565D01*
X216301Y449105D01*
X217025Y448951D01*
X217748Y449105D01*
X218265Y449488D01*
X218575Y450101D01*
X218678Y450638D01*
G01X212478Y456838D02*
X212685Y456225D01*
X213201Y455765D01*
X213821Y455458D01*
X214648Y455228D01*
X215578Y455151D01*
X216508Y455228D01*
X217335Y455458D01*
X217955Y455765D01*
X218471Y456225D01*
X218678Y456838D01*
X218471Y457451D01*
X217955Y457911D01*
X217335Y458218D01*
X216508Y458448D01*
X215578Y458525D01*
X214648Y458448D01*
X213821Y458218D01*
X213201Y457911D01*
X212685Y457451D01*
X212478Y456838D01*
G01X219678Y463705D02*
X213478D01*
Y465621D01*
X213788Y466235D01*
X214201Y466618D01*
X215028Y466771D01*
X215855Y466618D01*
X216371Y466158D01*
X216681Y465621D01*
Y463705D01*
G01Y465621D02*
X219678Y466771D01*
G01X214511Y469981D02*
X213891Y470441D01*
X213581Y470978D01*
X213478Y471591D01*
X213685Y472358D01*
X214201Y472895D01*
X214821Y473048D01*
X215441Y472971D01*
X215958Y472665D01*
X216991Y471131D01*
X217715Y470441D01*
X218748Y469981D01*
X219678Y469828D01*
Y473048D01*
G01X218748Y475951D02*
X219265Y476411D01*
X219575Y476948D01*
X219678Y477638D01*
X219471Y478328D01*
X219058Y478865D01*
X218335Y479248D01*
X217508Y479325D01*
X216681Y479171D01*
X216165Y478788D01*
X215751Y478251D01*
X215648Y477715D01*
X215751Y477178D01*
X216165Y476488D01*
X213478Y476718D01*
Y478788D01*
G01X218955Y482535D02*
X219471Y483071D01*
X219678Y483685D01*
X219471Y484298D01*
X218852Y484835D01*
X217921Y485218D01*
X216991Y485371D01*
X215855D01*
X214925Y485218D01*
X214098Y484835D01*
X213685Y484375D01*
X213478Y483838D01*
X213685Y483225D01*
X214098Y482765D01*
X214718Y482458D01*
X215545Y482305D01*
X216268Y482458D01*
X216991Y482841D01*
X217405Y483301D01*
X217508Y483838D01*
X217301Y484451D01*
X216785Y484911D01*
X215855Y485371D01*
G01X224852Y52728D02*
X225368Y53341D01*
X225678Y54031D01*
Y54645D01*
X225368Y55258D01*
X224852Y55718D01*
X224128Y55948D01*
X223405Y55795D01*
X222785Y55411D01*
X222371Y54721D01*
X222165Y53801D01*
X221751Y53265D01*
X221028Y53035D01*
X220305Y53188D01*
X219788Y53571D01*
X219478Y54108D01*
Y54645D01*
X219685Y55181D01*
X220201Y55641D01*
G01X225678Y59005D02*
X219478D01*
Y60845D01*
X219788Y61458D01*
X220511Y61918D01*
X221338Y62071D01*
X222165Y61918D01*
X222785Y61535D01*
X223095Y60845D01*
Y59005D01*
G01X224438Y65051D02*
X225161Y65511D01*
X225575Y66125D01*
X225678Y66815D01*
X225575Y67428D01*
X225058Y68041D01*
X224438Y68425D01*
X223818Y68501D01*
X223095Y68348D01*
X222578Y67811D01*
X222371Y67275D01*
Y66585D01*
G01Y67275D02*
X222061Y67735D01*
X221545Y68118D01*
X220925Y68271D01*
X220305Y68118D01*
X219788Y67735D01*
X219478Y67045D01*
X219581Y66355D01*
X219995Y65665D01*
G01X233678Y84705D02*
X227478D01*
Y86621D01*
X227788Y87235D01*
X228201Y87618D01*
X229028Y87771D01*
X229855Y87618D01*
X230371Y87158D01*
X230681Y86621D01*
Y84705D01*
G01Y86621D02*
X233678Y87771D01*
G01X228511Y90981D02*
X227891Y91441D01*
X227581Y91978D01*
X227478Y92591D01*
X227685Y93358D01*
X228201Y93895D01*
X228821Y94048D01*
X229441Y93971D01*
X229958Y93665D01*
X230991Y92131D01*
X231715Y91441D01*
X232748Y90981D01*
X233678Y90828D01*
Y94048D01*
G01Y99558D02*
X227478D01*
X231921Y96721D01*
Y100555D01*
G01X232955Y103535D02*
X233471Y104071D01*
X233678Y104685D01*
X233471Y105298D01*
X232852Y105835D01*
X231921Y106218D01*
X230991Y106371D01*
X229855D01*
X228925Y106218D01*
X228098Y105835D01*
X227685Y105375D01*
X227478Y104838D01*
X227685Y104225D01*
X228098Y103765D01*
X228718Y103458D01*
X229545Y103305D01*
X230268Y103458D01*
X230991Y103841D01*
X231405Y104301D01*
X231508Y104838D01*
X231301Y105451D01*
X230785Y105911D01*
X229855Y106371D01*
G01X229345Y152038D02*
Y158238D01*
X231261D01*
X231875Y157928D01*
X232258Y157515D01*
X232411Y156688D01*
X232258Y155861D01*
X231798Y155345D01*
X231261Y155035D01*
X229345D01*
G01X231261D02*
X232411Y152038D01*
G01X237078D02*
Y158238D01*
X236158Y156998D01*
G01Y152038D02*
X237998D01*
G01X241591Y153278D02*
X242051Y152555D01*
X242665Y152141D01*
X243355Y152038D01*
X243968Y152141D01*
X244581Y152658D01*
X244965Y153278D01*
X245041Y153898D01*
X244888Y154621D01*
X244351Y155138D01*
X243815Y155345D01*
X243125D01*
G01X243815D02*
X244275Y155655D01*
X244658Y156171D01*
X244811Y156791D01*
X244658Y157411D01*
X244275Y157928D01*
X243585Y158238D01*
X242895Y158135D01*
X242205Y157721D01*
G01X250398Y152038D02*
Y158238D01*
X247561Y153795D01*
X251395D01*
G01X230745Y177438D02*
Y183638D01*
X232661D01*
X233275Y183328D01*
X233658Y182915D01*
X233811Y182088D01*
X233658Y181261D01*
X233198Y180745D01*
X232661Y180435D01*
X230745D01*
G01X232661D02*
X233811Y177438D01*
G01X238478D02*
Y183638D01*
X237558Y182398D01*
G01Y177438D02*
X239398D01*
G01X242991Y178678D02*
X243451Y177955D01*
X244065Y177541D01*
X244755Y177438D01*
X245368Y177541D01*
X245981Y178058D01*
X246365Y178678D01*
X246441Y179298D01*
X246288Y180021D01*
X245751Y180538D01*
X245215Y180745D01*
X244525D01*
G01X245215D02*
X245675Y181055D01*
X246058Y181571D01*
X246211Y182191D01*
X246058Y182811D01*
X245675Y183328D01*
X244985Y183638D01*
X244295Y183535D01*
X243605Y183121D01*
G01X249191Y178368D02*
X249651Y177851D01*
X250188Y177541D01*
X250878Y177438D01*
X251568Y177645D01*
X252105Y178058D01*
X252488Y178781D01*
X252565Y179608D01*
X252411Y180435D01*
X252028Y180951D01*
X251491Y181365D01*
X250955Y181468D01*
X250418Y181365D01*
X249728Y180951D01*
X249958Y183638D01*
X252028D01*
G01X231145Y167638D02*
Y173838D01*
X233061D01*
X233675Y173528D01*
X234058Y173115D01*
X234211Y172288D01*
X234058Y171461D01*
X233598Y170945D01*
X233061Y170635D01*
X231145D01*
G01X233061D02*
X234211Y167638D01*
G01X238878D02*
Y173838D01*
X237958Y172598D01*
G01Y167638D02*
X239798D01*
G01X243391Y168878D02*
X243851Y168155D01*
X244465Y167741D01*
X245155Y167638D01*
X245768Y167741D01*
X246381Y168258D01*
X246765Y168878D01*
X246841Y169498D01*
X246688Y170221D01*
X246151Y170738D01*
X245615Y170945D01*
X244925D01*
G01X245615D02*
X246075Y171255D01*
X246458Y171771D01*
X246611Y172391D01*
X246458Y173011D01*
X246075Y173528D01*
X245385Y173838D01*
X244695Y173735D01*
X244005Y173321D01*
G01X249591Y168878D02*
X250051Y168155D01*
X250665Y167741D01*
X251355Y167638D01*
X251968Y167741D01*
X252581Y168258D01*
X252965Y168878D01*
X253041Y169498D01*
X252888Y170221D01*
X252351Y170738D01*
X251815Y170945D01*
X251125D01*
G01X251815D02*
X252275Y171255D01*
X252658Y171771D01*
X252811Y172391D01*
X252658Y173011D01*
X252275Y173528D01*
X251585Y173838D01*
X250895Y173735D01*
X250205Y173321D01*
G01X229745Y207538D02*
Y213738D01*
X231661D01*
X232275Y213428D01*
X232658Y213015D01*
X232811Y212188D01*
X232658Y211361D01*
X232198Y210845D01*
X231661Y210535D01*
X229745D01*
G01X231661D02*
X232811Y207538D01*
G01X237478D02*
Y213738D01*
X236558Y212498D01*
G01Y207538D02*
X238398D01*
G01X241991Y208778D02*
X242451Y208055D01*
X243065Y207641D01*
X243755Y207538D01*
X244368Y207641D01*
X244981Y208158D01*
X245365Y208778D01*
X245441Y209398D01*
X245288Y210121D01*
X244751Y210638D01*
X244215Y210845D01*
X243525D01*
G01X244215D02*
X244675Y211155D01*
X245058Y211671D01*
X245211Y212291D01*
X245058Y212911D01*
X244675Y213428D01*
X243985Y213738D01*
X243295Y213635D01*
X242605Y213221D01*
G01X248421Y210121D02*
X248958Y210845D01*
X249418Y211258D01*
X250031Y211465D01*
X250568Y211258D01*
X250951Y210845D01*
X251258Y210225D01*
X251335Y209501D01*
X251258Y208881D01*
X250951Y208261D01*
X250491Y207745D01*
X249955Y207538D01*
X249341Y207745D01*
X248805Y208364D01*
X248498Y209295D01*
X248421Y210328D01*
X248575Y211671D01*
X248805Y212395D01*
X249188Y213118D01*
X249725Y213635D01*
X250261Y213738D01*
X250798Y213531D01*
X251181Y213015D01*
G01X230345Y227738D02*
Y233938D01*
X232261D01*
X232875Y233628D01*
X233258Y233215D01*
X233411Y232388D01*
X233258Y231561D01*
X232798Y231045D01*
X232261Y230735D01*
X230345D01*
G01X232261D02*
X233411Y227738D01*
G01X238078D02*
Y233938D01*
X237158Y232698D01*
G01Y227738D02*
X238998D01*
G01X242591Y228978D02*
X243051Y228255D01*
X243665Y227841D01*
X244355Y227738D01*
X244968Y227841D01*
X245581Y228358D01*
X245965Y228978D01*
X246041Y229598D01*
X245888Y230321D01*
X245351Y230838D01*
X244815Y231045D01*
X244125D01*
G01X244815D02*
X245275Y231355D01*
X245658Y231871D01*
X245811Y232491D01*
X245658Y233111D01*
X245275Y233628D01*
X244585Y233938D01*
X243895Y233835D01*
X243205Y233421D01*
G01X250325Y227738D02*
X250478Y229081D01*
X250708Y230218D01*
X251015Y231251D01*
X251398Y232388D01*
X252011Y233938D01*
X248945D01*
G01X229745Y437438D02*
Y443638D01*
X231661D01*
X232275Y443328D01*
X232658Y442915D01*
X232811Y442088D01*
X232658Y441261D01*
X232198Y440745D01*
X231661Y440435D01*
X229745D01*
G01X231661D02*
X232811Y437438D01*
G01X237478D02*
Y443638D01*
X236558Y442398D01*
G01Y437438D02*
X238398D01*
G01X241991Y438678D02*
X242451Y437955D01*
X243065Y437541D01*
X243755Y437438D01*
X244368Y437541D01*
X244981Y438058D01*
X245365Y438678D01*
X245441Y439298D01*
X245288Y440021D01*
X244751Y440538D01*
X244215Y440745D01*
X243525D01*
G01X244215D02*
X244675Y441055D01*
X245058Y441571D01*
X245211Y442191D01*
X245058Y442811D01*
X244675Y443328D01*
X243985Y443638D01*
X243295Y443535D01*
X242605Y443121D01*
G01X248575Y438161D02*
X249111Y437645D01*
X249725Y437438D01*
X250338Y437645D01*
X250875Y438264D01*
X251258Y439195D01*
X251411Y440125D01*
Y441261D01*
X251258Y442191D01*
X250875Y443018D01*
X250415Y443431D01*
X249878Y443638D01*
X249265Y443431D01*
X248805Y443018D01*
X248498Y442398D01*
X248345Y441571D01*
X248498Y440848D01*
X248881Y440125D01*
X249341Y439711D01*
X249878Y439608D01*
X250491Y439815D01*
X250951Y440331D01*
X251411Y441261D01*
G01X229745Y446438D02*
Y452638D01*
X231661D01*
X232275Y452328D01*
X232658Y451915D01*
X232811Y451088D01*
X232658Y450261D01*
X232198Y449745D01*
X231661Y449435D01*
X229745D01*
G01X231661D02*
X232811Y446438D01*
G01X237478D02*
Y452638D01*
X236558Y451398D01*
G01Y446438D02*
X238398D01*
G01X243678Y452638D02*
X243065Y452431D01*
X242605Y451915D01*
X242298Y451295D01*
X242068Y450468D01*
X241991Y449538D01*
X242068Y448608D01*
X242298Y447781D01*
X242605Y447161D01*
X243065Y446645D01*
X243678Y446438D01*
X244291Y446645D01*
X244751Y447161D01*
X245058Y447781D01*
X245288Y448608D01*
X245365Y449538D01*
X245288Y450468D01*
X245058Y451295D01*
X244751Y451915D01*
X244291Y452431D01*
X243678Y452638D01*
G01X249878Y446438D02*
X250415Y446541D01*
X251028Y446851D01*
X251411Y447368D01*
X251565Y448091D01*
X251411Y448815D01*
X250951Y449435D01*
X250261Y449745D01*
X249495D01*
X249035Y449951D01*
X248651Y450468D01*
X248498Y451191D01*
X248728Y451915D01*
X249265Y452431D01*
X249878Y452638D01*
X250491Y452431D01*
X251028Y451915D01*
X251258Y451191D01*
X251105Y450468D01*
X250721Y449951D01*
X250261Y449745D01*
X249495D01*
X248805Y449435D01*
X248345Y448815D01*
X248191Y448091D01*
X248345Y447368D01*
X248728Y446851D01*
X249341Y446541D01*
X249878Y446438D01*
G01X242678Y-258495D02*
X236478D01*
Y-256579D01*
X236788Y-255965D01*
X237201Y-255582D01*
X238028Y-255429D01*
X238855Y-255582D01*
X239371Y-256042D01*
X239681Y-256579D01*
Y-258495D01*
G01Y-256579D02*
X242678Y-255429D01*
G01X237511Y-252219D02*
X236891Y-251759D01*
X236581Y-251222D01*
X236478Y-250609D01*
X236685Y-249842D01*
X237201Y-249305D01*
X237821Y-249152D01*
X238441Y-249229D01*
X238958Y-249535D01*
X239991Y-251069D01*
X240715Y-251759D01*
X241748Y-252219D01*
X242678Y-252372D01*
Y-249152D01*
G01X237511Y-246019D02*
X236891Y-245559D01*
X236581Y-245022D01*
X236478Y-244409D01*
X236685Y-243642D01*
X237201Y-243105D01*
X237821Y-242952D01*
X238441Y-243029D01*
X238958Y-243335D01*
X239991Y-244869D01*
X240715Y-245559D01*
X241748Y-246019D01*
X242678Y-246172D01*
Y-242952D01*
G01X241955Y-239665D02*
X242471Y-239129D01*
X242678Y-238515D01*
X242471Y-237902D01*
X241852Y-237365D01*
X240921Y-236982D01*
X239991Y-236829D01*
X238855D01*
X237925Y-236982D01*
X237098Y-237365D01*
X236685Y-237825D01*
X236478Y-238362D01*
X236685Y-238975D01*
X237098Y-239435D01*
X237718Y-239742D01*
X238545Y-239895D01*
X239268Y-239742D01*
X239991Y-239359D01*
X240405Y-238899D01*
X240508Y-238362D01*
X240301Y-237749D01*
X239785Y-237289D01*
X238855Y-236829D01*
G01X243578Y-232295D02*
X237378D01*
Y-230379D01*
X237688Y-229765D01*
X238101Y-229382D01*
X238928Y-229229D01*
X239755Y-229382D01*
X240271Y-229842D01*
X240581Y-230379D01*
Y-232295D01*
G01Y-230379D02*
X243578Y-229229D01*
G01X238411Y-226019D02*
X237791Y-225559D01*
X237481Y-225022D01*
X237378Y-224409D01*
X237585Y-223642D01*
X238101Y-223105D01*
X238721Y-222952D01*
X239341Y-223029D01*
X239858Y-223335D01*
X240891Y-224869D01*
X241615Y-225559D01*
X242648Y-226019D01*
X243578Y-226172D01*
Y-222952D01*
G01X242338Y-220049D02*
X243061Y-219589D01*
X243475Y-218975D01*
X243578Y-218285D01*
X243475Y-217672D01*
X242958Y-217059D01*
X242338Y-216675D01*
X241718Y-216599D01*
X240995Y-216752D01*
X240478Y-217289D01*
X240271Y-217825D01*
Y-218515D01*
G01Y-217825D02*
X239961Y-217365D01*
X239445Y-216982D01*
X238825Y-216829D01*
X238205Y-216982D01*
X237688Y-217365D01*
X237378Y-218055D01*
X237481Y-218745D01*
X237895Y-219435D01*
G01X238411Y-213619D02*
X237791Y-213159D01*
X237481Y-212622D01*
X237378Y-212009D01*
X237585Y-211242D01*
X238101Y-210705D01*
X238721Y-210552D01*
X239341Y-210629D01*
X239858Y-210935D01*
X240891Y-212469D01*
X241615Y-213159D01*
X242648Y-213619D01*
X243578Y-213772D01*
Y-210552D01*
G01X245895Y22925D02*
X245585Y22465D01*
X245378Y21928D01*
Y21315D01*
X245688Y20625D01*
X246205Y20088D01*
X246825Y19705D01*
X247858Y19398D01*
X248788Y19321D01*
X249718Y19475D01*
X250338Y19705D01*
X250958Y20165D01*
X251371Y20701D01*
X251578Y21238D01*
Y21775D01*
X251371Y22311D01*
X251061Y22771D01*
X250648Y23155D01*
G01X246411Y25981D02*
X245791Y26441D01*
X245481Y26978D01*
X245378Y27591D01*
X245585Y28358D01*
X246101Y28895D01*
X246721Y29048D01*
X247341Y28971D01*
X247858Y28665D01*
X248891Y27131D01*
X249615Y26441D01*
X250648Y25981D01*
X251578Y25828D01*
Y29048D01*
G01X248995Y32181D02*
X248271Y32718D01*
X247858Y33178D01*
X247651Y33791D01*
X247858Y34328D01*
X248271Y34711D01*
X248891Y35018D01*
X249615Y35095D01*
X250235Y35018D01*
X250855Y34711D01*
X251371Y34251D01*
X251578Y33715D01*
X251371Y33101D01*
X250752Y32565D01*
X249821Y32258D01*
X248788Y32181D01*
X247445Y32335D01*
X246721Y32565D01*
X245998Y32948D01*
X245481Y33485D01*
X245378Y34021D01*
X245585Y34558D01*
X246101Y34941D01*
G01X250648Y38151D02*
X251165Y38611D01*
X251475Y39148D01*
X251578Y39838D01*
X251371Y40528D01*
X250958Y41065D01*
X250235Y41448D01*
X249408Y41525D01*
X248581Y41371D01*
X248065Y40988D01*
X247651Y40451D01*
X247548Y39915D01*
X247651Y39378D01*
X248065Y38688D01*
X245378Y38918D01*
Y40988D01*
G01X250646Y45705D02*
X244446D01*
Y47621D01*
X244756Y48235D01*
X245169Y48618D01*
X245996Y48771D01*
X246823Y48618D01*
X247339Y48158D01*
X247649Y47621D01*
Y45705D01*
G01Y47621D02*
X250646Y48771D01*
G01X245479Y51981D02*
X244859Y52441D01*
X244549Y52978D01*
X244446Y53591D01*
X244653Y54358D01*
X245169Y54895D01*
X245789Y55048D01*
X246409Y54971D01*
X246926Y54665D01*
X247959Y53131D01*
X248683Y52441D01*
X249716Y51981D01*
X250646Y51828D01*
Y55048D01*
G01X249716Y57951D02*
X250233Y58411D01*
X250543Y58948D01*
X250646Y59638D01*
X250439Y60328D01*
X250026Y60865D01*
X249303Y61248D01*
X248476Y61325D01*
X247649Y61171D01*
X247133Y60788D01*
X246719Y60251D01*
X246616Y59715D01*
X246719Y59178D01*
X247133Y58488D01*
X244446Y58718D01*
Y60788D01*
G01Y65838D02*
X244653Y65225D01*
X245169Y64765D01*
X245789Y64458D01*
X246616Y64228D01*
X247546Y64151D01*
X248476Y64228D01*
X249303Y64458D01*
X249923Y64765D01*
X250439Y65225D01*
X250646Y65838D01*
X250439Y66451D01*
X249923Y66911D01*
X249303Y67218D01*
X248476Y67448D01*
X247546Y67525D01*
X246616Y67448D01*
X245789Y67218D01*
X245169Y66911D01*
X244653Y66451D01*
X244446Y65838D01*
G01X251678Y84705D02*
X245478D01*
Y86621D01*
X245788Y87235D01*
X246201Y87618D01*
X247028Y87771D01*
X247855Y87618D01*
X248371Y87158D01*
X248681Y86621D01*
Y84705D01*
G01Y86621D02*
X251678Y87771D01*
G01X246511Y90981D02*
X245891Y91441D01*
X245581Y91978D01*
X245478Y92591D01*
X245685Y93358D01*
X246201Y93895D01*
X246821Y94048D01*
X247441Y93971D01*
X247958Y93665D01*
X248991Y92131D01*
X249715Y91441D01*
X250748Y90981D01*
X251678Y90828D01*
Y94048D01*
G01Y99558D02*
X245478D01*
X249921Y96721D01*
Y100555D01*
G01X251678Y105758D02*
X245478D01*
X249921Y102921D01*
Y106755D01*
G01X259646Y84705D02*
X253446D01*
Y86621D01*
X253756Y87235D01*
X254169Y87618D01*
X254996Y87771D01*
X255823Y87618D01*
X256339Y87158D01*
X256649Y86621D01*
Y84705D01*
G01Y86621D02*
X259646Y87771D01*
G01X254479Y90981D02*
X253859Y91441D01*
X253549Y91978D01*
X253446Y92591D01*
X253653Y93358D01*
X254169Y93895D01*
X254789Y94048D01*
X255409Y93971D01*
X255926Y93665D01*
X256959Y92131D01*
X257683Y91441D01*
X258716Y90981D01*
X259646Y90828D01*
Y94048D01*
G01Y99558D02*
X253446D01*
X257889Y96721D01*
Y100555D01*
G01X259646Y104685D02*
X258303Y104838D01*
X257166Y105068D01*
X256133Y105375D01*
X254996Y105758D01*
X253446Y106371D01*
Y103305D01*
G01X242678Y84705D02*
X236478D01*
Y86621D01*
X236788Y87235D01*
X237201Y87618D01*
X238028Y87771D01*
X238855Y87618D01*
X239371Y87158D01*
X239681Y86621D01*
Y84705D01*
G01Y86621D02*
X242678Y87771D01*
G01X237511Y90981D02*
X236891Y91441D01*
X236581Y91978D01*
X236478Y92591D01*
X236685Y93358D01*
X237201Y93895D01*
X237821Y94048D01*
X238441Y93971D01*
X238958Y93665D01*
X239991Y92131D01*
X240715Y91441D01*
X241748Y90981D01*
X242678Y90828D01*
Y94048D01*
G01Y99558D02*
X236478D01*
X240921Y96721D01*
Y100555D01*
G01X240095Y103381D02*
X239371Y103918D01*
X238958Y104378D01*
X238751Y104991D01*
X238958Y105528D01*
X239371Y105911D01*
X239991Y106218D01*
X240715Y106295D01*
X241335Y106218D01*
X241955Y105911D01*
X242471Y105451D01*
X242678Y104915D01*
X242471Y104301D01*
X241852Y103765D01*
X240921Y103458D01*
X239888Y103381D01*
X238545Y103535D01*
X237821Y103765D01*
X237098Y104148D01*
X236581Y104685D01*
X236478Y105221D01*
X236685Y105758D01*
X237201Y106141D01*
G01X237845Y142438D02*
Y148638D01*
X239761D01*
X240375Y148328D01*
X240758Y147915D01*
X240911Y147088D01*
X240758Y146261D01*
X240298Y145745D01*
X239761Y145435D01*
X237845D01*
G01X239761D02*
X240911Y142438D01*
G01X244121Y147605D02*
X244581Y148225D01*
X245118Y148535D01*
X245731Y148638D01*
X246498Y148431D01*
X247035Y147915D01*
X247188Y147295D01*
X247111Y146675D01*
X246805Y146158D01*
X245271Y145125D01*
X244581Y144401D01*
X244121Y143368D01*
X243968Y142438D01*
X247188D01*
G01X251778D02*
X252315Y142541D01*
X252928Y142851D01*
X253311Y143368D01*
X253465Y144091D01*
X253311Y144815D01*
X252851Y145435D01*
X252161Y145745D01*
X251395D01*
X250935Y145951D01*
X250551Y146468D01*
X250398Y147191D01*
X250628Y147915D01*
X251165Y148431D01*
X251778Y148638D01*
X252391Y148431D01*
X252928Y147915D01*
X253158Y147191D01*
X253005Y146468D01*
X252621Y145951D01*
X252161Y145745D01*
X251395D01*
X250705Y145435D01*
X250245Y144815D01*
X250091Y144091D01*
X250245Y143368D01*
X250628Y142851D01*
X251241Y142541D01*
X251778Y142438D01*
G01X248845Y197438D02*
Y203638D01*
X250761D01*
X251375Y203328D01*
X251758Y202915D01*
X251911Y202088D01*
X251758Y201261D01*
X251298Y200745D01*
X250761Y200435D01*
X248845D01*
G01X250761D02*
X251911Y197438D01*
G01X257498D02*
Y203638D01*
X254661Y199195D01*
X258495D01*
G01X261091Y198678D02*
X261551Y197955D01*
X262165Y197541D01*
X262855Y197438D01*
X263468Y197541D01*
X264081Y198058D01*
X264465Y198678D01*
X264541Y199298D01*
X264388Y200021D01*
X263851Y200538D01*
X263315Y200745D01*
X262625D01*
G01X263315D02*
X263775Y201055D01*
X264158Y201571D01*
X264311Y202191D01*
X264158Y202811D01*
X263775Y203328D01*
X263085Y203638D01*
X262395Y203535D01*
X261705Y203121D01*
G01X237845Y186438D02*
Y192638D01*
X239761D01*
X240375Y192328D01*
X240758Y191915D01*
X240911Y191088D01*
X240758Y190261D01*
X240298Y189745D01*
X239761Y189435D01*
X237845D01*
G01X239761D02*
X240911Y186438D01*
G01X246498D02*
Y192638D01*
X243661Y188195D01*
X247495D01*
G01X250321Y191605D02*
X250781Y192225D01*
X251318Y192535D01*
X251931Y192638D01*
X252698Y192431D01*
X253235Y191915D01*
X253388Y191295D01*
X253311Y190675D01*
X253005Y190158D01*
X251471Y189125D01*
X250781Y188401D01*
X250321Y187368D01*
X250168Y186438D01*
X253388D01*
G01X237845Y236438D02*
Y242638D01*
X239761D01*
X240375Y242328D01*
X240758Y241915D01*
X240911Y241088D01*
X240758Y240261D01*
X240298Y239745D01*
X239761Y239435D01*
X237845D01*
G01X239761D02*
X240911Y236438D01*
G01X246498D02*
Y242638D01*
X243661Y238195D01*
X247495D01*
G01X251778Y236438D02*
Y242638D01*
X250858Y241398D01*
G01Y236438D02*
X252698D01*
G01X244165Y272385D02*
X243705Y272695D01*
X243168Y272902D01*
X242555D01*
X241865Y272592D01*
X241328Y272075D01*
X240945Y271455D01*
X240638Y270422D01*
X240561Y269492D01*
X240715Y268562D01*
X240945Y267942D01*
X241405Y267322D01*
X241941Y266909D01*
X242478Y266702D01*
X243015D01*
X243551Y266909D01*
X244011Y267219D01*
X244395Y267632D01*
G01X246991Y267942D02*
X247451Y267219D01*
X248065Y266805D01*
X248755Y266702D01*
X249368Y266805D01*
X249981Y267322D01*
X250365Y267942D01*
X250441Y268562D01*
X250288Y269285D01*
X249751Y269802D01*
X249215Y270009D01*
X248525D01*
G01X249215D02*
X249675Y270319D01*
X250058Y270835D01*
X250211Y271455D01*
X250058Y272075D01*
X249675Y272592D01*
X248985Y272902D01*
X248295Y272799D01*
X247605Y272385D01*
G01X254878Y272902D02*
X254265Y272695D01*
X253805Y272179D01*
X253498Y271559D01*
X253268Y270732D01*
X253191Y269802D01*
X253268Y268872D01*
X253498Y268045D01*
X253805Y267425D01*
X254265Y266909D01*
X254878Y266702D01*
X255491Y266909D01*
X255951Y267425D01*
X256258Y268045D01*
X256488Y268872D01*
X256565Y269802D01*
X256488Y270732D01*
X256258Y271559D01*
X255951Y272179D01*
X255491Y272695D01*
X254878Y272902D01*
G01X259391Y267942D02*
X259851Y267219D01*
X260465Y266805D01*
X261155Y266702D01*
X261768Y266805D01*
X262381Y267322D01*
X262765Y267942D01*
X262841Y268562D01*
X262688Y269285D01*
X262151Y269802D01*
X261615Y270009D01*
X260925D01*
G01X261615D02*
X262075Y270319D01*
X262458Y270835D01*
X262611Y271455D01*
X262458Y272075D01*
X262075Y272592D01*
X261385Y272902D01*
X260695Y272799D01*
X260005Y272385D01*
G01X243365Y288785D02*
X242905Y289095D01*
X242368Y289302D01*
X241755D01*
X241065Y288992D01*
X240528Y288475D01*
X240145Y287855D01*
X239838Y286822D01*
X239761Y285892D01*
X239915Y284962D01*
X240145Y284342D01*
X240605Y283722D01*
X241141Y283309D01*
X241678Y283102D01*
X242215D01*
X242751Y283309D01*
X243211Y283619D01*
X243595Y284032D01*
G01X246421Y288269D02*
X246881Y288889D01*
X247418Y289199D01*
X248031Y289302D01*
X248798Y289095D01*
X249335Y288579D01*
X249488Y287959D01*
X249411Y287339D01*
X249105Y286822D01*
X247571Y285789D01*
X246881Y285065D01*
X246421Y284032D01*
X246268Y283102D01*
X249488D01*
G01X252775Y283825D02*
X253311Y283309D01*
X253925Y283102D01*
X254538Y283309D01*
X255075Y283928D01*
X255458Y284859D01*
X255611Y285789D01*
Y286925D01*
X255458Y287855D01*
X255075Y288682D01*
X254615Y289095D01*
X254078Y289302D01*
X253465Y289095D01*
X253005Y288682D01*
X252698Y288062D01*
X252545Y287235D01*
X252698Y286512D01*
X253081Y285789D01*
X253541Y285375D01*
X254078Y285272D01*
X254691Y285479D01*
X255151Y285995D01*
X255611Y286925D01*
G01X258975Y283825D02*
X259511Y283309D01*
X260125Y283102D01*
X260738Y283309D01*
X261275Y283928D01*
X261658Y284859D01*
X261811Y285789D01*
Y286925D01*
X261658Y287855D01*
X261275Y288682D01*
X260815Y289095D01*
X260278Y289302D01*
X259665Y289095D01*
X259205Y288682D01*
X258898Y288062D01*
X258745Y287235D01*
X258898Y286512D01*
X259281Y285789D01*
X259741Y285375D01*
X260278Y285272D01*
X260891Y285479D01*
X261351Y285995D01*
X261811Y286925D01*
G01X243365Y303985D02*
X242905Y304295D01*
X242368Y304502D01*
X241755D01*
X241065Y304192D01*
X240528Y303675D01*
X240145Y303055D01*
X239838Y302022D01*
X239761Y301092D01*
X239915Y300162D01*
X240145Y299542D01*
X240605Y298922D01*
X241141Y298509D01*
X241678Y298302D01*
X242215D01*
X242751Y298509D01*
X243211Y298819D01*
X243595Y299232D01*
G01X246421Y303469D02*
X246881Y304089D01*
X247418Y304399D01*
X248031Y304502D01*
X248798Y304295D01*
X249335Y303779D01*
X249488Y303159D01*
X249411Y302539D01*
X249105Y302022D01*
X247571Y300989D01*
X246881Y300265D01*
X246421Y299232D01*
X246268Y298302D01*
X249488D01*
G01X252775Y299025D02*
X253311Y298509D01*
X253925Y298302D01*
X254538Y298509D01*
X255075Y299128D01*
X255458Y300059D01*
X255611Y300989D01*
Y302125D01*
X255458Y303055D01*
X255075Y303882D01*
X254615Y304295D01*
X254078Y304502D01*
X253465Y304295D01*
X253005Y303882D01*
X252698Y303262D01*
X252545Y302435D01*
X252698Y301712D01*
X253081Y300989D01*
X253541Y300575D01*
X254078Y300472D01*
X254691Y300679D01*
X255151Y301195D01*
X255611Y302125D01*
G01X260125Y298302D02*
X260278Y299645D01*
X260508Y300782D01*
X260815Y301815D01*
X261198Y302952D01*
X261811Y304502D01*
X258745D01*
G01X243365Y319385D02*
X242905Y319695D01*
X242368Y319902D01*
X241755D01*
X241065Y319592D01*
X240528Y319075D01*
X240145Y318455D01*
X239838Y317422D01*
X239761Y316492D01*
X239915Y315562D01*
X240145Y314942D01*
X240605Y314322D01*
X241141Y313909D01*
X241678Y313702D01*
X242215D01*
X242751Y313909D01*
X243211Y314219D01*
X243595Y314632D01*
G01X246191Y314942D02*
X246651Y314219D01*
X247265Y313805D01*
X247955Y313702D01*
X248568Y313805D01*
X249181Y314322D01*
X249565Y314942D01*
X249641Y315562D01*
X249488Y316285D01*
X248951Y316802D01*
X248415Y317009D01*
X247725D01*
G01X248415D02*
X248875Y317319D01*
X249258Y317835D01*
X249411Y318455D01*
X249258Y319075D01*
X248875Y319592D01*
X248185Y319902D01*
X247495Y319799D01*
X246805Y319385D01*
G01X254078Y319902D02*
X253465Y319695D01*
X253005Y319179D01*
X252698Y318559D01*
X252468Y317732D01*
X252391Y316802D01*
X252468Y315872D01*
X252698Y315045D01*
X253005Y314425D01*
X253465Y313909D01*
X254078Y313702D01*
X254691Y313909D01*
X255151Y314425D01*
X255458Y315045D01*
X255688Y315872D01*
X255765Y316802D01*
X255688Y317732D01*
X255458Y318559D01*
X255151Y319179D01*
X254691Y319695D01*
X254078Y319902D01*
G01X260278Y313702D02*
Y319902D01*
X259358Y318662D01*
G01Y313702D02*
X261198D01*
G01X242678Y463705D02*
X236478D01*
Y465621D01*
X236788Y466235D01*
X237201Y466618D01*
X238028Y466771D01*
X238855Y466618D01*
X239371Y466158D01*
X239681Y465621D01*
Y463705D01*
G01Y465621D02*
X242678Y466771D01*
G01X237511Y469981D02*
X236891Y470441D01*
X236581Y470978D01*
X236478Y471591D01*
X236685Y472358D01*
X237201Y472895D01*
X237821Y473048D01*
X238441Y472971D01*
X238958Y472665D01*
X239991Y471131D01*
X240715Y470441D01*
X241748Y469981D01*
X242678Y469828D01*
Y473048D01*
G01X241748Y475951D02*
X242265Y476411D01*
X242575Y476948D01*
X242678Y477638D01*
X242471Y478328D01*
X242058Y478865D01*
X241335Y479248D01*
X240508Y479325D01*
X239681Y479171D01*
X239165Y478788D01*
X238751Y478251D01*
X238648Y477715D01*
X238751Y477178D01*
X239165Y476488D01*
X236478Y476718D01*
Y478788D01*
G01X242678Y483838D02*
X242575Y484375D01*
X242265Y484988D01*
X241748Y485371D01*
X241025Y485525D01*
X240301Y485371D01*
X239681Y484911D01*
X239371Y484221D01*
Y483455D01*
X239165Y482995D01*
X238648Y482611D01*
X237925Y482458D01*
X237201Y482688D01*
X236685Y483225D01*
X236478Y483838D01*
X236685Y484451D01*
X237201Y484988D01*
X237925Y485218D01*
X238648Y485065D01*
X239165Y484681D01*
X239371Y484221D01*
Y483455D01*
X239681Y482765D01*
X240301Y482305D01*
X241025Y482151D01*
X241748Y482305D01*
X242265Y482688D01*
X242575Y483301D01*
X242678Y483838D01*
G01X254745Y-248562D02*
Y-242362D01*
X256661D01*
X257275Y-242672D01*
X257658Y-243085D01*
X257811Y-243912D01*
X257658Y-244739D01*
X257198Y-245255D01*
X256661Y-245565D01*
X254745D01*
G01X256661D02*
X257811Y-248562D01*
G01X261021Y-243395D02*
X261481Y-242775D01*
X262018Y-242465D01*
X262631Y-242362D01*
X263398Y-242569D01*
X263935Y-243085D01*
X264088Y-243705D01*
X264011Y-244325D01*
X263705Y-244842D01*
X262171Y-245875D01*
X261481Y-246599D01*
X261021Y-247632D01*
X260868Y-248562D01*
X264088D01*
G01X266991Y-247322D02*
X267451Y-248045D01*
X268065Y-248459D01*
X268755Y-248562D01*
X269368Y-248459D01*
X269981Y-247942D01*
X270365Y-247322D01*
X270441Y-246702D01*
X270288Y-245979D01*
X269751Y-245462D01*
X269215Y-245255D01*
X268525D01*
G01X269215D02*
X269675Y-244945D01*
X270058Y-244429D01*
X270211Y-243809D01*
X270058Y-243189D01*
X269675Y-242672D01*
X268985Y-242362D01*
X268295Y-242465D01*
X267605Y-242879D01*
G01X274878Y-242362D02*
X274265Y-242569D01*
X273805Y-243085D01*
X273498Y-243705D01*
X273268Y-244532D01*
X273191Y-245462D01*
X273268Y-246392D01*
X273498Y-247219D01*
X273805Y-247839D01*
X274265Y-248355D01*
X274878Y-248562D01*
X275491Y-248355D01*
X275951Y-247839D01*
X276258Y-247219D01*
X276488Y-246392D01*
X276565Y-245462D01*
X276488Y-244532D01*
X276258Y-243705D01*
X275951Y-243085D01*
X275491Y-242569D01*
X274878Y-242362D01*
G01X254745Y-238562D02*
Y-232362D01*
X256661D01*
X257275Y-232672D01*
X257658Y-233085D01*
X257811Y-233912D01*
X257658Y-234739D01*
X257198Y-235255D01*
X256661Y-235565D01*
X254745D01*
G01X256661D02*
X257811Y-238562D01*
G01X261021Y-233395D02*
X261481Y-232775D01*
X262018Y-232465D01*
X262631Y-232362D01*
X263398Y-232569D01*
X263935Y-233085D01*
X264088Y-233705D01*
X264011Y-234325D01*
X263705Y-234842D01*
X262171Y-235875D01*
X261481Y-236599D01*
X261021Y-237632D01*
X260868Y-238562D01*
X264088D01*
G01X266991Y-237322D02*
X267451Y-238045D01*
X268065Y-238459D01*
X268755Y-238562D01*
X269368Y-238459D01*
X269981Y-237942D01*
X270365Y-237322D01*
X270441Y-236702D01*
X270288Y-235979D01*
X269751Y-235462D01*
X269215Y-235255D01*
X268525D01*
G01X269215D02*
X269675Y-234945D01*
X270058Y-234429D01*
X270211Y-233809D01*
X270058Y-233189D01*
X269675Y-232672D01*
X268985Y-232362D01*
X268295Y-232465D01*
X267605Y-232879D01*
G01X273191Y-237322D02*
X273651Y-238045D01*
X274265Y-238459D01*
X274955Y-238562D01*
X275568Y-238459D01*
X276181Y-237942D01*
X276565Y-237322D01*
X276641Y-236702D01*
X276488Y-235979D01*
X275951Y-235462D01*
X275415Y-235255D01*
X274725D01*
G01X275415D02*
X275875Y-234945D01*
X276258Y-234429D01*
X276411Y-233809D01*
X276258Y-233189D01*
X275875Y-232672D01*
X275185Y-232362D01*
X274495Y-232465D01*
X273805Y-232879D01*
G01X269995Y-56075D02*
X269685Y-56535D01*
X269478Y-57072D01*
Y-57685D01*
X269788Y-58375D01*
X270305Y-58912D01*
X270925Y-59295D01*
X271958Y-59602D01*
X272888Y-59679D01*
X273818Y-59525D01*
X274438Y-59295D01*
X275058Y-58835D01*
X275471Y-58299D01*
X275678Y-57762D01*
Y-57225D01*
X275471Y-56689D01*
X275161Y-56229D01*
X274748Y-55845D01*
G01X275678Y-51562D02*
X269478D01*
X270718Y-52482D01*
G01X275678D02*
Y-50642D01*
G01Y-45515D02*
X274335Y-45362D01*
X273198Y-45132D01*
X272165Y-44825D01*
X271028Y-44442D01*
X269478Y-43829D01*
Y-46895D01*
G01X275678Y-39162D02*
X275575Y-38625D01*
X275265Y-38012D01*
X274748Y-37629D01*
X274025Y-37475D01*
X273301Y-37629D01*
X272681Y-38089D01*
X272371Y-38779D01*
Y-39545D01*
X272165Y-40005D01*
X271648Y-40389D01*
X270925Y-40542D01*
X270201Y-40312D01*
X269685Y-39775D01*
X269478Y-39162D01*
X269685Y-38549D01*
X270201Y-38012D01*
X270925Y-37782D01*
X271648Y-37935D01*
X272165Y-38319D01*
X272371Y-38779D01*
Y-39545D01*
X272681Y-40235D01*
X273301Y-40695D01*
X274025Y-40849D01*
X274748Y-40695D01*
X275265Y-40312D01*
X275575Y-39699D01*
X275678Y-39162D01*
G01X266895Y-16075D02*
X266585Y-16535D01*
X266378Y-17072D01*
Y-17685D01*
X266688Y-18375D01*
X267205Y-18912D01*
X267825Y-19295D01*
X268858Y-19602D01*
X269788Y-19679D01*
X270718Y-19525D01*
X271338Y-19295D01*
X271958Y-18835D01*
X272371Y-18299D01*
X272578Y-17762D01*
Y-17225D01*
X272371Y-16689D01*
X272061Y-16229D01*
X271648Y-15845D01*
G01X272578Y-11562D02*
X266378D01*
X267618Y-12482D01*
G01X272578D02*
Y-10642D01*
G01Y-5515D02*
X271235Y-5362D01*
X270098Y-5132D01*
X269065Y-4825D01*
X267928Y-4442D01*
X266378Y-3829D01*
Y-6895D01*
G01X271855Y-465D02*
X272371Y71D01*
X272578Y685D01*
X272371Y1298D01*
X271752Y1835D01*
X270821Y2218D01*
X269891Y2371D01*
X268755D01*
X267825Y2218D01*
X266998Y1835D01*
X266585Y1375D01*
X266378Y838D01*
X266585Y225D01*
X266998Y-235D01*
X267618Y-542D01*
X268445Y-695D01*
X269168Y-542D01*
X269891Y-159D01*
X270305Y301D01*
X270408Y838D01*
X270201Y1451D01*
X269685Y1911D01*
X268755Y2371D01*
G01X264745Y78538D02*
Y84738D01*
X266661D01*
X267275Y84428D01*
X267658Y84015D01*
X267811Y83188D01*
X267658Y82361D01*
X267198Y81845D01*
X266661Y81535D01*
X264745D01*
G01X266661D02*
X267811Y78538D01*
G01X271021Y83705D02*
X271481Y84325D01*
X272018Y84635D01*
X272631Y84738D01*
X273398Y84531D01*
X273935Y84015D01*
X274088Y83395D01*
X274011Y82775D01*
X273705Y82258D01*
X272171Y81225D01*
X271481Y80501D01*
X271021Y79468D01*
X270868Y78538D01*
X274088D01*
G01X279598D02*
Y84738D01*
X276761Y80295D01*
X280595D01*
G01X283191Y79778D02*
X283651Y79055D01*
X284265Y78641D01*
X284955Y78538D01*
X285568Y78641D01*
X286181Y79158D01*
X286565Y79778D01*
X286641Y80398D01*
X286488Y81121D01*
X285951Y81638D01*
X285415Y81845D01*
X284725D01*
G01X285415D02*
X285875Y82155D01*
X286258Y82671D01*
X286411Y83291D01*
X286258Y83911D01*
X285875Y84428D01*
X285185Y84738D01*
X284495Y84635D01*
X283805Y84221D01*
G01X262678Y144705D02*
X256478D01*
Y146621D01*
X256788Y147235D01*
X257201Y147618D01*
X258028Y147771D01*
X258855Y147618D01*
X259371Y147158D01*
X259681Y146621D01*
Y144705D01*
G01Y146621D02*
X262678Y147771D01*
G01Y153358D02*
X256478D01*
X260921Y150521D01*
Y154355D01*
G01X256478Y158638D02*
X256685Y158025D01*
X257201Y157565D01*
X257821Y157258D01*
X258648Y157028D01*
X259578Y156951D01*
X260508Y157028D01*
X261335Y157258D01*
X261955Y157565D01*
X262471Y158025D01*
X262678Y158638D01*
X262471Y159251D01*
X261955Y159711D01*
X261335Y160018D01*
X260508Y160248D01*
X259578Y160325D01*
X258648Y160248D01*
X257821Y160018D01*
X257201Y159711D01*
X256685Y159251D01*
X256478Y158638D01*
G01X257511Y163381D02*
X256891Y163841D01*
X256581Y164378D01*
X256478Y164991D01*
X256685Y165758D01*
X257201Y166295D01*
X257821Y166448D01*
X258441Y166371D01*
X258958Y166065D01*
X259991Y164531D01*
X260715Y163841D01*
X261748Y163381D01*
X262678Y163228D01*
Y166448D01*
G01Y170705D02*
X256478D01*
Y172621D01*
X256788Y173235D01*
X257201Y173618D01*
X258028Y173771D01*
X258855Y173618D01*
X259371Y173158D01*
X259681Y172621D01*
Y170705D01*
G01Y172621D02*
X262678Y173771D01*
G01Y179358D02*
X256478D01*
X260921Y176521D01*
Y180355D01*
G01X256478Y184638D02*
X256685Y184025D01*
X257201Y183565D01*
X257821Y183258D01*
X258648Y183028D01*
X259578Y182951D01*
X260508Y183028D01*
X261335Y183258D01*
X261955Y183565D01*
X262471Y184025D01*
X262678Y184638D01*
X262471Y185251D01*
X261955Y185711D01*
X261335Y186018D01*
X260508Y186248D01*
X259578Y186325D01*
X258648Y186248D01*
X257821Y186018D01*
X257201Y185711D01*
X256685Y185251D01*
X256478Y184638D01*
G01X261438Y189151D02*
X262161Y189611D01*
X262575Y190225D01*
X262678Y190915D01*
X262575Y191528D01*
X262058Y192141D01*
X261438Y192525D01*
X260818Y192601D01*
X260095Y192448D01*
X259578Y191911D01*
X259371Y191375D01*
Y190685D01*
G01Y191375D02*
X259061Y191835D01*
X258545Y192218D01*
X257925Y192371D01*
X257305Y192218D01*
X256788Y191835D01*
X256478Y191145D01*
X256581Y190455D01*
X256995Y189765D01*
G01X263678Y206705D02*
X257478D01*
Y208621D01*
X257788Y209235D01*
X258201Y209618D01*
X259028Y209771D01*
X259855Y209618D01*
X260371Y209158D01*
X260681Y208621D01*
Y206705D01*
G01Y208621D02*
X263678Y209771D01*
G01Y215358D02*
X257478D01*
X261921Y212521D01*
Y216355D01*
G01X257478Y220638D02*
X257685Y220025D01*
X258201Y219565D01*
X258821Y219258D01*
X259648Y219028D01*
X260578Y218951D01*
X261508Y219028D01*
X262335Y219258D01*
X262955Y219565D01*
X263471Y220025D01*
X263678Y220638D01*
X263471Y221251D01*
X262955Y221711D01*
X262335Y222018D01*
X261508Y222248D01*
X260578Y222325D01*
X259648Y222248D01*
X258821Y222018D01*
X258201Y221711D01*
X257685Y221251D01*
X257478Y220638D01*
G01X263678Y227758D02*
X257478D01*
X261921Y224921D01*
Y228755D01*
G01X263678Y230705D02*
X257478D01*
Y232621D01*
X257788Y233235D01*
X258201Y233618D01*
X259028Y233771D01*
X259855Y233618D01*
X260371Y233158D01*
X260681Y232621D01*
Y230705D01*
G01Y232621D02*
X263678Y233771D01*
G01Y239358D02*
X257478D01*
X261921Y236521D01*
Y240355D01*
G01X257478Y244638D02*
X257685Y244025D01*
X258201Y243565D01*
X258821Y243258D01*
X259648Y243028D01*
X260578Y242951D01*
X261508Y243028D01*
X262335Y243258D01*
X262955Y243565D01*
X263471Y244025D01*
X263678Y244638D01*
X263471Y245251D01*
X262955Y245711D01*
X262335Y246018D01*
X261508Y246248D01*
X260578Y246325D01*
X259648Y246248D01*
X258821Y246018D01*
X258201Y245711D01*
X257685Y245251D01*
X257478Y244638D01*
G01X262748Y249151D02*
X263265Y249611D01*
X263575Y250148D01*
X263678Y250838D01*
X263471Y251528D01*
X263058Y252065D01*
X262335Y252448D01*
X261508Y252525D01*
X260681Y252371D01*
X260165Y251988D01*
X259751Y251451D01*
X259648Y250915D01*
X259751Y250378D01*
X260165Y249688D01*
X257478Y249918D01*
Y251988D01*
G01X267678Y441705D02*
X261478D01*
Y443621D01*
X261788Y444235D01*
X262201Y444618D01*
X263028Y444771D01*
X263855Y444618D01*
X264371Y444158D01*
X264681Y443621D01*
Y441705D01*
G01Y443621D02*
X267678Y444771D01*
G01Y449438D02*
X261478D01*
X262718Y448518D01*
G01X267678D02*
Y450358D01*
G01X266438Y453951D02*
X267161Y454411D01*
X267575Y455025D01*
X267678Y455715D01*
X267575Y456328D01*
X267058Y456941D01*
X266438Y457325D01*
X265818Y457401D01*
X265095Y457248D01*
X264578Y456711D01*
X264371Y456175D01*
Y455485D01*
G01Y456175D02*
X264061Y456635D01*
X263545Y457018D01*
X262925Y457171D01*
X262305Y457018D01*
X261788Y456635D01*
X261478Y455945D01*
X261581Y455255D01*
X261995Y454565D01*
G01X267678Y461838D02*
X267575Y462375D01*
X267265Y462988D01*
X266748Y463371D01*
X266025Y463525D01*
X265301Y463371D01*
X264681Y462911D01*
X264371Y462221D01*
Y461455D01*
X264165Y460995D01*
X263648Y460611D01*
X262925Y460458D01*
X262201Y460688D01*
X261685Y461225D01*
X261478Y461838D01*
X261685Y462451D01*
X262201Y462988D01*
X262925Y463218D01*
X263648Y463065D01*
X264165Y462681D01*
X264371Y462221D01*
Y461455D01*
X264681Y460765D01*
X265301Y460305D01*
X266025Y460151D01*
X266748Y460305D01*
X267265Y460688D01*
X267575Y461301D01*
X267678Y461838D01*
G01Y467705D02*
X261478D01*
Y469621D01*
X261788Y470235D01*
X262201Y470618D01*
X263028Y470771D01*
X263855Y470618D01*
X264371Y470158D01*
X264681Y469621D01*
Y467705D01*
G01Y469621D02*
X267678Y470771D01*
G01X262511Y473981D02*
X261891Y474441D01*
X261581Y474978D01*
X261478Y475591D01*
X261685Y476358D01*
X262201Y476895D01*
X262821Y477048D01*
X263441Y476971D01*
X263958Y476665D01*
X264991Y475131D01*
X265715Y474441D01*
X266748Y473981D01*
X267678Y473828D01*
Y477048D01*
G01X266748Y479951D02*
X267265Y480411D01*
X267575Y480948D01*
X267678Y481638D01*
X267471Y482328D01*
X267058Y482865D01*
X266335Y483248D01*
X265508Y483325D01*
X264681Y483171D01*
X264165Y482788D01*
X263751Y482251D01*
X263648Y481715D01*
X263751Y481178D01*
X264165Y480488D01*
X261478Y480718D01*
Y482788D01*
G01X267678Y487685D02*
X266335Y487838D01*
X265198Y488068D01*
X264165Y488375D01*
X263028Y488758D01*
X261478Y489371D01*
Y486305D01*
G01X288661Y318438D02*
X290578Y324638D01*
X292495Y318438D01*
G01X291805Y320608D02*
X289351D01*
G01X284795Y343425D02*
X284485Y342965D01*
X284278Y342428D01*
Y341815D01*
X284588Y341125D01*
X285105Y340588D01*
X285725Y340205D01*
X286758Y339898D01*
X287688Y339821D01*
X288618Y339975D01*
X289238Y340205D01*
X289858Y340665D01*
X290271Y341201D01*
X290478Y341738D01*
Y342275D01*
X290271Y342811D01*
X289961Y343271D01*
X289548Y343655D01*
G01X290478Y346405D02*
X284278D01*
Y348321D01*
X284588Y348935D01*
X285001Y349318D01*
X285828Y349471D01*
X286655Y349318D01*
X287171Y348858D01*
X287481Y348321D01*
Y346405D01*
G01Y348321D02*
X290478Y349471D01*
G01X289238Y352451D02*
X289961Y352911D01*
X290375Y353525D01*
X290478Y354215D01*
X290375Y354828D01*
X289858Y355441D01*
X289238Y355825D01*
X288618Y355901D01*
X287895Y355748D01*
X287378Y355211D01*
X287171Y354675D01*
Y353985D01*
G01Y354675D02*
X286861Y355135D01*
X286345Y355518D01*
X285725Y355671D01*
X285105Y355518D01*
X284588Y355135D01*
X284278Y354445D01*
X284381Y353755D01*
X284795Y353065D01*
G01X289265Y383121D02*
X288805Y383431D01*
X288268Y383638D01*
X287655D01*
X286965Y383328D01*
X286428Y382811D01*
X286045Y382191D01*
X285738Y381158D01*
X285661Y380228D01*
X285815Y379298D01*
X286045Y378678D01*
X286505Y378058D01*
X287041Y377645D01*
X287578Y377438D01*
X288115D01*
X288651Y377645D01*
X289111Y377955D01*
X289495Y378368D01*
G01X289078Y451707D02*
X282878D01*
Y453623D01*
X283188Y454237D01*
X283601Y454620D01*
X284428Y454773D01*
X285255Y454620D01*
X285771Y454160D01*
X286081Y453623D01*
Y451707D01*
G01Y453623D02*
X289078Y454773D01*
G01X283911Y457983D02*
X283291Y458443D01*
X282981Y458980D01*
X282878Y459593D01*
X283085Y460360D01*
X283601Y460897D01*
X284221Y461050D01*
X284841Y460973D01*
X285358Y460667D01*
X286391Y459133D01*
X287115Y458443D01*
X288148Y457983D01*
X289078Y457830D01*
Y461050D01*
G01X282878Y465640D02*
X283085Y465027D01*
X283601Y464567D01*
X284221Y464260D01*
X285048Y464030D01*
X285978Y463953D01*
X286908Y464030D01*
X287735Y464260D01*
X288355Y464567D01*
X288871Y465027D01*
X289078Y465640D01*
X288871Y466253D01*
X288355Y466713D01*
X287735Y467020D01*
X286908Y467250D01*
X285978Y467327D01*
X285048Y467250D01*
X284221Y467020D01*
X283601Y466713D01*
X283085Y466253D01*
X282878Y465640D01*
G01X289078Y471840D02*
X288975Y472377D01*
X288665Y472990D01*
X288148Y473373D01*
X287425Y473527D01*
X286701Y473373D01*
X286081Y472913D01*
X285771Y472223D01*
Y471457D01*
X285565Y470997D01*
X285048Y470613D01*
X284325Y470460D01*
X283601Y470690D01*
X283085Y471227D01*
X282878Y471840D01*
X283085Y472453D01*
X283601Y472990D01*
X284325Y473220D01*
X285048Y473067D01*
X285565Y472683D01*
X285771Y472223D01*
Y471457D01*
X286081Y470767D01*
X286701Y470307D01*
X287425Y470153D01*
X288148Y470307D01*
X288665Y470690D01*
X288975Y471303D01*
X289078Y471840D01*
G01X298078Y142105D02*
X291878D01*
Y144021D01*
X292188Y144635D01*
X292601Y145018D01*
X293428Y145171D01*
X294255Y145018D01*
X294771Y144558D01*
X295081Y144021D01*
Y142105D01*
G01Y144021D02*
X298078Y145171D01*
G01Y149838D02*
X291878D01*
X293118Y148918D01*
G01X298078D02*
Y150758D01*
G01Y156038D02*
X297975Y156575D01*
X297665Y157188D01*
X297148Y157571D01*
X296425Y157725D01*
X295701Y157571D01*
X295081Y157111D01*
X294771Y156421D01*
Y155655D01*
X294565Y155195D01*
X294048Y154811D01*
X293325Y154658D01*
X292601Y154888D01*
X292085Y155425D01*
X291878Y156038D01*
X292085Y156651D01*
X292601Y157188D01*
X293325Y157418D01*
X294048Y157265D01*
X294565Y156881D01*
X294771Y156421D01*
Y155655D01*
X295081Y154965D01*
X295701Y154505D01*
X296425Y154351D01*
X297148Y154505D01*
X297665Y154888D01*
X297975Y155501D01*
X298078Y156038D01*
G01Y162238D02*
X297975Y162775D01*
X297665Y163388D01*
X297148Y163771D01*
X296425Y163925D01*
X295701Y163771D01*
X295081Y163311D01*
X294771Y162621D01*
Y161855D01*
X294565Y161395D01*
X294048Y161011D01*
X293325Y160858D01*
X292601Y161088D01*
X292085Y161625D01*
X291878Y162238D01*
X292085Y162851D01*
X292601Y163388D01*
X293325Y163618D01*
X294048Y163465D01*
X294565Y163081D01*
X294771Y162621D01*
Y161855D01*
X295081Y161165D01*
X295701Y160705D01*
X296425Y160551D01*
X297148Y160705D01*
X297665Y161088D01*
X297975Y161701D01*
X298078Y162238D01*
G01X299078Y451707D02*
X292878D01*
Y453623D01*
X293188Y454237D01*
X293601Y454620D01*
X294428Y454773D01*
X295255Y454620D01*
X295771Y454160D01*
X296081Y453623D01*
Y451707D01*
G01Y453623D02*
X299078Y454773D01*
G01X293911Y457983D02*
X293291Y458443D01*
X292981Y458980D01*
X292878Y459593D01*
X293085Y460360D01*
X293601Y460897D01*
X294221Y461050D01*
X294841Y460973D01*
X295358Y460667D01*
X296391Y459133D01*
X297115Y458443D01*
X298148Y457983D01*
X299078Y457830D01*
Y461050D01*
G01Y465640D02*
X292878D01*
X294118Y464720D01*
G01X299078D02*
Y466560D01*
G01X292878Y471840D02*
X293085Y471227D01*
X293601Y470767D01*
X294221Y470460D01*
X295048Y470230D01*
X295978Y470153D01*
X296908Y470230D01*
X297735Y470460D01*
X298355Y470767D01*
X298871Y471227D01*
X299078Y471840D01*
X298871Y472453D01*
X298355Y472913D01*
X297735Y473220D01*
X296908Y473450D01*
X295978Y473527D01*
X295048Y473450D01*
X294221Y473220D01*
X293601Y472913D01*
X293085Y472453D01*
X292878Y471840D01*
G01X333565Y119921D02*
X333105Y120231D01*
X332568Y120438D01*
X331955D01*
X331265Y120128D01*
X330728Y119611D01*
X330345Y118991D01*
X330038Y117958D01*
X329961Y117028D01*
X330115Y116098D01*
X330345Y115478D01*
X330805Y114858D01*
X331341Y114445D01*
X331878Y114238D01*
X332415D01*
X332951Y114445D01*
X333411Y114755D01*
X333795Y115168D01*
G01X338078Y114238D02*
Y120438D01*
X337158Y119198D01*
G01Y114238D02*
X338998D01*
G01X344278D02*
X344815Y114341D01*
X345428Y114651D01*
X345811Y115168D01*
X345965Y115891D01*
X345811Y116615D01*
X345351Y117235D01*
X344661Y117545D01*
X343895D01*
X343435Y117751D01*
X343051Y118268D01*
X342898Y118991D01*
X343128Y119715D01*
X343665Y120231D01*
X344278Y120438D01*
X344891Y120231D01*
X345428Y119715D01*
X345658Y118991D01*
X345505Y118268D01*
X345121Y117751D01*
X344661Y117545D01*
X343895D01*
X343205Y117235D01*
X342745Y116615D01*
X342591Y115891D01*
X342745Y115168D01*
X343128Y114651D01*
X343741Y114341D01*
X344278Y114238D01*
G01X350478D02*
Y120438D01*
X349558Y119198D01*
G01Y114238D02*
X351398D01*
G01X337745Y314438D02*
Y320638D01*
X339661D01*
X340275Y320328D01*
X340658Y319915D01*
X340811Y319088D01*
X340658Y318261D01*
X340198Y317745D01*
X339661Y317435D01*
X337745D01*
G01X339661D02*
X340811Y314438D01*
G01X344021Y319605D02*
X344481Y320225D01*
X345018Y320535D01*
X345631Y320638D01*
X346398Y320431D01*
X346935Y319915D01*
X347088Y319295D01*
X347011Y318675D01*
X346705Y318158D01*
X345171Y317125D01*
X344481Y316401D01*
X344021Y315368D01*
X343868Y314438D01*
X347088D01*
G01X350221Y317021D02*
X350758Y317745D01*
X351218Y318158D01*
X351831Y318365D01*
X352368Y318158D01*
X352751Y317745D01*
X353058Y317125D01*
X353135Y316401D01*
X353058Y315781D01*
X352751Y315161D01*
X352291Y314645D01*
X351755Y314438D01*
X351141Y314645D01*
X350605Y315264D01*
X350298Y316195D01*
X350221Y317228D01*
X350375Y318571D01*
X350605Y319295D01*
X350988Y320018D01*
X351525Y320535D01*
X352061Y320638D01*
X352598Y320431D01*
X352981Y319915D01*
G01X356575Y315161D02*
X357111Y314645D01*
X357725Y314438D01*
X358338Y314645D01*
X358875Y315264D01*
X359258Y316195D01*
X359411Y317125D01*
Y318261D01*
X359258Y319191D01*
X358875Y320018D01*
X358415Y320431D01*
X357878Y320638D01*
X357265Y320431D01*
X356805Y320018D01*
X356498Y319398D01*
X356345Y318571D01*
X356498Y317848D01*
X356881Y317125D01*
X357341Y316711D01*
X357878Y316608D01*
X358491Y316815D01*
X358951Y317331D01*
X359411Y318261D01*
G01X330995Y397025D02*
X330685Y396565D01*
X330478Y396028D01*
Y395415D01*
X330788Y394725D01*
X331305Y394188D01*
X331925Y393805D01*
X332958Y393498D01*
X333888Y393421D01*
X334818Y393575D01*
X335438Y393805D01*
X336058Y394265D01*
X336471Y394801D01*
X336678Y395338D01*
Y395875D01*
X336471Y396411D01*
X336161Y396871D01*
X335748Y397255D01*
G01X336678Y401385D02*
X335335Y401538D01*
X334198Y401768D01*
X333165Y402075D01*
X332028Y402458D01*
X330478Y403071D01*
Y400005D01*
G01X335438Y406051D02*
X336161Y406511D01*
X336575Y407125D01*
X336678Y407815D01*
X336575Y408428D01*
X336058Y409041D01*
X335438Y409425D01*
X334818Y409501D01*
X334095Y409348D01*
X333578Y408811D01*
X333371Y408275D01*
Y407585D01*
G01Y408275D02*
X333061Y408735D01*
X332545Y409118D01*
X331925Y409271D01*
X331305Y409118D01*
X330788Y408735D01*
X330478Y408045D01*
X330581Y407355D01*
X330995Y406665D01*
G01X340995Y397025D02*
X340685Y396565D01*
X340478Y396028D01*
Y395415D01*
X340788Y394725D01*
X341305Y394188D01*
X341925Y393805D01*
X342958Y393498D01*
X343888Y393421D01*
X344818Y393575D01*
X345438Y393805D01*
X346058Y394265D01*
X346471Y394801D01*
X346678Y395338D01*
Y395875D01*
X346471Y396411D01*
X346161Y396871D01*
X345748Y397255D01*
G01X346678Y401385D02*
X345335Y401538D01*
X344198Y401768D01*
X343165Y402075D01*
X342028Y402458D01*
X340478Y403071D01*
Y400005D01*
G01X346678Y407738D02*
X346575Y408275D01*
X346265Y408888D01*
X345748Y409271D01*
X345025Y409425D01*
X344301Y409271D01*
X343681Y408811D01*
X343371Y408121D01*
Y407355D01*
X343165Y406895D01*
X342648Y406511D01*
X341925Y406358D01*
X341201Y406588D01*
X340685Y407125D01*
X340478Y407738D01*
X340685Y408351D01*
X341201Y408888D01*
X341925Y409118D01*
X342648Y408965D01*
X343165Y408581D01*
X343371Y408121D01*
Y407355D01*
X343681Y406665D01*
X344301Y406205D01*
X345025Y406051D01*
X345748Y406205D01*
X346265Y406588D01*
X346575Y407201D01*
X346678Y407738D01*
G01X349765Y-118279D02*
X349305Y-117969D01*
X348768Y-117762D01*
X348155D01*
X347465Y-118072D01*
X346928Y-118589D01*
X346545Y-119209D01*
X346238Y-120242D01*
X346161Y-121172D01*
X346315Y-122102D01*
X346545Y-122722D01*
X347005Y-123342D01*
X347541Y-123755D01*
X348078Y-123962D01*
X348615D01*
X349151Y-123755D01*
X349611Y-123445D01*
X349995Y-123032D01*
G01X354278Y-123962D02*
Y-117762D01*
X353358Y-119002D01*
G01Y-123962D02*
X355198D01*
G01X359021Y-121379D02*
X359558Y-120655D01*
X360018Y-120242D01*
X360631Y-120035D01*
X361168Y-120242D01*
X361551Y-120655D01*
X361858Y-121275D01*
X361935Y-121999D01*
X361858Y-122619D01*
X361551Y-123239D01*
X361091Y-123755D01*
X360555Y-123962D01*
X359941Y-123755D01*
X359405Y-123136D01*
X359098Y-122205D01*
X359021Y-121172D01*
X359175Y-119829D01*
X359405Y-119105D01*
X359788Y-118382D01*
X360325Y-117865D01*
X360861Y-117762D01*
X361398Y-117969D01*
X361781Y-118485D01*
G01X366678Y-123962D02*
X367215Y-123859D01*
X367828Y-123549D01*
X368211Y-123032D01*
X368365Y-122309D01*
X368211Y-121585D01*
X367751Y-120965D01*
X367061Y-120655D01*
X366295D01*
X365835Y-120449D01*
X365451Y-119932D01*
X365298Y-119209D01*
X365528Y-118485D01*
X366065Y-117969D01*
X366678Y-117762D01*
X367291Y-117969D01*
X367828Y-118485D01*
X368058Y-119209D01*
X367905Y-119932D01*
X367521Y-120449D01*
X367061Y-120655D01*
X366295D01*
X365605Y-120965D01*
X365145Y-121585D01*
X364991Y-122309D01*
X365145Y-123032D01*
X365528Y-123549D01*
X366141Y-123859D01*
X366678Y-123962D01*
G01X358745Y-50562D02*
Y-44362D01*
X360661D01*
X361275Y-44672D01*
X361658Y-45085D01*
X361811Y-45912D01*
X361658Y-46739D01*
X361198Y-47255D01*
X360661Y-47565D01*
X358745D01*
G01X360661D02*
X361811Y-50562D01*
G01X365021Y-45395D02*
X365481Y-44775D01*
X366018Y-44465D01*
X366631Y-44362D01*
X367398Y-44569D01*
X367935Y-45085D01*
X368088Y-45705D01*
X368011Y-46325D01*
X367705Y-46842D01*
X366171Y-47875D01*
X365481Y-48599D01*
X365021Y-49632D01*
X364868Y-50562D01*
X368088D01*
G01X372678D02*
Y-44362D01*
X371758Y-45602D01*
G01Y-50562D02*
X373598D01*
G01X378725D02*
X378878Y-49219D01*
X379108Y-48082D01*
X379415Y-47049D01*
X379798Y-45912D01*
X380411Y-44362D01*
X377345D01*
G01X358745Y-41562D02*
Y-35362D01*
X360661D01*
X361275Y-35672D01*
X361658Y-36085D01*
X361811Y-36912D01*
X361658Y-37739D01*
X361198Y-38255D01*
X360661Y-38565D01*
X358745D01*
G01X360661D02*
X361811Y-41562D01*
G01X365021Y-36395D02*
X365481Y-35775D01*
X366018Y-35465D01*
X366631Y-35362D01*
X367398Y-35569D01*
X367935Y-36085D01*
X368088Y-36705D01*
X368011Y-37325D01*
X367705Y-37842D01*
X366171Y-38875D01*
X365481Y-39599D01*
X365021Y-40632D01*
X364868Y-41562D01*
X368088D01*
G01X372678D02*
Y-35362D01*
X371758Y-36602D01*
G01Y-41562D02*
X373598D01*
G01X378878D02*
X379415Y-41459D01*
X380028Y-41149D01*
X380411Y-40632D01*
X380565Y-39909D01*
X380411Y-39185D01*
X379951Y-38565D01*
X379261Y-38255D01*
X378495D01*
X378035Y-38049D01*
X377651Y-37532D01*
X377498Y-36809D01*
X377728Y-36085D01*
X378265Y-35569D01*
X378878Y-35362D01*
X379491Y-35569D01*
X380028Y-36085D01*
X380258Y-36809D01*
X380105Y-37532D01*
X379721Y-38049D01*
X379261Y-38255D01*
X378495D01*
X377805Y-38565D01*
X377345Y-39185D01*
X377191Y-39909D01*
X377345Y-40632D01*
X377728Y-41149D01*
X378341Y-41459D01*
X378878Y-41562D01*
G01X358745Y-14562D02*
Y-8362D01*
X360661D01*
X361275Y-8672D01*
X361658Y-9085D01*
X361811Y-9912D01*
X361658Y-10739D01*
X361198Y-11255D01*
X360661Y-11565D01*
X358745D01*
G01X360661D02*
X361811Y-14562D01*
G01X366478D02*
Y-8362D01*
X365558Y-9602D01*
G01Y-14562D02*
X367398D01*
G01X371375Y-13839D02*
X371911Y-14355D01*
X372525Y-14562D01*
X373138Y-14355D01*
X373675Y-13736D01*
X374058Y-12805D01*
X374211Y-11875D01*
Y-10739D01*
X374058Y-9809D01*
X373675Y-8982D01*
X373215Y-8569D01*
X372678Y-8362D01*
X372065Y-8569D01*
X371605Y-8982D01*
X371298Y-9602D01*
X371145Y-10429D01*
X371298Y-11152D01*
X371681Y-11875D01*
X372141Y-12289D01*
X372678Y-12392D01*
X373291Y-12185D01*
X373751Y-11669D01*
X374211Y-10739D01*
G01X377191Y-13632D02*
X377651Y-14149D01*
X378188Y-14459D01*
X378878Y-14562D01*
X379568Y-14355D01*
X380105Y-13942D01*
X380488Y-13219D01*
X380565Y-12392D01*
X380411Y-11565D01*
X380028Y-11049D01*
X379491Y-10635D01*
X378955Y-10532D01*
X378418Y-10635D01*
X377728Y-11049D01*
X377958Y-8362D01*
X380028D01*
G01X358745Y-23562D02*
Y-17362D01*
X360661D01*
X361275Y-17672D01*
X361658Y-18085D01*
X361811Y-18912D01*
X361658Y-19739D01*
X361198Y-20255D01*
X360661Y-20565D01*
X358745D01*
G01X360661D02*
X361811Y-23562D01*
G01X365021Y-18395D02*
X365481Y-17775D01*
X366018Y-17465D01*
X366631Y-17362D01*
X367398Y-17569D01*
X367935Y-18085D01*
X368088Y-18705D01*
X368011Y-19325D01*
X367705Y-19842D01*
X366171Y-20875D01*
X365481Y-21599D01*
X365021Y-22632D01*
X364868Y-23562D01*
X368088D01*
G01X372678Y-17362D02*
X372065Y-17569D01*
X371605Y-18085D01*
X371298Y-18705D01*
X371068Y-19532D01*
X370991Y-20462D01*
X371068Y-21392D01*
X371298Y-22219D01*
X371605Y-22839D01*
X372065Y-23355D01*
X372678Y-23562D01*
X373291Y-23355D01*
X373751Y-22839D01*
X374058Y-22219D01*
X374288Y-21392D01*
X374365Y-20462D01*
X374288Y-19532D01*
X374058Y-18705D01*
X373751Y-18085D01*
X373291Y-17569D01*
X372678Y-17362D01*
G01X377575Y-22839D02*
X378111Y-23355D01*
X378725Y-23562D01*
X379338Y-23355D01*
X379875Y-22736D01*
X380258Y-21805D01*
X380411Y-20875D01*
Y-19739D01*
X380258Y-18809D01*
X379875Y-17982D01*
X379415Y-17569D01*
X378878Y-17362D01*
X378265Y-17569D01*
X377805Y-17982D01*
X377498Y-18602D01*
X377345Y-19429D01*
X377498Y-20152D01*
X377881Y-20875D01*
X378341Y-21289D01*
X378878Y-21392D01*
X379491Y-21185D01*
X379951Y-20669D01*
X380411Y-19739D01*
G01X358745Y18438D02*
Y24638D01*
X360661D01*
X361275Y24328D01*
X361658Y23915D01*
X361811Y23088D01*
X361658Y22261D01*
X361198Y21745D01*
X360661Y21435D01*
X358745D01*
G01X360661D02*
X361811Y18438D01*
G01X365021Y23605D02*
X365481Y24225D01*
X366018Y24535D01*
X366631Y24638D01*
X367398Y24431D01*
X367935Y23915D01*
X368088Y23295D01*
X368011Y22675D01*
X367705Y22158D01*
X366171Y21125D01*
X365481Y20401D01*
X365021Y19368D01*
X364868Y18438D01*
X368088D01*
G01X371221Y21021D02*
X371758Y21745D01*
X372218Y22158D01*
X372831Y22365D01*
X373368Y22158D01*
X373751Y21745D01*
X374058Y21125D01*
X374135Y20401D01*
X374058Y19781D01*
X373751Y19161D01*
X373291Y18645D01*
X372755Y18438D01*
X372141Y18645D01*
X371605Y19264D01*
X371298Y20195D01*
X371221Y21228D01*
X371375Y22571D01*
X371605Y23295D01*
X371988Y24018D01*
X372525Y24535D01*
X373061Y24638D01*
X373598Y24431D01*
X373981Y23915D01*
G01X377191Y19368D02*
X377651Y18851D01*
X378188Y18541D01*
X378878Y18438D01*
X379568Y18645D01*
X380105Y19058D01*
X380488Y19781D01*
X380565Y20608D01*
X380411Y21435D01*
X380028Y21951D01*
X379491Y22365D01*
X378955Y22468D01*
X378418Y22365D01*
X377728Y21951D01*
X377958Y24638D01*
X380028D01*
G01X358745Y28438D02*
Y34638D01*
X360661D01*
X361275Y34328D01*
X361658Y33915D01*
X361811Y33088D01*
X361658Y32261D01*
X361198Y31745D01*
X360661Y31435D01*
X358745D01*
G01X360661D02*
X361811Y28438D01*
G01X365021Y33605D02*
X365481Y34225D01*
X366018Y34535D01*
X366631Y34638D01*
X367398Y34431D01*
X367935Y33915D01*
X368088Y33295D01*
X368011Y32675D01*
X367705Y32158D01*
X366171Y31125D01*
X365481Y30401D01*
X365021Y29368D01*
X364868Y28438D01*
X368088D01*
G01X371221Y31021D02*
X371758Y31745D01*
X372218Y32158D01*
X372831Y32365D01*
X373368Y32158D01*
X373751Y31745D01*
X374058Y31125D01*
X374135Y30401D01*
X374058Y29781D01*
X373751Y29161D01*
X373291Y28645D01*
X372755Y28438D01*
X372141Y28645D01*
X371605Y29264D01*
X371298Y30195D01*
X371221Y31228D01*
X371375Y32571D01*
X371605Y33295D01*
X371988Y34018D01*
X372525Y34535D01*
X373061Y34638D01*
X373598Y34431D01*
X373981Y33915D01*
G01X379798Y28438D02*
Y34638D01*
X376961Y30195D01*
X380795D01*
G01X361478Y157105D02*
X355278D01*
Y159021D01*
X355588Y159635D01*
X356001Y160018D01*
X356828Y160171D01*
X357655Y160018D01*
X358171Y159558D01*
X358481Y159021D01*
Y157105D01*
G01Y159021D02*
X361478Y160171D01*
G01Y164838D02*
X355278D01*
X356518Y163918D01*
G01X361478D02*
Y165758D01*
G01Y170885D02*
X360135Y171038D01*
X358998Y171268D01*
X357965Y171575D01*
X356828Y171958D01*
X355278Y172571D01*
Y169505D01*
G01X361478Y178158D02*
X355278D01*
X359721Y175321D01*
Y179155D01*
G01X356678Y325705D02*
X350478D01*
Y327621D01*
X350788Y328235D01*
X351201Y328618D01*
X352028Y328771D01*
X352855Y328618D01*
X353371Y328158D01*
X353681Y327621D01*
Y325705D01*
G01Y327621D02*
X356678Y328771D01*
G01Y333438D02*
X350478D01*
X351718Y332518D01*
G01X356678D02*
Y334358D01*
G01X350478Y339638D02*
X350685Y339025D01*
X351201Y338565D01*
X351821Y338258D01*
X352648Y338028D01*
X353578Y337951D01*
X354508Y338028D01*
X355335Y338258D01*
X355955Y338565D01*
X356471Y339025D01*
X356678Y339638D01*
X356471Y340251D01*
X355955Y340711D01*
X355335Y341018D01*
X354508Y341248D01*
X353578Y341325D01*
X352648Y341248D01*
X351821Y341018D01*
X351201Y340711D01*
X350685Y340251D01*
X350478Y339638D01*
G01X355955Y344535D02*
X356471Y345071D01*
X356678Y345685D01*
X356471Y346298D01*
X355852Y346835D01*
X354921Y347218D01*
X353991Y347371D01*
X352855D01*
X351925Y347218D01*
X351098Y346835D01*
X350685Y346375D01*
X350478Y345838D01*
X350685Y345225D01*
X351098Y344765D01*
X351718Y344458D01*
X352545Y344305D01*
X353268Y344458D01*
X353991Y344841D01*
X354405Y345301D01*
X354508Y345838D01*
X354301Y346451D01*
X353785Y346911D01*
X352855Y347371D01*
G01X361845Y-4530D02*
Y1670D01*
X363761D01*
X364375Y1360D01*
X364758Y947D01*
X364911Y120D01*
X364758Y-707D01*
X364298Y-1223D01*
X363761Y-1533D01*
X361845D01*
G01X363761D02*
X364911Y-4530D01*
G01X368275Y-3807D02*
X368811Y-4323D01*
X369425Y-4530D01*
X370038Y-4323D01*
X370575Y-3704D01*
X370958Y-2773D01*
X371111Y-1843D01*
Y-707D01*
X370958Y223D01*
X370575Y1050D01*
X370115Y1463D01*
X369578Y1670D01*
X368965Y1463D01*
X368505Y1050D01*
X368198Y430D01*
X368045Y-397D01*
X368198Y-1120D01*
X368581Y-1843D01*
X369041Y-2257D01*
X369578Y-2360D01*
X370191Y-2153D01*
X370651Y-1637D01*
X371111Y-707D01*
G01X374321Y637D02*
X374781Y1257D01*
X375318Y1567D01*
X375931Y1670D01*
X376698Y1463D01*
X377235Y947D01*
X377388Y327D01*
X377311Y-293D01*
X377005Y-810D01*
X375471Y-1843D01*
X374781Y-2567D01*
X374321Y-3600D01*
X374168Y-4530D01*
X377388D01*
G01X366678Y325705D02*
X360478D01*
Y327621D01*
X360788Y328235D01*
X361201Y328618D01*
X362028Y328771D01*
X362855Y328618D01*
X363371Y328158D01*
X363681Y327621D01*
Y325705D01*
G01Y327621D02*
X366678Y328771D01*
G01Y333438D02*
X360478D01*
X361718Y332518D01*
G01X366678D02*
Y334358D01*
G01Y339638D02*
X360478D01*
X361718Y338718D01*
G01X366678D02*
Y340558D01*
G01X360478Y345838D02*
X360685Y345225D01*
X361201Y344765D01*
X361821Y344458D01*
X362648Y344228D01*
X363578Y344151D01*
X364508Y344228D01*
X365335Y344458D01*
X365955Y344765D01*
X366471Y345225D01*
X366678Y345838D01*
X366471Y346451D01*
X365955Y346911D01*
X365335Y347218D01*
X364508Y347448D01*
X363578Y347525D01*
X362648Y347448D01*
X361821Y347218D01*
X361201Y346911D01*
X360685Y346451D01*
X360478Y345838D01*
G01X376678Y325705D02*
X370478D01*
Y327621D01*
X370788Y328235D01*
X371201Y328618D01*
X372028Y328771D01*
X372855Y328618D01*
X373371Y328158D01*
X373681Y327621D01*
Y325705D01*
G01Y327621D02*
X376678Y328771D01*
G01Y333438D02*
X370478D01*
X371718Y332518D01*
G01X376678D02*
Y334358D01*
G01Y339638D02*
X370478D01*
X371718Y338718D01*
G01X376678D02*
Y340558D01*
G01Y345838D02*
X370478D01*
X371718Y344918D01*
G01X376678D02*
Y346758D01*
G01X391995Y-12653D02*
X391685Y-13113D01*
X391478Y-13650D01*
Y-14263D01*
X391788Y-14953D01*
X392305Y-15490D01*
X392925Y-15873D01*
X393958Y-16180D01*
X394888Y-16257D01*
X395818Y-16103D01*
X396438Y-15873D01*
X397058Y-15413D01*
X397471Y-14877D01*
X397678Y-14340D01*
Y-13803D01*
X397471Y-13267D01*
X397161Y-12807D01*
X396748Y-12423D01*
G01X397678Y-8140D02*
X391478D01*
X392718Y-9060D01*
G01X397678D02*
Y-7220D01*
G01Y-1020D02*
X391478D01*
X395921Y-3857D01*
Y-23D01*
G01X396748Y2573D02*
X397265Y3033D01*
X397575Y3570D01*
X397678Y4260D01*
X397471Y4950D01*
X397058Y5487D01*
X396335Y5870D01*
X395508Y5947D01*
X394681Y5793D01*
X394165Y5410D01*
X393751Y4873D01*
X393648Y4337D01*
X393751Y3800D01*
X394165Y3110D01*
X391478Y3340D01*
Y5410D01*
G01X395349Y29303D02*
X394889Y29613D01*
X394352Y29820D01*
X393739D01*
X393049Y29510D01*
X392512Y28993D01*
X392129Y28373D01*
X391822Y27340D01*
X391745Y26410D01*
X391899Y25480D01*
X392129Y24860D01*
X392589Y24240D01*
X393125Y23827D01*
X393662Y23620D01*
X394199D01*
X394735Y23827D01*
X395195Y24137D01*
X395579Y24550D01*
G01X399862Y23620D02*
Y29820D01*
X398942Y28580D01*
G01Y23620D02*
X400782D01*
G01X406062Y29820D02*
X405449Y29613D01*
X404989Y29097D01*
X404682Y28477D01*
X404452Y27650D01*
X404375Y26720D01*
X404452Y25790D01*
X404682Y24963D01*
X404989Y24343D01*
X405449Y23827D01*
X406062Y23620D01*
X406675Y23827D01*
X407135Y24343D01*
X407442Y24963D01*
X407672Y25790D01*
X407749Y26720D01*
X407672Y27650D01*
X407442Y28477D01*
X407135Y29097D01*
X406675Y29613D01*
X406062Y29820D01*
G01X410575Y24860D02*
X411035Y24137D01*
X411649Y23723D01*
X412339Y23620D01*
X412952Y23723D01*
X413565Y24240D01*
X413949Y24860D01*
X414025Y25480D01*
X413872Y26203D01*
X413335Y26720D01*
X412799Y26927D01*
X412109D01*
G01X412799D02*
X413259Y27237D01*
X413642Y27753D01*
X413795Y28373D01*
X413642Y28993D01*
X413259Y29510D01*
X412569Y29820D01*
X411879Y29717D01*
X411189Y29303D01*
G01X396745Y-192530D02*
Y-186330D01*
X398661D01*
X399275Y-186640D01*
X399658Y-187053D01*
X399811Y-187880D01*
X399658Y-188707D01*
X399198Y-189223D01*
X398661Y-189533D01*
X396745D01*
G01X398661D02*
X399811Y-192530D01*
G01X405398D02*
Y-186330D01*
X402561Y-190773D01*
X406395D01*
G01X410678Y-192530D02*
X411215Y-192427D01*
X411828Y-192117D01*
X412211Y-191600D01*
X412365Y-190877D01*
X412211Y-190153D01*
X411751Y-189533D01*
X411061Y-189223D01*
X410295D01*
X409835Y-189017D01*
X409451Y-188500D01*
X409298Y-187777D01*
X409528Y-187053D01*
X410065Y-186537D01*
X410678Y-186330D01*
X411291Y-186537D01*
X411828Y-187053D01*
X412058Y-187777D01*
X411905Y-188500D01*
X411521Y-189017D01*
X411061Y-189223D01*
X410295D01*
X409605Y-189533D01*
X409145Y-190153D01*
X408991Y-190877D01*
X409145Y-191600D01*
X409528Y-192117D01*
X410141Y-192427D01*
X410678Y-192530D01*
G01X415191Y-191290D02*
X415651Y-192013D01*
X416265Y-192427D01*
X416955Y-192530D01*
X417568Y-192427D01*
X418181Y-191910D01*
X418565Y-191290D01*
X418641Y-190670D01*
X418488Y-189947D01*
X417951Y-189430D01*
X417415Y-189223D01*
X416725D01*
G01X417415D02*
X417875Y-188913D01*
X418258Y-188397D01*
X418411Y-187777D01*
X418258Y-187157D01*
X417875Y-186640D01*
X417185Y-186330D01*
X416495Y-186433D01*
X415805Y-186847D01*
G01X396745Y-182530D02*
Y-176330D01*
X398661D01*
X399275Y-176640D01*
X399658Y-177053D01*
X399811Y-177880D01*
X399658Y-178707D01*
X399198Y-179223D01*
X398661Y-179533D01*
X396745D01*
G01X398661D02*
X399811Y-182530D01*
G01X405398D02*
Y-176330D01*
X402561Y-180773D01*
X406395D01*
G01X410678Y-182530D02*
X411215Y-182427D01*
X411828Y-182117D01*
X412211Y-181600D01*
X412365Y-180877D01*
X412211Y-180153D01*
X411751Y-179533D01*
X411061Y-179223D01*
X410295D01*
X409835Y-179017D01*
X409451Y-178500D01*
X409298Y-177777D01*
X409528Y-177053D01*
X410065Y-176537D01*
X410678Y-176330D01*
X411291Y-176537D01*
X411828Y-177053D01*
X412058Y-177777D01*
X411905Y-178500D01*
X411521Y-179017D01*
X411061Y-179223D01*
X410295D01*
X409605Y-179533D01*
X409145Y-180153D01*
X408991Y-180877D01*
X409145Y-181600D01*
X409528Y-182117D01*
X410141Y-182427D01*
X410678Y-182530D01*
G01X415421Y-177363D02*
X415881Y-176743D01*
X416418Y-176433D01*
X417031Y-176330D01*
X417798Y-176537D01*
X418335Y-177053D01*
X418488Y-177673D01*
X418411Y-178293D01*
X418105Y-178810D01*
X416571Y-179843D01*
X415881Y-180567D01*
X415421Y-181600D01*
X415268Y-182530D01*
X418488D01*
G01X394663Y-99403D02*
X394353Y-99863D01*
X394146Y-100400D01*
Y-101013D01*
X394456Y-101703D01*
X394973Y-102240D01*
X395593Y-102623D01*
X396626Y-102930D01*
X397556Y-103007D01*
X398486Y-102853D01*
X399106Y-102623D01*
X399726Y-102163D01*
X400139Y-101627D01*
X400346Y-101090D01*
Y-100553D01*
X400139Y-100017D01*
X399829Y-99557D01*
X399416Y-99173D01*
G01X400346Y-94890D02*
X394146D01*
X395386Y-95810D01*
G01X400346D02*
Y-93970D01*
G01X395179Y-90147D02*
X394559Y-89687D01*
X394249Y-89150D01*
X394146Y-88537D01*
X394353Y-87770D01*
X394869Y-87233D01*
X395489Y-87080D01*
X396109Y-87157D01*
X396626Y-87463D01*
X397659Y-88997D01*
X398383Y-89687D01*
X399416Y-90147D01*
X400346Y-90300D01*
Y-87080D01*
G01X395179Y-83947D02*
X394559Y-83487D01*
X394249Y-82950D01*
X394146Y-82337D01*
X394353Y-81570D01*
X394869Y-81033D01*
X395489Y-80880D01*
X396109Y-80957D01*
X396626Y-81263D01*
X397659Y-82797D01*
X398383Y-83487D01*
X399416Y-83947D01*
X400346Y-84100D01*
Y-80880D01*
G01X408151Y-57879D02*
X407831Y-57629D01*
X407458Y-57462D01*
X407031D01*
X406551Y-57712D01*
X406178Y-58129D01*
X405911Y-58629D01*
X405698Y-59462D01*
X405645Y-60212D01*
X405751Y-60962D01*
X405911Y-61462D01*
X406231Y-61962D01*
X406605Y-62295D01*
X406978Y-62462D01*
X407351D01*
X407725Y-62295D01*
X408045Y-62045D01*
X408311Y-61712D01*
G01X411378Y-62462D02*
Y-57462D01*
X410738Y-58462D01*
G01Y-62462D02*
X412018D01*
G01X414605Y-61712D02*
X414925Y-62129D01*
X415298Y-62379D01*
X415778Y-62462D01*
X416258Y-62295D01*
X416631Y-61962D01*
X416898Y-61379D01*
X416951Y-60712D01*
X416845Y-60045D01*
X416578Y-59629D01*
X416205Y-59295D01*
X415831Y-59212D01*
X415458Y-59295D01*
X414978Y-59629D01*
X415138Y-57462D01*
X416578D01*
G01X420178Y-62462D02*
Y-57462D01*
X419538Y-58462D01*
G01Y-62462D02*
X420818D01*
G01X403171Y-38340D02*
Y-33340D01*
X404505D01*
X404931Y-33590D01*
X405198Y-33923D01*
X405305Y-34590D01*
X405198Y-35257D01*
X404878Y-35673D01*
X404505Y-35923D01*
X403171D01*
G01X404505D02*
X405305Y-38340D01*
G01X407465Y-37590D02*
X407785Y-38007D01*
X408158Y-38257D01*
X408638Y-38340D01*
X409118Y-38173D01*
X409491Y-37840D01*
X409758Y-37257D01*
X409811Y-36590D01*
X409705Y-35923D01*
X409438Y-35507D01*
X409065Y-35173D01*
X408691Y-35090D01*
X408318Y-35173D01*
X407838Y-35507D01*
X407998Y-33340D01*
X409438D01*
G01X413038D02*
X412611Y-33507D01*
X412291Y-33923D01*
X412078Y-34423D01*
X411918Y-35090D01*
X411865Y-35840D01*
X411918Y-36590D01*
X412078Y-37257D01*
X412291Y-37757D01*
X412611Y-38173D01*
X413038Y-38340D01*
X413465Y-38173D01*
X413785Y-37757D01*
X413998Y-37257D01*
X414158Y-36590D01*
X414211Y-35840D01*
X414158Y-35090D01*
X413998Y-34423D01*
X413785Y-33923D01*
X413465Y-33507D01*
X413038Y-33340D01*
G01X417438D02*
X417011Y-33507D01*
X416691Y-33923D01*
X416478Y-34423D01*
X416318Y-35090D01*
X416265Y-35840D01*
X416318Y-36590D01*
X416478Y-37257D01*
X416691Y-37757D01*
X417011Y-38173D01*
X417438Y-38340D01*
X417865Y-38173D01*
X418185Y-37757D01*
X418398Y-37257D01*
X418558Y-36590D01*
X418611Y-35840D01*
X418558Y-35090D01*
X418398Y-34423D01*
X418185Y-33923D01*
X417865Y-33507D01*
X417438Y-33340D01*
G01X410911Y-24530D02*
Y-19530D01*
X412245D01*
X412671Y-19780D01*
X412938Y-20113D01*
X413045Y-20780D01*
X412938Y-21447D01*
X412618Y-21863D01*
X412245Y-22113D01*
X410911D01*
G01X412245D02*
X413045Y-24530D01*
G01X415205Y-23780D02*
X415525Y-24197D01*
X415898Y-24447D01*
X416378Y-24530D01*
X416858Y-24363D01*
X417231Y-24030D01*
X417498Y-23447D01*
X417551Y-22780D01*
X417445Y-22113D01*
X417178Y-21697D01*
X416805Y-21363D01*
X416431Y-21280D01*
X416058Y-21363D01*
X415578Y-21697D01*
X415738Y-19530D01*
X417178D01*
G01X420778D02*
X420351Y-19697D01*
X420031Y-20113D01*
X419818Y-20613D01*
X419658Y-21280D01*
X419605Y-22030D01*
X419658Y-22780D01*
X419818Y-23447D01*
X420031Y-23947D01*
X420351Y-24363D01*
X420778Y-24530D01*
X421205Y-24363D01*
X421525Y-23947D01*
X421738Y-23447D01*
X421898Y-22780D01*
X421951Y-22030D01*
X421898Y-21280D01*
X421738Y-20613D01*
X421525Y-20113D01*
X421205Y-19697D01*
X420778Y-19530D01*
G01X425178Y-24530D02*
Y-19530D01*
X424538Y-20530D01*
G01Y-24530D02*
X425818D01*
G01X413283Y-11167D02*
X412963Y-10917D01*
X412590Y-10750D01*
X412163D01*
X411683Y-11000D01*
X411310Y-11417D01*
X411043Y-11917D01*
X410830Y-12750D01*
X410777Y-13500D01*
X410883Y-14250D01*
X411043Y-14750D01*
X411363Y-15250D01*
X411737Y-15583D01*
X412110Y-15750D01*
X412483D01*
X412857Y-15583D01*
X413177Y-15333D01*
X413443Y-15000D01*
G01X416510Y-15750D02*
Y-10750D01*
X415870Y-11750D01*
G01Y-15750D02*
X417150D01*
G01X419737Y-14750D02*
X420057Y-15333D01*
X420483Y-15667D01*
X420963Y-15750D01*
X421390Y-15667D01*
X421817Y-15250D01*
X422083Y-14750D01*
X422137Y-14250D01*
X422030Y-13667D01*
X421657Y-13250D01*
X421283Y-13083D01*
X420803D01*
G01X421283D02*
X421603Y-12833D01*
X421870Y-12417D01*
X421977Y-11917D01*
X421870Y-11417D01*
X421603Y-11000D01*
X421123Y-10750D01*
X420643Y-10833D01*
X420163Y-11167D01*
G01X424403Y-15167D02*
X424777Y-15583D01*
X425203Y-15750D01*
X425630Y-15583D01*
X426003Y-15083D01*
X426270Y-14333D01*
X426377Y-13583D01*
Y-12667D01*
X426270Y-11917D01*
X426003Y-11250D01*
X425683Y-10917D01*
X425310Y-10750D01*
X424883Y-10917D01*
X424563Y-11250D01*
X424350Y-11750D01*
X424243Y-12417D01*
X424350Y-13000D01*
X424617Y-13583D01*
X424937Y-13917D01*
X425310Y-14000D01*
X425737Y-13833D01*
X426057Y-13417D01*
X426377Y-12667D01*
G01X400745Y39438D02*
Y45638D01*
X402661D01*
X403275Y45328D01*
X403658Y44915D01*
X403811Y44088D01*
X403658Y43261D01*
X403198Y42745D01*
X402661Y42435D01*
X400745D01*
G01X402661D02*
X403811Y39438D01*
G01X406791Y40368D02*
X407251Y39851D01*
X407788Y39541D01*
X408478Y39438D01*
X409168Y39645D01*
X409705Y40058D01*
X410088Y40781D01*
X410165Y41608D01*
X410011Y42435D01*
X409628Y42951D01*
X409091Y43365D01*
X408555Y43468D01*
X408018Y43365D01*
X407328Y42951D01*
X407558Y45638D01*
X409628D01*
G01X414678D02*
X414065Y45431D01*
X413605Y44915D01*
X413298Y44295D01*
X413068Y43468D01*
X412991Y42538D01*
X413068Y41608D01*
X413298Y40781D01*
X413605Y40161D01*
X414065Y39645D01*
X414678Y39438D01*
X415291Y39645D01*
X415751Y40161D01*
X416058Y40781D01*
X416288Y41608D01*
X416365Y42538D01*
X416288Y43468D01*
X416058Y44295D01*
X415751Y44915D01*
X415291Y45431D01*
X414678Y45638D01*
G01X419191Y40678D02*
X419651Y39955D01*
X420265Y39541D01*
X420955Y39438D01*
X421568Y39541D01*
X422181Y40058D01*
X422565Y40678D01*
X422641Y41298D01*
X422488Y42021D01*
X421951Y42538D01*
X421415Y42745D01*
X420725D01*
G01X421415D02*
X421875Y43055D01*
X422258Y43571D01*
X422411Y44191D01*
X422258Y44811D01*
X421875Y45328D01*
X421185Y45638D01*
X420495Y45535D01*
X419805Y45121D01*
G01X408968Y49447D02*
X402768D01*
Y51363D01*
X403078Y51977D01*
X403491Y52360D01*
X404318Y52513D01*
X405145Y52360D01*
X405661Y51900D01*
X405971Y51363D01*
Y49447D01*
G01Y51363D02*
X408968Y52513D01*
G01X408038Y55493D02*
X408555Y55953D01*
X408865Y56490D01*
X408968Y57180D01*
X408761Y57870D01*
X408348Y58407D01*
X407625Y58790D01*
X406798Y58867D01*
X405971Y58713D01*
X405455Y58330D01*
X405041Y57793D01*
X404938Y57257D01*
X405041Y56720D01*
X405455Y56030D01*
X402768Y56260D01*
Y58330D01*
G01Y63380D02*
X402975Y62767D01*
X403491Y62307D01*
X404111Y62000D01*
X404938Y61770D01*
X405868Y61693D01*
X406798Y61770D01*
X407625Y62000D01*
X408245Y62307D01*
X408761Y62767D01*
X408968Y63380D01*
X408761Y63993D01*
X408245Y64453D01*
X407625Y64760D01*
X406798Y64990D01*
X405868Y65067D01*
X404938Y64990D01*
X404111Y64760D01*
X403491Y64453D01*
X402975Y63993D01*
X402768Y63380D01*
G01X408968Y70500D02*
X402768D01*
X407211Y67663D01*
Y71497D01*
G01X395745Y333538D02*
Y339738D01*
X397661D01*
X398275Y339428D01*
X398658Y339015D01*
X398811Y338188D01*
X398658Y337361D01*
X398198Y336845D01*
X397661Y336535D01*
X395745D01*
G01X397661D02*
X398811Y333538D01*
G01X403478D02*
Y339738D01*
X402558Y338498D01*
G01Y333538D02*
X404398D01*
G01X409678D02*
Y339738D01*
X408758Y338498D01*
G01Y333538D02*
X410598D01*
G01X414191Y334468D02*
X414651Y333951D01*
X415188Y333641D01*
X415878Y333538D01*
X416568Y333745D01*
X417105Y334158D01*
X417488Y334881D01*
X417565Y335708D01*
X417411Y336535D01*
X417028Y337051D01*
X416491Y337465D01*
X415955Y337568D01*
X415418Y337465D01*
X414728Y337051D01*
X414958Y339738D01*
X417028D01*
G01X415753Y-117082D02*
Y-110882D01*
X417669D01*
X418283Y-111192D01*
X418666Y-111605D01*
X418819Y-112432D01*
X418666Y-113259D01*
X418206Y-113775D01*
X417669Y-114085D01*
X415753D01*
G01X417669D02*
X418819Y-117082D01*
G01X422029Y-111915D02*
X422489Y-111295D01*
X423026Y-110985D01*
X423639Y-110882D01*
X424406Y-111089D01*
X424943Y-111605D01*
X425096Y-112225D01*
X425019Y-112845D01*
X424713Y-113362D01*
X423179Y-114395D01*
X422489Y-115119D01*
X422029Y-116152D01*
X421876Y-117082D01*
X425096D01*
G01X429533D02*
X429686Y-115739D01*
X429916Y-114602D01*
X430223Y-113569D01*
X430606Y-112432D01*
X431219Y-110882D01*
X428153D01*
G01X434199Y-116152D02*
X434659Y-116669D01*
X435196Y-116979D01*
X435886Y-117082D01*
X436576Y-116875D01*
X437113Y-116462D01*
X437496Y-115739D01*
X437573Y-114912D01*
X437419Y-114085D01*
X437036Y-113569D01*
X436499Y-113155D01*
X435963Y-113052D01*
X435426Y-113155D01*
X434736Y-113569D01*
X434966Y-110882D01*
X437036D01*
G01X423151Y-89879D02*
X422831Y-89629D01*
X422458Y-89462D01*
X422031D01*
X421551Y-89712D01*
X421178Y-90129D01*
X420911Y-90629D01*
X420698Y-91462D01*
X420645Y-92212D01*
X420751Y-92962D01*
X420911Y-93462D01*
X421231Y-93962D01*
X421605Y-94295D01*
X421978Y-94462D01*
X422351D01*
X422725Y-94295D01*
X423045Y-94045D01*
X423311Y-93712D01*
G01X426378Y-94462D02*
Y-89462D01*
X425738Y-90462D01*
G01Y-94462D02*
X427018D01*
G01X429765Y-90295D02*
X430085Y-89795D01*
X430458Y-89545D01*
X430885Y-89462D01*
X431418Y-89629D01*
X431791Y-90045D01*
X431898Y-90545D01*
X431845Y-91045D01*
X431631Y-91462D01*
X430565Y-92295D01*
X430085Y-92879D01*
X429765Y-93712D01*
X429658Y-94462D01*
X431898D01*
G01X435071D02*
X435178Y-93379D01*
X435338Y-92462D01*
X435551Y-91629D01*
X435818Y-90712D01*
X436245Y-89462D01*
X434111D01*
G01X423151Y-34379D02*
X422831Y-34129D01*
X422458Y-33962D01*
X422031D01*
X421551Y-34212D01*
X421178Y-34629D01*
X420911Y-35129D01*
X420698Y-35962D01*
X420645Y-36712D01*
X420751Y-37462D01*
X420911Y-37962D01*
X421231Y-38462D01*
X421605Y-38795D01*
X421978Y-38962D01*
X422351D01*
X422725Y-38795D01*
X423045Y-38545D01*
X423311Y-38212D01*
G01X425365Y-34795D02*
X425685Y-34295D01*
X426058Y-34045D01*
X426485Y-33962D01*
X427018Y-34129D01*
X427391Y-34545D01*
X427498Y-35045D01*
X427445Y-35545D01*
X427231Y-35962D01*
X426165Y-36795D01*
X425685Y-37379D01*
X425365Y-38212D01*
X425258Y-38962D01*
X427498D01*
G01X430778D02*
Y-33962D01*
X430138Y-34962D01*
G01Y-38962D02*
X431418D01*
G01X435178Y-33962D02*
X434751Y-34129D01*
X434431Y-34545D01*
X434218Y-35045D01*
X434058Y-35712D01*
X434005Y-36462D01*
X434058Y-37212D01*
X434218Y-37879D01*
X434431Y-38379D01*
X434751Y-38795D01*
X435178Y-38962D01*
X435605Y-38795D01*
X435925Y-38379D01*
X436138Y-37879D01*
X436298Y-37212D01*
X436351Y-36462D01*
X436298Y-35712D01*
X436138Y-35045D01*
X435925Y-34545D01*
X435605Y-34129D01*
X435178Y-33962D01*
G01X419495Y-6889D02*
X419245Y-7209D01*
X419078Y-7582D01*
Y-8009D01*
X419328Y-8489D01*
X419745Y-8862D01*
X420245Y-9129D01*
X421078Y-9342D01*
X421828Y-9395D01*
X422578Y-9289D01*
X423078Y-9129D01*
X423578Y-8809D01*
X423911Y-8435D01*
X424078Y-8062D01*
Y-7689D01*
X423911Y-7315D01*
X423661Y-6995D01*
X423328Y-6729D01*
G01X419911Y-4675D02*
X419411Y-4355D01*
X419161Y-3982D01*
X419078Y-3555D01*
X419245Y-3022D01*
X419661Y-2649D01*
X420161Y-2542D01*
X420661Y-2595D01*
X421078Y-2809D01*
X421911Y-3875D01*
X422495Y-4355D01*
X423328Y-4675D01*
X424078Y-4782D01*
Y-2542D01*
G01X419078Y738D02*
X419245Y311D01*
X419661Y-9D01*
X420161Y-222D01*
X420828Y-382D01*
X421578Y-435D01*
X422328Y-382D01*
X422995Y-222D01*
X423495Y-9D01*
X423911Y311D01*
X424078Y738D01*
X423911Y1165D01*
X423495Y1485D01*
X422995Y1698D01*
X422328Y1858D01*
X421578Y1911D01*
X420828Y1858D01*
X420161Y1698D01*
X419661Y1485D01*
X419245Y1165D01*
X419078Y738D01*
G01X419911Y4125D02*
X419411Y4445D01*
X419161Y4818D01*
X419078Y5245D01*
X419245Y5778D01*
X419661Y6151D01*
X420161Y6258D01*
X420661Y6205D01*
X421078Y5991D01*
X421911Y4925D01*
X422495Y4445D01*
X423328Y4125D01*
X424078Y4018D01*
Y6258D01*
G01X426791Y1030D02*
Y6030D01*
X428125D01*
X428551Y5780D01*
X428818Y5447D01*
X428925Y4780D01*
X428818Y4113D01*
X428498Y3697D01*
X428125Y3447D01*
X426791D01*
G01X428125D02*
X428925Y1030D01*
G01X431245Y5197D02*
X431565Y5697D01*
X431938Y5947D01*
X432365Y6030D01*
X432898Y5863D01*
X433271Y5447D01*
X433378Y4947D01*
X433325Y4447D01*
X433111Y4030D01*
X432045Y3197D01*
X431565Y2613D01*
X431245Y1780D01*
X431138Y1030D01*
X433378D01*
G01X436551D02*
X436658Y2113D01*
X436818Y3030D01*
X437031Y3863D01*
X437298Y4780D01*
X437725Y6030D01*
X435591D01*
G01X441058D02*
X440631Y5863D01*
X440311Y5447D01*
X440098Y4947D01*
X439938Y4280D01*
X439885Y3530D01*
X439938Y2780D01*
X440098Y2113D01*
X440311Y1613D01*
X440631Y1197D01*
X441058Y1030D01*
X441485Y1197D01*
X441805Y1613D01*
X442018Y2113D01*
X442178Y2780D01*
X442231Y3530D01*
X442178Y4280D01*
X442018Y4947D01*
X441805Y5447D01*
X441485Y5863D01*
X441058Y6030D01*
G01X421157Y12455D02*
X420837Y12705D01*
X420464Y12872D01*
X420037D01*
X419557Y12622D01*
X419184Y12205D01*
X418917Y11705D01*
X418704Y10872D01*
X418651Y10122D01*
X418757Y9372D01*
X418917Y8872D01*
X419237Y8372D01*
X419611Y8039D01*
X419984Y7872D01*
X420357D01*
X420731Y8039D01*
X421051Y8289D01*
X421317Y8622D01*
G01X423371Y12039D02*
X423691Y12539D01*
X424064Y12789D01*
X424491Y12872D01*
X425024Y12705D01*
X425397Y12289D01*
X425504Y11789D01*
X425451Y11289D01*
X425237Y10872D01*
X424171Y10039D01*
X423691Y9455D01*
X423371Y8622D01*
X423264Y7872D01*
X425504D01*
G01X428784D02*
Y12872D01*
X428144Y11872D01*
G01Y7872D02*
X429424D01*
G01X432011Y8622D02*
X432331Y8205D01*
X432704Y7955D01*
X433184Y7872D01*
X433664Y8039D01*
X434037Y8372D01*
X434304Y8955D01*
X434357Y9622D01*
X434251Y10289D01*
X433984Y10705D01*
X433611Y11039D01*
X433237Y11122D01*
X432864Y11039D01*
X432384Y10705D01*
X432544Y12872D01*
X433984D01*
G01X426793Y-6844D02*
Y-1844D01*
X428127D01*
X428553Y-2094D01*
X428820Y-2427D01*
X428927Y-3094D01*
X428820Y-3761D01*
X428500Y-4177D01*
X428127Y-4427D01*
X426793D01*
G01X428127D02*
X428927Y-6844D01*
G01X431087Y-6094D02*
X431407Y-6511D01*
X431780Y-6761D01*
X432260Y-6844D01*
X432740Y-6677D01*
X433113Y-6344D01*
X433380Y-5761D01*
X433433Y-5094D01*
X433327Y-4427D01*
X433060Y-4011D01*
X432687Y-3677D01*
X432313Y-3594D01*
X431940Y-3677D01*
X431460Y-4011D01*
X431620Y-1844D01*
X433060D01*
G01X436660D02*
X436233Y-2011D01*
X435913Y-2427D01*
X435700Y-2927D01*
X435540Y-3594D01*
X435487Y-4344D01*
X435540Y-5094D01*
X435700Y-5761D01*
X435913Y-6261D01*
X436233Y-6677D01*
X436660Y-6844D01*
X437087Y-6677D01*
X437407Y-6261D01*
X437620Y-5761D01*
X437780Y-5094D01*
X437833Y-4344D01*
X437780Y-3594D01*
X437620Y-2927D01*
X437407Y-2427D01*
X437087Y-2011D01*
X436660Y-1844D01*
G01X440047Y-2677D02*
X440367Y-2177D01*
X440740Y-1927D01*
X441167Y-1844D01*
X441700Y-2011D01*
X442073Y-2427D01*
X442180Y-2927D01*
X442127Y-3427D01*
X441913Y-3844D01*
X440847Y-4677D01*
X440367Y-5261D01*
X440047Y-6094D01*
X439940Y-6844D01*
X442180D01*
G01X416078Y-8129D02*
X411078D01*
Y-6795D01*
X411328Y-6369D01*
X411661Y-6102D01*
X412328Y-5995D01*
X412995Y-6102D01*
X413411Y-6422D01*
X413661Y-6795D01*
Y-8129D01*
G01Y-6795D02*
X416078Y-5995D01*
G01X411911Y-3675D02*
X411411Y-3355D01*
X411161Y-2982D01*
X411078Y-2555D01*
X411245Y-2022D01*
X411661Y-1649D01*
X412161Y-1542D01*
X412661Y-1595D01*
X413078Y-1809D01*
X413911Y-2875D01*
X414495Y-3355D01*
X415328Y-3675D01*
X416078Y-3782D01*
Y-1542D01*
G01Y1631D02*
X414995Y1738D01*
X414078Y1898D01*
X413245Y2111D01*
X412328Y2378D01*
X411078Y2805D01*
Y671D01*
G01X416078Y6138D02*
X411078D01*
X412078Y5498D01*
G01X416078D02*
Y6778D01*
G01X418971Y21429D02*
X418511Y21739D01*
X417974Y21946D01*
X417361D01*
X416671Y21636D01*
X416134Y21119D01*
X415751Y20499D01*
X415444Y19466D01*
X415367Y18536D01*
X415521Y17606D01*
X415751Y16986D01*
X416211Y16366D01*
X416747Y15953D01*
X417284Y15746D01*
X417821D01*
X418357Y15953D01*
X418817Y16263D01*
X419201Y16676D01*
G01X423484Y15746D02*
Y21946D01*
X422564Y20706D01*
G01Y15746D02*
X424404D01*
G01X427997Y16986D02*
X428457Y16263D01*
X429071Y15849D01*
X429761Y15746D01*
X430374Y15849D01*
X430987Y16366D01*
X431371Y16986D01*
X431447Y17606D01*
X431294Y18329D01*
X430757Y18846D01*
X430221Y19053D01*
X429531D01*
G01X430221D02*
X430681Y19363D01*
X431064Y19879D01*
X431217Y20499D01*
X431064Y21119D01*
X430681Y21636D01*
X429991Y21946D01*
X429301Y21843D01*
X428611Y21429D01*
G01X435884Y21946D02*
X435271Y21739D01*
X434811Y21223D01*
X434504Y20603D01*
X434274Y19776D01*
X434197Y18846D01*
X434274Y17916D01*
X434504Y17089D01*
X434811Y16469D01*
X435271Y15953D01*
X435884Y15746D01*
X436497Y15953D01*
X436957Y16469D01*
X437264Y17089D01*
X437494Y17916D01*
X437571Y18846D01*
X437494Y19776D01*
X437264Y20603D01*
X436957Y21223D01*
X436497Y21739D01*
X435884Y21946D01*
G01X412195Y52667D02*
X411885Y52207D01*
X411678Y51670D01*
Y51057D01*
X411988Y50367D01*
X412505Y49830D01*
X413125Y49447D01*
X414158Y49140D01*
X415088Y49063D01*
X416018Y49217D01*
X416638Y49447D01*
X417258Y49907D01*
X417671Y50443D01*
X417878Y50980D01*
Y51517D01*
X417671Y52053D01*
X417361Y52513D01*
X416948Y52897D01*
G01X417878Y57180D02*
X411678D01*
X412918Y56260D01*
G01X417878D02*
Y58100D01*
G01X416948Y61693D02*
X417465Y62153D01*
X417775Y62690D01*
X417878Y63380D01*
X417671Y64070D01*
X417258Y64607D01*
X416535Y64990D01*
X415708Y65067D01*
X414881Y64913D01*
X414365Y64530D01*
X413951Y63993D01*
X413848Y63457D01*
X413951Y62920D01*
X414365Y62230D01*
X411678Y62460D01*
Y64530D01*
G01X417878Y70500D02*
X411678D01*
X416121Y67663D01*
Y71497D01*
G01X429678Y103705D02*
X423478D01*
Y105621D01*
X423788Y106235D01*
X424201Y106618D01*
X425028Y106771D01*
X425855Y106618D01*
X426371Y106158D01*
X426681Y105621D01*
Y103705D01*
G01Y105621D02*
X429678Y106771D01*
G01X424511Y109981D02*
X423891Y110441D01*
X423581Y110978D01*
X423478Y111591D01*
X423685Y112358D01*
X424201Y112895D01*
X424821Y113048D01*
X425441Y112971D01*
X425958Y112665D01*
X426991Y111131D01*
X427715Y110441D01*
X428748Y109981D01*
X429678Y109828D01*
Y113048D01*
G01X424511Y116181D02*
X423891Y116641D01*
X423581Y117178D01*
X423478Y117791D01*
X423685Y118558D01*
X424201Y119095D01*
X424821Y119248D01*
X425441Y119171D01*
X425958Y118865D01*
X426991Y117331D01*
X427715Y116641D01*
X428748Y116181D01*
X429678Y116028D01*
Y119248D01*
G01Y124758D02*
X423478D01*
X427921Y121921D01*
Y125755D01*
G01X419065Y408121D02*
X418605Y408431D01*
X418068Y408638D01*
X417455D01*
X416765Y408328D01*
X416228Y407811D01*
X415845Y407191D01*
X415538Y406158D01*
X415461Y405228D01*
X415615Y404298D01*
X415845Y403678D01*
X416305Y403058D01*
X416841Y402645D01*
X417378Y402438D01*
X417915D01*
X418451Y402645D01*
X418911Y402955D01*
X419295Y403368D01*
G01X423578Y402438D02*
X424115Y402541D01*
X424728Y402851D01*
X425111Y403368D01*
X425265Y404091D01*
X425111Y404815D01*
X424651Y405435D01*
X423961Y405745D01*
X423195D01*
X422735Y405951D01*
X422351Y406468D01*
X422198Y407191D01*
X422428Y407915D01*
X422965Y408431D01*
X423578Y408638D01*
X424191Y408431D01*
X424728Y407915D01*
X424958Y407191D01*
X424805Y406468D01*
X424421Y405951D01*
X423961Y405745D01*
X423195D01*
X422505Y405435D01*
X422045Y404815D01*
X421891Y404091D01*
X422045Y403368D01*
X422428Y402851D01*
X423041Y402541D01*
X423578Y402438D01*
G01X429778Y408638D02*
X429165Y408431D01*
X428705Y407915D01*
X428398Y407295D01*
X428168Y406468D01*
X428091Y405538D01*
X428168Y404608D01*
X428398Y403781D01*
X428705Y403161D01*
X429165Y402645D01*
X429778Y402438D01*
X430391Y402645D01*
X430851Y403161D01*
X431158Y403781D01*
X431388Y404608D01*
X431465Y405538D01*
X431388Y406468D01*
X431158Y407295D01*
X430851Y407915D01*
X430391Y408431D01*
X429778Y408638D01*
G01X415965Y417121D02*
X415505Y417431D01*
X414968Y417638D01*
X414355D01*
X413665Y417328D01*
X413128Y416811D01*
X412745Y416191D01*
X412438Y415158D01*
X412361Y414228D01*
X412515Y413298D01*
X412745Y412678D01*
X413205Y412058D01*
X413741Y411645D01*
X414278Y411438D01*
X414815D01*
X415351Y411645D01*
X415811Y411955D01*
X416195Y412368D01*
G01X419021Y416605D02*
X419481Y417225D01*
X420018Y417535D01*
X420631Y417638D01*
X421398Y417431D01*
X421935Y416915D01*
X422088Y416295D01*
X422011Y415675D01*
X421705Y415158D01*
X420171Y414125D01*
X419481Y413401D01*
X419021Y412368D01*
X418868Y411438D01*
X422088D01*
G01X426525D02*
X426678Y412781D01*
X426908Y413918D01*
X427215Y414951D01*
X427598Y416088D01*
X428211Y417638D01*
X425145D01*
G01X431191Y412678D02*
X431651Y411955D01*
X432265Y411541D01*
X432955Y411438D01*
X433568Y411541D01*
X434181Y412058D01*
X434565Y412678D01*
X434641Y413298D01*
X434488Y414021D01*
X433951Y414538D01*
X433415Y414745D01*
X432725D01*
G01X433415D02*
X433875Y415055D01*
X434258Y415571D01*
X434411Y416191D01*
X434258Y416811D01*
X433875Y417328D01*
X433185Y417638D01*
X432495Y417535D01*
X431805Y417121D01*
G01X446646Y-152295D02*
X440446D01*
Y-150379D01*
X440756Y-149765D01*
X441169Y-149382D01*
X441996Y-149229D01*
X442823Y-149382D01*
X443339Y-149842D01*
X443649Y-150379D01*
Y-152295D01*
G01Y-150379D02*
X446646Y-149229D01*
G01Y-143642D02*
X440446D01*
X444889Y-146479D01*
Y-142645D01*
G01X446646Y-137442D02*
X440446D01*
X444889Y-140279D01*
Y-136445D01*
G01X440446Y-132162D02*
X440653Y-132775D01*
X441169Y-133235D01*
X441789Y-133542D01*
X442616Y-133772D01*
X443546Y-133849D01*
X444476Y-133772D01*
X445303Y-133542D01*
X445923Y-133235D01*
X446439Y-132775D01*
X446646Y-132162D01*
X446439Y-131549D01*
X445923Y-131089D01*
X445303Y-130782D01*
X444476Y-130552D01*
X443546Y-130475D01*
X442616Y-130552D01*
X441789Y-130782D01*
X441169Y-131089D01*
X440653Y-131549D01*
X440446Y-132162D01*
G01X435646Y-152295D02*
X429446D01*
Y-150379D01*
X429756Y-149765D01*
X430169Y-149382D01*
X430996Y-149229D01*
X431823Y-149382D01*
X432339Y-149842D01*
X432649Y-150379D01*
Y-152295D01*
G01Y-150379D02*
X435646Y-149229D01*
G01Y-143642D02*
X429446D01*
X433889Y-146479D01*
Y-142645D01*
G01X435646Y-137442D02*
X429446D01*
X433889Y-140279D01*
Y-136445D01*
G01X435646Y-132162D02*
X429446D01*
X430686Y-133082D01*
G01X435646D02*
Y-131242D01*
G01X444787Y-100757D02*
X444537Y-101077D01*
X444370Y-101450D01*
Y-101877D01*
X444620Y-102357D01*
X445037Y-102730D01*
X445537Y-102997D01*
X446370Y-103210D01*
X447120Y-103263D01*
X447870Y-103157D01*
X448370Y-102997D01*
X448870Y-102677D01*
X449203Y-102303D01*
X449370Y-101930D01*
Y-101557D01*
X449203Y-101183D01*
X448953Y-100863D01*
X448620Y-100597D01*
G01X449370Y-97530D02*
X444370D01*
X445370Y-98170D01*
G01X449370D02*
Y-96890D01*
G01X447287Y-94143D02*
X446703Y-93770D01*
X446370Y-93450D01*
X446203Y-93023D01*
X446370Y-92650D01*
X446703Y-92383D01*
X447203Y-92170D01*
X447787Y-92117D01*
X448287Y-92170D01*
X448787Y-92383D01*
X449203Y-92703D01*
X449370Y-93077D01*
X449203Y-93503D01*
X448703Y-93877D01*
X447953Y-94090D01*
X447120Y-94143D01*
X446037Y-94037D01*
X445453Y-93877D01*
X444870Y-93610D01*
X444453Y-93237D01*
X444370Y-92863D01*
X444537Y-92490D01*
X444953Y-92223D01*
G01X444370Y-88730D02*
X444537Y-89157D01*
X444953Y-89477D01*
X445453Y-89690D01*
X446120Y-89850D01*
X446870Y-89903D01*
X447620Y-89850D01*
X448287Y-89690D01*
X448787Y-89477D01*
X449203Y-89157D01*
X449370Y-88730D01*
X449203Y-88303D01*
X448787Y-87983D01*
X448287Y-87770D01*
X447620Y-87610D01*
X446870Y-87557D01*
X446120Y-87610D01*
X445453Y-87770D01*
X444953Y-87983D01*
X444537Y-88303D01*
X444370Y-88730D01*
G01X442539Y-85580D02*
Y-80580D01*
X443873D01*
X444299Y-80830D01*
X444566Y-81163D01*
X444673Y-81830D01*
X444566Y-82497D01*
X444246Y-82913D01*
X443873Y-83163D01*
X442539D01*
G01X443873D02*
X444673Y-85580D01*
G01X446993Y-81413D02*
X447313Y-80913D01*
X447686Y-80663D01*
X448113Y-80580D01*
X448646Y-80747D01*
X449019Y-81163D01*
X449126Y-81663D01*
X449073Y-82163D01*
X448859Y-82580D01*
X447793Y-83413D01*
X447313Y-83997D01*
X446993Y-84830D01*
X446886Y-85580D01*
X449126D01*
G01X452299D02*
X452406Y-84497D01*
X452566Y-83580D01*
X452779Y-82747D01*
X453046Y-81830D01*
X453473Y-80580D01*
X451339D01*
G01X456806Y-85580D02*
X457179Y-85497D01*
X457606Y-85247D01*
X457873Y-84830D01*
X457979Y-84247D01*
X457873Y-83663D01*
X457553Y-83163D01*
X457073Y-82913D01*
X456539D01*
X456219Y-82747D01*
X455953Y-82330D01*
X455846Y-81747D01*
X456006Y-81163D01*
X456379Y-80747D01*
X456806Y-80580D01*
X457233Y-80747D01*
X457606Y-81163D01*
X457766Y-81747D01*
X457659Y-82330D01*
X457393Y-82747D01*
X457073Y-82913D01*
X456539D01*
X456059Y-83163D01*
X455739Y-83663D01*
X455633Y-84247D01*
X455739Y-84830D01*
X456006Y-85247D01*
X456433Y-85497D01*
X456806Y-85580D01*
G01X429039Y-67057D02*
X428789Y-67377D01*
X428622Y-67750D01*
Y-68177D01*
X428872Y-68657D01*
X429289Y-69030D01*
X429789Y-69297D01*
X430622Y-69510D01*
X431372Y-69563D01*
X432122Y-69457D01*
X432622Y-69297D01*
X433122Y-68977D01*
X433455Y-68603D01*
X433622Y-68230D01*
Y-67857D01*
X433455Y-67483D01*
X433205Y-67163D01*
X432872Y-66897D01*
G01X433039Y-64737D02*
X433455Y-64363D01*
X433622Y-63937D01*
X433455Y-63510D01*
X432955Y-63137D01*
X432205Y-62870D01*
X431455Y-62763D01*
X430539D01*
X429789Y-62870D01*
X429122Y-63137D01*
X428789Y-63457D01*
X428622Y-63830D01*
X428789Y-64257D01*
X429122Y-64577D01*
X429622Y-64790D01*
X430289Y-64897D01*
X430872Y-64790D01*
X431455Y-64523D01*
X431789Y-64203D01*
X431872Y-63830D01*
X431705Y-63403D01*
X431289Y-63083D01*
X430539Y-62763D01*
G01X432622Y-60603D02*
X433205Y-60283D01*
X433539Y-59857D01*
X433622Y-59377D01*
X433539Y-58950D01*
X433122Y-58523D01*
X432622Y-58257D01*
X432122Y-58203D01*
X431539Y-58310D01*
X431122Y-58683D01*
X430955Y-59057D01*
Y-59537D01*
G01Y-59057D02*
X430705Y-58737D01*
X430289Y-58470D01*
X429789Y-58363D01*
X429289Y-58470D01*
X428872Y-58737D01*
X428622Y-59217D01*
X428705Y-59697D01*
X429039Y-60177D01*
G01X443995Y-43889D02*
X443745Y-44209D01*
X443578Y-44582D01*
Y-45009D01*
X443828Y-45489D01*
X444245Y-45862D01*
X444745Y-46129D01*
X445578Y-46342D01*
X446328Y-46395D01*
X447078Y-46289D01*
X447578Y-46129D01*
X448078Y-45809D01*
X448411Y-45435D01*
X448578Y-45062D01*
Y-44689D01*
X448411Y-44315D01*
X448161Y-43995D01*
X447828Y-43729D01*
G01X444411Y-41675D02*
X443911Y-41355D01*
X443661Y-40982D01*
X443578Y-40555D01*
X443745Y-40022D01*
X444161Y-39649D01*
X444661Y-39542D01*
X445161Y-39595D01*
X445578Y-39809D01*
X446411Y-40875D01*
X446995Y-41355D01*
X447828Y-41675D01*
X448578Y-41782D01*
Y-39542D01*
G01X443578Y-36262D02*
X443745Y-36689D01*
X444161Y-37009D01*
X444661Y-37222D01*
X445328Y-37382D01*
X446078Y-37435D01*
X446828Y-37382D01*
X447495Y-37222D01*
X447995Y-37009D01*
X448411Y-36689D01*
X448578Y-36262D01*
X448411Y-35835D01*
X447995Y-35515D01*
X447495Y-35302D01*
X446828Y-35142D01*
X446078Y-35089D01*
X445328Y-35142D01*
X444661Y-35302D01*
X444161Y-35515D01*
X443745Y-35835D01*
X443578Y-36262D01*
G01X448578Y-31969D02*
X447495Y-31862D01*
X446578Y-31702D01*
X445745Y-31489D01*
X444828Y-31222D01*
X443578Y-30795D01*
Y-32929D01*
G01X444495Y-13889D02*
X444245Y-14209D01*
X444078Y-14582D01*
Y-15009D01*
X444328Y-15489D01*
X444745Y-15862D01*
X445245Y-16129D01*
X446078Y-16342D01*
X446828Y-16395D01*
X447578Y-16289D01*
X448078Y-16129D01*
X448578Y-15809D01*
X448911Y-15435D01*
X449078Y-15062D01*
Y-14689D01*
X448911Y-14315D01*
X448661Y-13995D01*
X448328Y-13729D01*
G01X449078Y-10662D02*
X444078D01*
X445078Y-11302D01*
G01X449078D02*
Y-10022D01*
G01X444078Y-6262D02*
X444245Y-6689D01*
X444661Y-7009D01*
X445161Y-7222D01*
X445828Y-7382D01*
X446578Y-7435D01*
X447328Y-7382D01*
X447995Y-7222D01*
X448495Y-7009D01*
X448911Y-6689D01*
X449078Y-6262D01*
X448911Y-5835D01*
X448495Y-5515D01*
X447995Y-5302D01*
X447328Y-5142D01*
X446578Y-5089D01*
X445828Y-5142D01*
X445161Y-5302D01*
X444661Y-5515D01*
X444245Y-5835D01*
X444078Y-6262D01*
G01X449078Y-1969D02*
X447995Y-1862D01*
X447078Y-1702D01*
X446245Y-1489D01*
X445328Y-1222D01*
X444078Y-795D01*
Y-2929D01*
G01X436151Y-20379D02*
X435831Y-20129D01*
X435458Y-19962D01*
X435031D01*
X434551Y-20212D01*
X434178Y-20629D01*
X433911Y-21129D01*
X433698Y-21962D01*
X433645Y-22712D01*
X433751Y-23462D01*
X433911Y-23962D01*
X434231Y-24462D01*
X434605Y-24795D01*
X434978Y-24962D01*
X435351D01*
X435725Y-24795D01*
X436045Y-24545D01*
X436311Y-24212D01*
G01X439378Y-24962D02*
Y-19962D01*
X438738Y-20962D01*
G01Y-24962D02*
X440018D01*
G01X442765Y-22879D02*
X443138Y-22295D01*
X443458Y-21962D01*
X443885Y-21795D01*
X444258Y-21962D01*
X444525Y-22295D01*
X444738Y-22795D01*
X444791Y-23379D01*
X444738Y-23879D01*
X444525Y-24379D01*
X444205Y-24795D01*
X443831Y-24962D01*
X443405Y-24795D01*
X443031Y-24295D01*
X442818Y-23545D01*
X442765Y-22712D01*
X442871Y-21629D01*
X443031Y-21045D01*
X443298Y-20462D01*
X443671Y-20045D01*
X444045Y-19962D01*
X444418Y-20129D01*
X444685Y-20545D01*
G01X447005Y-24212D02*
X447325Y-24629D01*
X447698Y-24879D01*
X448178Y-24962D01*
X448658Y-24795D01*
X449031Y-24462D01*
X449298Y-23879D01*
X449351Y-23212D01*
X449245Y-22545D01*
X448978Y-22129D01*
X448605Y-21795D01*
X448231Y-21712D01*
X447858Y-21795D01*
X447378Y-22129D01*
X447538Y-19962D01*
X448978D01*
G01X442595Y45051D02*
X442135Y45361D01*
X441598Y45568D01*
X440985D01*
X440295Y45258D01*
X439758Y44741D01*
X439375Y44121D01*
X439068Y43088D01*
X438991Y42158D01*
X439145Y41228D01*
X439375Y40608D01*
X439835Y39988D01*
X440371Y39575D01*
X440908Y39368D01*
X441445D01*
X441981Y39575D01*
X442441Y39885D01*
X442825Y40298D01*
G01X447108Y39368D02*
Y45568D01*
X446188Y44328D01*
G01Y39368D02*
X448028D01*
G01X451621Y40608D02*
X452081Y39885D01*
X452695Y39471D01*
X453385Y39368D01*
X453998Y39471D01*
X454611Y39988D01*
X454995Y40608D01*
X455071Y41228D01*
X454918Y41951D01*
X454381Y42468D01*
X453845Y42675D01*
X453155D01*
G01X453845D02*
X454305Y42985D01*
X454688Y43501D01*
X454841Y44121D01*
X454688Y44741D01*
X454305Y45258D01*
X453615Y45568D01*
X452925Y45465D01*
X452235Y45051D01*
G01X460428Y39368D02*
Y45568D01*
X457591Y41125D01*
X461425D01*
G01X445965Y73221D02*
X445505Y73531D01*
X444968Y73738D01*
X444355D01*
X443665Y73428D01*
X443128Y72911D01*
X442745Y72291D01*
X442438Y71258D01*
X442361Y70328D01*
X442515Y69398D01*
X442745Y68778D01*
X443205Y68158D01*
X443741Y67745D01*
X444278Y67538D01*
X444815D01*
X445351Y67745D01*
X445811Y68055D01*
X446195Y68468D01*
G01X450478Y67538D02*
Y73738D01*
X449558Y72498D01*
G01Y67538D02*
X451398D01*
G01X455221Y70121D02*
X455758Y70845D01*
X456218Y71258D01*
X456831Y71465D01*
X457368Y71258D01*
X457751Y70845D01*
X458058Y70225D01*
X458135Y69501D01*
X458058Y68881D01*
X457751Y68261D01*
X457291Y67745D01*
X456755Y67538D01*
X456141Y67745D01*
X455605Y68364D01*
X455298Y69295D01*
X455221Y70328D01*
X455375Y71671D01*
X455605Y72395D01*
X455988Y73118D01*
X456525Y73635D01*
X457061Y73738D01*
X457598Y73531D01*
X457981Y73015D01*
G01X461191Y68778D02*
X461651Y68055D01*
X462265Y67641D01*
X462955Y67538D01*
X463568Y67641D01*
X464181Y68158D01*
X464565Y68778D01*
X464641Y69398D01*
X464488Y70121D01*
X463951Y70638D01*
X463415Y70845D01*
X462725D01*
G01X463415D02*
X463875Y71155D01*
X464258Y71671D01*
X464411Y72291D01*
X464258Y72911D01*
X463875Y73428D01*
X463185Y73738D01*
X462495Y73635D01*
X461805Y73221D01*
G01X438678Y103705D02*
X432478D01*
Y105621D01*
X432788Y106235D01*
X433201Y106618D01*
X434028Y106771D01*
X434855Y106618D01*
X435371Y106158D01*
X435681Y105621D01*
Y103705D01*
G01Y105621D02*
X438678Y106771D01*
G01X433511Y109981D02*
X432891Y110441D01*
X432581Y110978D01*
X432478Y111591D01*
X432685Y112358D01*
X433201Y112895D01*
X433821Y113048D01*
X434441Y112971D01*
X434958Y112665D01*
X435991Y111131D01*
X436715Y110441D01*
X437748Y109981D01*
X438678Y109828D01*
Y113048D01*
G01X433511Y116181D02*
X432891Y116641D01*
X432581Y117178D01*
X432478Y117791D01*
X432685Y118558D01*
X433201Y119095D01*
X433821Y119248D01*
X434441Y119171D01*
X434958Y118865D01*
X435991Y117331D01*
X436715Y116641D01*
X437748Y116181D01*
X438678Y116028D01*
Y119248D01*
G01X437438Y122151D02*
X438161Y122611D01*
X438575Y123225D01*
X438678Y123915D01*
X438575Y124528D01*
X438058Y125141D01*
X437438Y125525D01*
X436818Y125601D01*
X436095Y125448D01*
X435578Y124911D01*
X435371Y124375D01*
Y123685D01*
G01Y124375D02*
X435061Y124835D01*
X434545Y125218D01*
X433925Y125371D01*
X433305Y125218D01*
X432788Y124835D01*
X432478Y124145D01*
X432581Y123455D01*
X432995Y122765D01*
G01X447678Y103705D02*
X441478D01*
Y105621D01*
X441788Y106235D01*
X442201Y106618D01*
X443028Y106771D01*
X443855Y106618D01*
X444371Y106158D01*
X444681Y105621D01*
Y103705D01*
G01Y105621D02*
X447678Y106771D01*
G01X442511Y109981D02*
X441891Y110441D01*
X441581Y110978D01*
X441478Y111591D01*
X441685Y112358D01*
X442201Y112895D01*
X442821Y113048D01*
X443441Y112971D01*
X443958Y112665D01*
X444991Y111131D01*
X445715Y110441D01*
X446748Y109981D01*
X447678Y109828D01*
Y113048D01*
G01Y117638D02*
X441478D01*
X442718Y116718D01*
G01X447678D02*
Y118558D01*
G01X446748Y122151D02*
X447265Y122611D01*
X447575Y123148D01*
X447678Y123838D01*
X447471Y124528D01*
X447058Y125065D01*
X446335Y125448D01*
X445508Y125525D01*
X444681Y125371D01*
X444165Y124988D01*
X443751Y124451D01*
X443648Y123915D01*
X443751Y123378D01*
X444165Y122688D01*
X441478Y122918D01*
Y124988D01*
G01X430745Y182438D02*
Y188638D01*
X432661D01*
X433275Y188328D01*
X433658Y187915D01*
X433811Y187088D01*
X433658Y186261D01*
X433198Y185745D01*
X432661Y185435D01*
X430745D01*
G01X432661D02*
X433811Y182438D01*
G01X437021Y187605D02*
X437481Y188225D01*
X438018Y188535D01*
X438631Y188638D01*
X439398Y188431D01*
X439935Y187915D01*
X440088Y187295D01*
X440011Y186675D01*
X439705Y186158D01*
X438171Y185125D01*
X437481Y184401D01*
X437021Y183368D01*
X436868Y182438D01*
X440088D01*
G01X443221Y185021D02*
X443758Y185745D01*
X444218Y186158D01*
X444831Y186365D01*
X445368Y186158D01*
X445751Y185745D01*
X446058Y185125D01*
X446135Y184401D01*
X446058Y183781D01*
X445751Y183161D01*
X445291Y182645D01*
X444755Y182438D01*
X444141Y182645D01*
X443605Y183264D01*
X443298Y184195D01*
X443221Y185228D01*
X443375Y186571D01*
X443605Y187295D01*
X443988Y188018D01*
X444525Y188535D01*
X445061Y188638D01*
X445598Y188431D01*
X445981Y187915D01*
G01X450878Y188638D02*
X450265Y188431D01*
X449805Y187915D01*
X449498Y187295D01*
X449268Y186468D01*
X449191Y185538D01*
X449268Y184608D01*
X449498Y183781D01*
X449805Y183161D01*
X450265Y182645D01*
X450878Y182438D01*
X451491Y182645D01*
X451951Y183161D01*
X452258Y183781D01*
X452488Y184608D01*
X452565Y185538D01*
X452488Y186468D01*
X452258Y187295D01*
X451951Y187915D01*
X451491Y188431D01*
X450878Y188638D01*
G01X433965Y198121D02*
X433505Y198431D01*
X432968Y198638D01*
X432355D01*
X431665Y198328D01*
X431128Y197811D01*
X430745Y197191D01*
X430438Y196158D01*
X430361Y195228D01*
X430515Y194298D01*
X430745Y193678D01*
X431205Y193058D01*
X431741Y192645D01*
X432278Y192438D01*
X432815D01*
X433351Y192645D01*
X433811Y192955D01*
X434195Y193368D01*
G01X437021Y197605D02*
X437481Y198225D01*
X438018Y198535D01*
X438631Y198638D01*
X439398Y198431D01*
X439935Y197915D01*
X440088Y197295D01*
X440011Y196675D01*
X439705Y196158D01*
X438171Y195125D01*
X437481Y194401D01*
X437021Y193368D01*
X436868Y192438D01*
X440088D01*
G01X443221Y197605D02*
X443681Y198225D01*
X444218Y198535D01*
X444831Y198638D01*
X445598Y198431D01*
X446135Y197915D01*
X446288Y197295D01*
X446211Y196675D01*
X445905Y196158D01*
X444371Y195125D01*
X443681Y194401D01*
X443221Y193368D01*
X443068Y192438D01*
X446288D01*
G01X449575Y193161D02*
X450111Y192645D01*
X450725Y192438D01*
X451338Y192645D01*
X451875Y193264D01*
X452258Y194195D01*
X452411Y195125D01*
Y196261D01*
X452258Y197191D01*
X451875Y198018D01*
X451415Y198431D01*
X450878Y198638D01*
X450265Y198431D01*
X449805Y198018D01*
X449498Y197398D01*
X449345Y196571D01*
X449498Y195848D01*
X449881Y195125D01*
X450341Y194711D01*
X450878Y194608D01*
X451491Y194815D01*
X451951Y195331D01*
X452411Y196261D01*
G01X430745Y212438D02*
Y218638D01*
X432661D01*
X433275Y218328D01*
X433658Y217915D01*
X433811Y217088D01*
X433658Y216261D01*
X433198Y215745D01*
X432661Y215435D01*
X430745D01*
G01X432661D02*
X433811Y212438D01*
G01X437021Y217605D02*
X437481Y218225D01*
X438018Y218535D01*
X438631Y218638D01*
X439398Y218431D01*
X439935Y217915D01*
X440088Y217295D01*
X440011Y216675D01*
X439705Y216158D01*
X438171Y215125D01*
X437481Y214401D01*
X437021Y213368D01*
X436868Y212438D01*
X440088D01*
G01X443221Y217605D02*
X443681Y218225D01*
X444218Y218535D01*
X444831Y218638D01*
X445598Y218431D01*
X446135Y217915D01*
X446288Y217295D01*
X446211Y216675D01*
X445905Y216158D01*
X444371Y215125D01*
X443681Y214401D01*
X443221Y213368D01*
X443068Y212438D01*
X446288D01*
G01X449421Y215021D02*
X449958Y215745D01*
X450418Y216158D01*
X451031Y216365D01*
X451568Y216158D01*
X451951Y215745D01*
X452258Y215125D01*
X452335Y214401D01*
X452258Y213781D01*
X451951Y213161D01*
X451491Y212645D01*
X450955Y212438D01*
X450341Y212645D01*
X449805Y213264D01*
X449498Y214195D01*
X449421Y215228D01*
X449575Y216571D01*
X449805Y217295D01*
X450188Y218018D01*
X450725Y218535D01*
X451261Y218638D01*
X451798Y218431D01*
X452181Y217915D01*
G01X433965Y208121D02*
X433505Y208431D01*
X432968Y208638D01*
X432355D01*
X431665Y208328D01*
X431128Y207811D01*
X430745Y207191D01*
X430438Y206158D01*
X430361Y205228D01*
X430515Y204298D01*
X430745Y203678D01*
X431205Y203058D01*
X431741Y202645D01*
X432278Y202438D01*
X432815D01*
X433351Y202645D01*
X433811Y202955D01*
X434195Y203368D01*
G01X437021Y207605D02*
X437481Y208225D01*
X438018Y208535D01*
X438631Y208638D01*
X439398Y208431D01*
X439935Y207915D01*
X440088Y207295D01*
X440011Y206675D01*
X439705Y206158D01*
X438171Y205125D01*
X437481Y204401D01*
X437021Y203368D01*
X436868Y202438D01*
X440088D01*
G01X443375Y203161D02*
X443911Y202645D01*
X444525Y202438D01*
X445138Y202645D01*
X445675Y203264D01*
X446058Y204195D01*
X446211Y205125D01*
Y206261D01*
X446058Y207191D01*
X445675Y208018D01*
X445215Y208431D01*
X444678Y208638D01*
X444065Y208431D01*
X443605Y208018D01*
X443298Y207398D01*
X443145Y206571D01*
X443298Y205848D01*
X443681Y205125D01*
X444141Y204711D01*
X444678Y204608D01*
X445291Y204815D01*
X445751Y205331D01*
X446211Y206261D01*
G01X451798Y202438D02*
Y208638D01*
X448961Y204195D01*
X452795D01*
G01X460531Y-92881D02*
X460281Y-93201D01*
X460114Y-93574D01*
Y-94001D01*
X460364Y-94481D01*
X460781Y-94854D01*
X461281Y-95121D01*
X462114Y-95334D01*
X462864Y-95387D01*
X463614Y-95281D01*
X464114Y-95121D01*
X464614Y-94801D01*
X464947Y-94427D01*
X465114Y-94054D01*
Y-93681D01*
X464947Y-93307D01*
X464697Y-92987D01*
X464364Y-92721D01*
G01X465114Y-89654D02*
X460114D01*
X461114Y-90294D01*
G01X465114D02*
Y-89014D01*
G01X464114Y-86427D02*
X464697Y-86107D01*
X465031Y-85681D01*
X465114Y-85201D01*
X465031Y-84774D01*
X464614Y-84347D01*
X464114Y-84081D01*
X463614Y-84027D01*
X463031Y-84134D01*
X462614Y-84507D01*
X462447Y-84881D01*
Y-85361D01*
G01Y-84881D02*
X462197Y-84561D01*
X461781Y-84294D01*
X461281Y-84187D01*
X460781Y-84294D01*
X460364Y-84561D01*
X460114Y-85041D01*
X460197Y-85521D01*
X460531Y-86001D01*
G01X464364Y-82027D02*
X464781Y-81707D01*
X465031Y-81334D01*
X465114Y-80854D01*
X464947Y-80374D01*
X464614Y-80001D01*
X464031Y-79734D01*
X463364Y-79681D01*
X462697Y-79787D01*
X462281Y-80054D01*
X461947Y-80427D01*
X461864Y-80801D01*
X461947Y-81174D01*
X462281Y-81654D01*
X460114Y-81494D01*
Y-80054D01*
G01X459531Y-64383D02*
X459281Y-64703D01*
X459114Y-65076D01*
Y-65503D01*
X459364Y-65983D01*
X459781Y-66356D01*
X460281Y-66623D01*
X461114Y-66836D01*
X461864Y-66889D01*
X462614Y-66783D01*
X463114Y-66623D01*
X463614Y-66303D01*
X463947Y-65929D01*
X464114Y-65556D01*
Y-65183D01*
X463947Y-64809D01*
X463697Y-64489D01*
X463364Y-64223D01*
G01X464114Y-61156D02*
X459114D01*
X460114Y-61796D01*
G01X464114D02*
Y-60516D01*
G01X462031Y-57769D02*
X461447Y-57396D01*
X461114Y-57076D01*
X460947Y-56649D01*
X461114Y-56276D01*
X461447Y-56009D01*
X461947Y-55796D01*
X462531Y-55743D01*
X463031Y-55796D01*
X463531Y-56009D01*
X463947Y-56329D01*
X464114Y-56703D01*
X463947Y-57129D01*
X463447Y-57503D01*
X462697Y-57716D01*
X461864Y-57769D01*
X460781Y-57663D01*
X460197Y-57503D01*
X459614Y-57236D01*
X459197Y-56863D01*
X459114Y-56489D01*
X459281Y-56116D01*
X459697Y-55849D01*
G01X464114Y-52356D02*
X459114D01*
X460114Y-52996D01*
G01X464114D02*
Y-51716D01*
G01X451661Y-64385D02*
X451411Y-64705D01*
X451244Y-65078D01*
Y-65505D01*
X451494Y-65985D01*
X451911Y-66358D01*
X452411Y-66625D01*
X453244Y-66838D01*
X453994Y-66891D01*
X454744Y-66785D01*
X455244Y-66625D01*
X455744Y-66305D01*
X456077Y-65931D01*
X456244Y-65558D01*
Y-65185D01*
X456077Y-64811D01*
X455827Y-64491D01*
X455494Y-64225D01*
G01X456244Y-61158D02*
X451244D01*
X452244Y-61798D01*
G01X456244D02*
Y-60518D01*
G01X455494Y-57931D02*
X455911Y-57611D01*
X456161Y-57238D01*
X456244Y-56758D01*
X456077Y-56278D01*
X455744Y-55905D01*
X455161Y-55638D01*
X454494Y-55585D01*
X453827Y-55691D01*
X453411Y-55958D01*
X453077Y-56331D01*
X452994Y-56705D01*
X453077Y-57078D01*
X453411Y-57558D01*
X451244Y-57398D01*
Y-55958D01*
G01X452077Y-53371D02*
X451577Y-53051D01*
X451327Y-52678D01*
X451244Y-52251D01*
X451411Y-51718D01*
X451827Y-51345D01*
X452327Y-51238D01*
X452827Y-51291D01*
X453244Y-51505D01*
X454077Y-52571D01*
X454661Y-53051D01*
X455494Y-53371D01*
X456244Y-53478D01*
Y-51238D01*
G01X452653Y-42663D02*
X452333Y-42413D01*
X451960Y-42246D01*
X451533D01*
X451053Y-42496D01*
X450680Y-42913D01*
X450413Y-43413D01*
X450200Y-44246D01*
X450147Y-44996D01*
X450253Y-45746D01*
X450413Y-46246D01*
X450733Y-46746D01*
X451107Y-47079D01*
X451480Y-47246D01*
X451853D01*
X452227Y-47079D01*
X452547Y-46829D01*
X452813Y-46496D01*
G01X455880Y-47246D02*
Y-42246D01*
X455240Y-43246D01*
G01Y-47246D02*
X456520D01*
G01X460920D02*
Y-42246D01*
X458947Y-45829D01*
X461613D01*
G01X464573Y-47246D02*
X464680Y-46163D01*
X464840Y-45246D01*
X465053Y-44413D01*
X465320Y-43496D01*
X465747Y-42246D01*
X463613D01*
G01X452653Y-34789D02*
X452333Y-34539D01*
X451960Y-34372D01*
X451533D01*
X451053Y-34622D01*
X450680Y-35039D01*
X450413Y-35539D01*
X450200Y-36372D01*
X450147Y-37122D01*
X450253Y-37872D01*
X450413Y-38372D01*
X450733Y-38872D01*
X451107Y-39205D01*
X451480Y-39372D01*
X451853D01*
X452227Y-39205D01*
X452547Y-38955D01*
X452813Y-38622D01*
G01X455880Y-39372D02*
Y-34372D01*
X455240Y-35372D01*
G01Y-39372D02*
X456520D01*
G01X459107Y-38372D02*
X459427Y-38955D01*
X459853Y-39289D01*
X460333Y-39372D01*
X460760Y-39289D01*
X461187Y-38872D01*
X461453Y-38372D01*
X461507Y-37872D01*
X461400Y-37289D01*
X461027Y-36872D01*
X460653Y-36705D01*
X460173D01*
G01X460653D02*
X460973Y-36455D01*
X461240Y-36039D01*
X461347Y-35539D01*
X461240Y-35039D01*
X460973Y-34622D01*
X460493Y-34372D01*
X460013Y-34455D01*
X459533Y-34789D01*
G01X464680Y-39372D02*
X465053Y-39289D01*
X465480Y-39039D01*
X465747Y-38622D01*
X465853Y-38039D01*
X465747Y-37455D01*
X465427Y-36955D01*
X464947Y-36705D01*
X464413D01*
X464093Y-36539D01*
X463827Y-36122D01*
X463720Y-35539D01*
X463880Y-34955D01*
X464253Y-34539D01*
X464680Y-34372D01*
X465107Y-34539D01*
X465480Y-34955D01*
X465640Y-35539D01*
X465533Y-36122D01*
X465267Y-36539D01*
X464947Y-36705D01*
X464413D01*
X463933Y-36955D01*
X463613Y-37455D01*
X463507Y-38039D01*
X463613Y-38622D01*
X463880Y-39039D01*
X464307Y-39289D01*
X464680Y-39372D01*
G01X464086Y-16381D02*
X459086D01*
Y-15047D01*
X459336Y-14621D01*
X459669Y-14354D01*
X460336Y-14247D01*
X461003Y-14354D01*
X461419Y-14674D01*
X461669Y-15047D01*
Y-16381D01*
G01Y-15047D02*
X464086Y-14247D01*
G01Y-10274D02*
X459086D01*
X462669Y-12247D01*
Y-9581D01*
G01X463086Y-7687D02*
X463669Y-7367D01*
X464003Y-6941D01*
X464086Y-6461D01*
X464003Y-6034D01*
X463586Y-5607D01*
X463086Y-5341D01*
X462586Y-5287D01*
X462003Y-5394D01*
X461586Y-5767D01*
X461419Y-6141D01*
Y-6621D01*
G01Y-6141D02*
X461169Y-5821D01*
X460753Y-5554D01*
X460253Y-5447D01*
X459753Y-5554D01*
X459336Y-5821D01*
X459086Y-6301D01*
X459169Y-6781D01*
X459503Y-7261D01*
G01X462003Y-3127D02*
X461419Y-2754D01*
X461086Y-2434D01*
X460919Y-2007D01*
X461086Y-1634D01*
X461419Y-1367D01*
X461919Y-1154D01*
X462503Y-1101D01*
X463003Y-1154D01*
X463503Y-1367D01*
X463919Y-1687D01*
X464086Y-2061D01*
X463919Y-2487D01*
X463419Y-2861D01*
X462669Y-3074D01*
X461836Y-3127D01*
X460753Y-3021D01*
X460169Y-2861D01*
X459586Y-2594D01*
X459169Y-2221D01*
X459086Y-1847D01*
X459253Y-1474D01*
X459669Y-1207D01*
G01X456329Y-20979D02*
X456009Y-20729D01*
X455636Y-20562D01*
X455209D01*
X454729Y-20812D01*
X454356Y-21229D01*
X454089Y-21729D01*
X453876Y-22562D01*
X453823Y-23312D01*
X453929Y-24062D01*
X454089Y-24562D01*
X454409Y-25062D01*
X454783Y-25395D01*
X455156Y-25562D01*
X455529D01*
X455903Y-25395D01*
X456223Y-25145D01*
X456489Y-24812D01*
G01X459556Y-25562D02*
Y-20562D01*
X458916Y-21562D01*
G01Y-25562D02*
X460196D01*
G01X462943Y-21395D02*
X463263Y-20895D01*
X463636Y-20645D01*
X464063Y-20562D01*
X464596Y-20729D01*
X464969Y-21145D01*
X465076Y-21645D01*
X465023Y-22145D01*
X464809Y-22562D01*
X463743Y-23395D01*
X463263Y-23979D01*
X462943Y-24812D01*
X462836Y-25562D01*
X465076D01*
G01X468356D02*
X468729Y-25479D01*
X469156Y-25229D01*
X469423Y-24812D01*
X469529Y-24229D01*
X469423Y-23645D01*
X469103Y-23145D01*
X468623Y-22895D01*
X468089D01*
X467769Y-22729D01*
X467503Y-22312D01*
X467396Y-21729D01*
X467556Y-21145D01*
X467929Y-20729D01*
X468356Y-20562D01*
X468783Y-20729D01*
X469156Y-21145D01*
X469316Y-21729D01*
X469209Y-22312D01*
X468943Y-22729D01*
X468623Y-22895D01*
X468089D01*
X467609Y-23145D01*
X467289Y-23645D01*
X467183Y-24229D01*
X467289Y-24812D01*
X467556Y-25229D01*
X467983Y-25479D01*
X468356Y-25562D01*
G01X456212Y-16381D02*
X451212D01*
Y-15047D01*
X451462Y-14621D01*
X451795Y-14354D01*
X452462Y-14247D01*
X453129Y-14354D01*
X453545Y-14674D01*
X453795Y-15047D01*
Y-16381D01*
G01Y-15047D02*
X456212Y-14247D01*
G01Y-10274D02*
X451212D01*
X454795Y-12247D01*
Y-9581D01*
G01X455212Y-7687D02*
X455795Y-7367D01*
X456129Y-6941D01*
X456212Y-6461D01*
X456129Y-6034D01*
X455712Y-5607D01*
X455212Y-5341D01*
X454712Y-5287D01*
X454129Y-5394D01*
X453712Y-5767D01*
X453545Y-6141D01*
Y-6621D01*
G01Y-6141D02*
X453295Y-5821D01*
X452879Y-5554D01*
X452379Y-5447D01*
X451879Y-5554D01*
X451462Y-5821D01*
X451212Y-6301D01*
X451295Y-6781D01*
X451629Y-7261D01*
G01X456212Y-2221D02*
X455129Y-2114D01*
X454212Y-1954D01*
X453379Y-1741D01*
X452462Y-1474D01*
X451212Y-1047D01*
Y-3181D01*
G01X460529Y12455D02*
X460209Y12705D01*
X459836Y12872D01*
X459409D01*
X458929Y12622D01*
X458556Y12205D01*
X458289Y11705D01*
X458076Y10872D01*
X458023Y10122D01*
X458129Y9372D01*
X458289Y8872D01*
X458609Y8372D01*
X458983Y8039D01*
X459356Y7872D01*
X459729D01*
X460103Y8039D01*
X460423Y8289D01*
X460689Y8622D01*
G01X463756Y7872D02*
Y12872D01*
X463116Y11872D01*
G01Y7872D02*
X464396D01*
G01X466983Y8872D02*
X467303Y8289D01*
X467729Y7955D01*
X468209Y7872D01*
X468636Y7955D01*
X469063Y8372D01*
X469329Y8872D01*
X469383Y9372D01*
X469276Y9955D01*
X468903Y10372D01*
X468529Y10539D01*
X468049D01*
G01X468529D02*
X468849Y10789D01*
X469116Y11205D01*
X469223Y11705D01*
X469116Y12205D01*
X468849Y12622D01*
X468369Y12872D01*
X467889Y12789D01*
X467409Y12455D01*
G01X471543Y12039D02*
X471863Y12539D01*
X472236Y12789D01*
X472663Y12872D01*
X473196Y12705D01*
X473569Y12289D01*
X473676Y11789D01*
X473623Y11289D01*
X473409Y10872D01*
X472343Y10039D01*
X471863Y9455D01*
X471543Y8622D01*
X471436Y7872D01*
X473676D01*
G01X449995Y9925D02*
X449685Y9465D01*
X449478Y8928D01*
Y8315D01*
X449788Y7625D01*
X450305Y7088D01*
X450925Y6705D01*
X451958Y6398D01*
X452888Y6321D01*
X453818Y6475D01*
X454438Y6705D01*
X455058Y7165D01*
X455471Y7701D01*
X455678Y8238D01*
Y8775D01*
X455471Y9311D01*
X455161Y9771D01*
X454748Y10155D01*
G01X455678Y14438D02*
X449478D01*
X450718Y13518D01*
G01X455678D02*
Y15358D01*
G01X450511Y19181D02*
X449891Y19641D01*
X449581Y20178D01*
X449478Y20791D01*
X449685Y21558D01*
X450201Y22095D01*
X450821Y22248D01*
X451441Y22171D01*
X451958Y21865D01*
X452991Y20331D01*
X453715Y19641D01*
X454748Y19181D01*
X455678Y19028D01*
Y22248D01*
G01X453095Y25381D02*
X452371Y25918D01*
X451958Y26378D01*
X451751Y26991D01*
X451958Y27528D01*
X452371Y27911D01*
X452991Y28218D01*
X453715Y28295D01*
X454335Y28218D01*
X454955Y27911D01*
X455471Y27451D01*
X455678Y26915D01*
X455471Y26301D01*
X454852Y25765D01*
X453921Y25458D01*
X452888Y25381D01*
X451545Y25535D01*
X450821Y25765D01*
X450098Y26148D01*
X449581Y26685D01*
X449478Y27221D01*
X449685Y27758D01*
X450201Y28141D01*
G01X465678Y103705D02*
X459478D01*
Y105621D01*
X459788Y106235D01*
X460201Y106618D01*
X461028Y106771D01*
X461855Y106618D01*
X462371Y106158D01*
X462681Y105621D01*
Y103705D01*
G01Y105621D02*
X465678Y106771D01*
G01X460511Y109981D02*
X459891Y110441D01*
X459581Y110978D01*
X459478Y111591D01*
X459685Y112358D01*
X460201Y112895D01*
X460821Y113048D01*
X461441Y112971D01*
X461958Y112665D01*
X462991Y111131D01*
X463715Y110441D01*
X464748Y109981D01*
X465678Y109828D01*
Y113048D01*
G01X460511Y116181D02*
X459891Y116641D01*
X459581Y117178D01*
X459478Y117791D01*
X459685Y118558D01*
X460201Y119095D01*
X460821Y119248D01*
X461441Y119171D01*
X461958Y118865D01*
X462991Y117331D01*
X463715Y116641D01*
X464748Y116181D01*
X465678Y116028D01*
Y119248D01*
G01X459478Y123838D02*
X459685Y123225D01*
X460201Y122765D01*
X460821Y122458D01*
X461648Y122228D01*
X462578Y122151D01*
X463508Y122228D01*
X464335Y122458D01*
X464955Y122765D01*
X465471Y123225D01*
X465678Y123838D01*
X465471Y124451D01*
X464955Y124911D01*
X464335Y125218D01*
X463508Y125448D01*
X462578Y125525D01*
X461648Y125448D01*
X460821Y125218D01*
X460201Y124911D01*
X459685Y124451D01*
X459478Y123838D01*
G01X456678Y103705D02*
X450478D01*
Y105621D01*
X450788Y106235D01*
X451201Y106618D01*
X452028Y106771D01*
X452855Y106618D01*
X453371Y106158D01*
X453681Y105621D01*
Y103705D01*
G01Y105621D02*
X456678Y106771D01*
G01X451511Y109981D02*
X450891Y110441D01*
X450581Y110978D01*
X450478Y111591D01*
X450685Y112358D01*
X451201Y112895D01*
X451821Y113048D01*
X452441Y112971D01*
X452958Y112665D01*
X453991Y111131D01*
X454715Y110441D01*
X455748Y109981D01*
X456678Y109828D01*
Y113048D01*
G01Y117638D02*
X450478D01*
X451718Y116718D01*
G01X456678D02*
Y118558D01*
G01X454095Y122381D02*
X453371Y122918D01*
X452958Y123378D01*
X452751Y123991D01*
X452958Y124528D01*
X453371Y124911D01*
X453991Y125218D01*
X454715Y125295D01*
X455335Y125218D01*
X455955Y124911D01*
X456471Y124451D01*
X456678Y123915D01*
X456471Y123301D01*
X455852Y122765D01*
X454921Y122458D01*
X453888Y122381D01*
X452545Y122535D01*
X451821Y122765D01*
X451098Y123148D01*
X450581Y123685D01*
X450478Y124221D01*
X450685Y124758D01*
X451201Y125141D01*
G01X469646Y-164295D02*
X463446D01*
Y-162379D01*
X463756Y-161765D01*
X464169Y-161382D01*
X464996Y-161229D01*
X465823Y-161382D01*
X466339Y-161842D01*
X466649Y-162379D01*
Y-164295D01*
G01Y-162379D02*
X469646Y-161229D01*
G01X468406Y-158249D02*
X469129Y-157789D01*
X469543Y-157175D01*
X469646Y-156485D01*
X469543Y-155872D01*
X469026Y-155259D01*
X468406Y-154875D01*
X467786Y-154799D01*
X467063Y-154952D01*
X466546Y-155489D01*
X466339Y-156025D01*
Y-156715D01*
G01Y-156025D02*
X466029Y-155565D01*
X465513Y-155182D01*
X464893Y-155029D01*
X464273Y-155182D01*
X463756Y-155565D01*
X463446Y-156255D01*
X463549Y-156945D01*
X463963Y-157635D01*
G01X468716Y-152049D02*
X469233Y-151589D01*
X469543Y-151052D01*
X469646Y-150362D01*
X469439Y-149672D01*
X469026Y-149135D01*
X468303Y-148752D01*
X467476Y-148675D01*
X466649Y-148829D01*
X466133Y-149212D01*
X465719Y-149749D01*
X465616Y-150285D01*
X465719Y-150822D01*
X466133Y-151512D01*
X463446Y-151282D01*
Y-149212D01*
G01X469646Y-144162D02*
X469543Y-143625D01*
X469233Y-143012D01*
X468716Y-142629D01*
X467993Y-142475D01*
X467269Y-142629D01*
X466649Y-143089D01*
X466339Y-143779D01*
Y-144545D01*
X466133Y-145005D01*
X465616Y-145389D01*
X464893Y-145542D01*
X464169Y-145312D01*
X463653Y-144775D01*
X463446Y-144162D01*
X463653Y-143549D01*
X464169Y-143012D01*
X464893Y-142782D01*
X465616Y-142935D01*
X466133Y-143319D01*
X466339Y-143779D01*
Y-144545D01*
X466649Y-145235D01*
X467269Y-145695D01*
X467993Y-145849D01*
X468716Y-145695D01*
X469233Y-145312D01*
X469543Y-144699D01*
X469646Y-144162D01*
G01X478646Y-164295D02*
X472446D01*
Y-162379D01*
X472756Y-161765D01*
X473169Y-161382D01*
X473996Y-161229D01*
X474823Y-161382D01*
X475339Y-161842D01*
X475649Y-162379D01*
Y-164295D01*
G01Y-162379D02*
X478646Y-161229D01*
G01X477406Y-158249D02*
X478129Y-157789D01*
X478543Y-157175D01*
X478646Y-156485D01*
X478543Y-155872D01*
X478026Y-155259D01*
X477406Y-154875D01*
X476786Y-154799D01*
X476063Y-154952D01*
X475546Y-155489D01*
X475339Y-156025D01*
Y-156715D01*
G01Y-156025D02*
X475029Y-155565D01*
X474513Y-155182D01*
X473893Y-155029D01*
X473273Y-155182D01*
X472756Y-155565D01*
X472446Y-156255D01*
X472549Y-156945D01*
X472963Y-157635D01*
G01X477716Y-152049D02*
X478233Y-151589D01*
X478543Y-151052D01*
X478646Y-150362D01*
X478439Y-149672D01*
X478026Y-149135D01*
X477303Y-148752D01*
X476476Y-148675D01*
X475649Y-148829D01*
X475133Y-149212D01*
X474719Y-149749D01*
X474616Y-150285D01*
X474719Y-150822D01*
X475133Y-151512D01*
X472446Y-151282D01*
Y-149212D01*
G01X477716Y-145849D02*
X478233Y-145389D01*
X478543Y-144852D01*
X478646Y-144162D01*
X478439Y-143472D01*
X478026Y-142935D01*
X477303Y-142552D01*
X476476Y-142475D01*
X475649Y-142629D01*
X475133Y-143012D01*
X474719Y-143549D01*
X474616Y-144085D01*
X474719Y-144622D01*
X475133Y-145312D01*
X472446Y-145082D01*
Y-143012D01*
G01X468409Y-108629D02*
X468159Y-108949D01*
X467992Y-109322D01*
Y-109749D01*
X468242Y-110229D01*
X468659Y-110602D01*
X469159Y-110869D01*
X469992Y-111082D01*
X470742Y-111135D01*
X471492Y-111029D01*
X471992Y-110869D01*
X472492Y-110549D01*
X472825Y-110175D01*
X472992Y-109802D01*
Y-109429D01*
X472825Y-109055D01*
X472575Y-108735D01*
X472242Y-108469D01*
G01X472992Y-105402D02*
X467992D01*
X468992Y-106042D01*
G01X472992D02*
Y-104762D01*
G01X467992Y-101002D02*
X468159Y-101429D01*
X468575Y-101749D01*
X469075Y-101962D01*
X469742Y-102122D01*
X470492Y-102175D01*
X471242Y-102122D01*
X471909Y-101962D01*
X472409Y-101749D01*
X472825Y-101429D01*
X472992Y-101002D01*
X472825Y-100575D01*
X472409Y-100255D01*
X471909Y-100042D01*
X471242Y-99882D01*
X470492Y-99829D01*
X469742Y-99882D01*
X469075Y-100042D01*
X468575Y-100255D01*
X468159Y-100575D01*
X467992Y-101002D01*
G01X472992Y-96602D02*
X472909Y-96229D01*
X472659Y-95802D01*
X472242Y-95535D01*
X471659Y-95429D01*
X471075Y-95535D01*
X470575Y-95855D01*
X470325Y-96335D01*
Y-96869D01*
X470159Y-97189D01*
X469742Y-97455D01*
X469159Y-97562D01*
X468575Y-97402D01*
X468159Y-97029D01*
X467992Y-96602D01*
X468159Y-96175D01*
X468575Y-95802D01*
X469159Y-95642D01*
X469742Y-95749D01*
X470159Y-96015D01*
X470325Y-96335D01*
Y-96869D01*
X470575Y-97349D01*
X471075Y-97669D01*
X471659Y-97775D01*
X472242Y-97669D01*
X472659Y-97402D01*
X472909Y-96975D01*
X472992Y-96602D01*
G01X475995Y-89889D02*
X475745Y-90209D01*
X475578Y-90582D01*
Y-91009D01*
X475828Y-91489D01*
X476245Y-91862D01*
X476745Y-92129D01*
X477578Y-92342D01*
X478328Y-92395D01*
X479078Y-92289D01*
X479578Y-92129D01*
X480078Y-91809D01*
X480411Y-91435D01*
X480578Y-91062D01*
Y-90689D01*
X480411Y-90315D01*
X480161Y-89995D01*
X479828Y-89729D01*
G01X476411Y-87675D02*
X475911Y-87355D01*
X475661Y-86982D01*
X475578Y-86555D01*
X475745Y-86022D01*
X476161Y-85649D01*
X476661Y-85542D01*
X477161Y-85595D01*
X477578Y-85809D01*
X478411Y-86875D01*
X478995Y-87355D01*
X479828Y-87675D01*
X480578Y-87782D01*
Y-85542D01*
G01X476411Y-83275D02*
X475911Y-82955D01*
X475661Y-82582D01*
X475578Y-82155D01*
X475745Y-81622D01*
X476161Y-81249D01*
X476661Y-81142D01*
X477161Y-81195D01*
X477578Y-81409D01*
X478411Y-82475D01*
X478995Y-82955D01*
X479828Y-83275D01*
X480578Y-83382D01*
Y-81142D01*
G01X475578Y-77862D02*
X475745Y-78289D01*
X476161Y-78609D01*
X476661Y-78822D01*
X477328Y-78982D01*
X478078Y-79035D01*
X478828Y-78982D01*
X479495Y-78822D01*
X479995Y-78609D01*
X480411Y-78289D01*
X480578Y-77862D01*
X480411Y-77435D01*
X479995Y-77115D01*
X479495Y-76902D01*
X478828Y-76742D01*
X478078Y-76689D01*
X477328Y-76742D01*
X476661Y-76902D01*
X476161Y-77115D01*
X475745Y-77435D01*
X475578Y-77862D01*
G01X467409Y-64385D02*
X467159Y-64705D01*
X466992Y-65078D01*
Y-65505D01*
X467242Y-65985D01*
X467659Y-66358D01*
X468159Y-66625D01*
X468992Y-66838D01*
X469742Y-66891D01*
X470492Y-66785D01*
X470992Y-66625D01*
X471492Y-66305D01*
X471825Y-65931D01*
X471992Y-65558D01*
Y-65185D01*
X471825Y-64811D01*
X471575Y-64491D01*
X471242Y-64225D01*
G01X471992Y-61158D02*
X466992D01*
X467992Y-61798D01*
G01X471992D02*
Y-60518D01*
G01Y-56865D02*
X470909Y-56758D01*
X469992Y-56598D01*
X469159Y-56385D01*
X468242Y-56118D01*
X466992Y-55691D01*
Y-57825D01*
G01X471992Y-52358D02*
X466992D01*
X467992Y-52998D01*
G01X471992D02*
Y-51718D01*
G01X475995Y-68889D02*
X475745Y-69209D01*
X475578Y-69582D01*
Y-70009D01*
X475828Y-70489D01*
X476245Y-70862D01*
X476745Y-71129D01*
X477578Y-71342D01*
X478328Y-71395D01*
X479078Y-71289D01*
X479578Y-71129D01*
X480078Y-70809D01*
X480411Y-70435D01*
X480578Y-70062D01*
Y-69689D01*
X480411Y-69315D01*
X480161Y-68995D01*
X479828Y-68729D01*
G01X476411Y-66675D02*
X475911Y-66355D01*
X475661Y-65982D01*
X475578Y-65555D01*
X475745Y-65022D01*
X476161Y-64649D01*
X476661Y-64542D01*
X477161Y-64595D01*
X477578Y-64809D01*
X478411Y-65875D01*
X478995Y-66355D01*
X479828Y-66675D01*
X480578Y-66782D01*
Y-64542D01*
G01Y-61262D02*
X475578D01*
X476578Y-61902D01*
G01X480578D02*
Y-60622D01*
G01Y-56222D02*
X475578D01*
X479161Y-58195D01*
Y-55529D01*
G01X468409Y-45637D02*
X468159Y-45957D01*
X467992Y-46330D01*
Y-46757D01*
X468242Y-47237D01*
X468659Y-47610D01*
X469159Y-47877D01*
X469992Y-48090D01*
X470742Y-48143D01*
X471492Y-48037D01*
X471992Y-47877D01*
X472492Y-47557D01*
X472825Y-47183D01*
X472992Y-46810D01*
Y-46437D01*
X472825Y-46063D01*
X472575Y-45743D01*
X472242Y-45477D01*
G01X468825Y-43423D02*
X468325Y-43103D01*
X468075Y-42730D01*
X467992Y-42303D01*
X468159Y-41770D01*
X468575Y-41397D01*
X469075Y-41290D01*
X469575Y-41343D01*
X469992Y-41557D01*
X470825Y-42623D01*
X471409Y-43103D01*
X472242Y-43423D01*
X472992Y-43530D01*
Y-41290D01*
G01X467992Y-38010D02*
X468159Y-38437D01*
X468575Y-38757D01*
X469075Y-38970D01*
X469742Y-39130D01*
X470492Y-39183D01*
X471242Y-39130D01*
X471909Y-38970D01*
X472409Y-38757D01*
X472825Y-38437D01*
X472992Y-38010D01*
X472825Y-37583D01*
X472409Y-37263D01*
X471909Y-37050D01*
X471242Y-36890D01*
X470492Y-36837D01*
X469742Y-36890D01*
X469075Y-37050D01*
X468575Y-37263D01*
X468159Y-37583D01*
X467992Y-38010D01*
G01X472992Y-33610D02*
X467992D01*
X468992Y-34250D01*
G01X472992D02*
Y-32970D01*
G01X476995Y-47889D02*
X476745Y-48209D01*
X476578Y-48582D01*
Y-49009D01*
X476828Y-49489D01*
X477245Y-49862D01*
X477745Y-50129D01*
X478578Y-50342D01*
X479328Y-50395D01*
X480078Y-50289D01*
X480578Y-50129D01*
X481078Y-49809D01*
X481411Y-49435D01*
X481578Y-49062D01*
Y-48689D01*
X481411Y-48315D01*
X481161Y-47995D01*
X480828Y-47729D01*
G01X481578Y-44662D02*
X476578D01*
X477578Y-45302D01*
G01X481578D02*
Y-44022D01*
G01X477411Y-41275D02*
X476911Y-40955D01*
X476661Y-40582D01*
X476578Y-40155D01*
X476745Y-39622D01*
X477161Y-39249D01*
X477661Y-39142D01*
X478161Y-39195D01*
X478578Y-39409D01*
X479411Y-40475D01*
X479995Y-40955D01*
X480828Y-41275D01*
X481578Y-41382D01*
Y-39142D01*
G01X480995Y-36769D02*
X481411Y-36395D01*
X481578Y-35969D01*
X481411Y-35542D01*
X480911Y-35169D01*
X480161Y-34902D01*
X479411Y-34795D01*
X478495D01*
X477745Y-34902D01*
X477078Y-35169D01*
X476745Y-35489D01*
X476578Y-35862D01*
X476745Y-36289D01*
X477078Y-36609D01*
X477578Y-36822D01*
X478245Y-36929D01*
X478828Y-36822D01*
X479411Y-36555D01*
X479745Y-36235D01*
X479828Y-35862D01*
X479661Y-35435D01*
X479245Y-35115D01*
X478495Y-34795D01*
G01X476351Y-23779D02*
X476031Y-23529D01*
X475658Y-23362D01*
X475231D01*
X474751Y-23612D01*
X474378Y-24029D01*
X474111Y-24529D01*
X473898Y-25362D01*
X473845Y-26112D01*
X473951Y-26862D01*
X474111Y-27362D01*
X474431Y-27862D01*
X474805Y-28195D01*
X475178Y-28362D01*
X475551D01*
X475925Y-28195D01*
X476245Y-27945D01*
X476511Y-27612D01*
G01X478565Y-24195D02*
X478885Y-23695D01*
X479258Y-23445D01*
X479685Y-23362D01*
X480218Y-23529D01*
X480591Y-23945D01*
X480698Y-24445D01*
X480645Y-24945D01*
X480431Y-25362D01*
X479365Y-26195D01*
X478885Y-26779D01*
X478565Y-27612D01*
X478458Y-28362D01*
X480698D01*
G01X483978D02*
Y-23362D01*
X483338Y-24362D01*
G01Y-28362D02*
X484618D01*
G01X487365Y-24195D02*
X487685Y-23695D01*
X488058Y-23445D01*
X488485Y-23362D01*
X489018Y-23529D01*
X489391Y-23945D01*
X489498Y-24445D01*
X489445Y-24945D01*
X489231Y-25362D01*
X488165Y-26195D01*
X487685Y-26779D01*
X487365Y-27612D01*
X487258Y-28362D01*
X489498D01*
G01X469151Y-10379D02*
X468831Y-10129D01*
X468458Y-9962D01*
X468031D01*
X467551Y-10212D01*
X467178Y-10629D01*
X466911Y-11129D01*
X466698Y-11962D01*
X466645Y-12712D01*
X466751Y-13462D01*
X466911Y-13962D01*
X467231Y-14462D01*
X467605Y-14795D01*
X467978Y-14962D01*
X468351D01*
X468725Y-14795D01*
X469045Y-14545D01*
X469311Y-14212D01*
G01X471365Y-10795D02*
X471685Y-10295D01*
X472058Y-10045D01*
X472485Y-9962D01*
X473018Y-10129D01*
X473391Y-10545D01*
X473498Y-11045D01*
X473445Y-11545D01*
X473231Y-11962D01*
X472165Y-12795D01*
X471685Y-13379D01*
X471365Y-14212D01*
X471258Y-14962D01*
X473498D01*
G01X476778Y-9962D02*
X476351Y-10129D01*
X476031Y-10545D01*
X475818Y-11045D01*
X475658Y-11712D01*
X475605Y-12462D01*
X475658Y-13212D01*
X475818Y-13879D01*
X476031Y-14379D01*
X476351Y-14795D01*
X476778Y-14962D01*
X477205Y-14795D01*
X477525Y-14379D01*
X477738Y-13879D01*
X477898Y-13212D01*
X477951Y-12462D01*
X477898Y-11712D01*
X477738Y-11045D01*
X477525Y-10545D01*
X477205Y-10129D01*
X476778Y-9962D01*
G01X480165Y-12879D02*
X480538Y-12295D01*
X480858Y-11962D01*
X481285Y-11795D01*
X481658Y-11962D01*
X481925Y-12295D01*
X482138Y-12795D01*
X482191Y-13379D01*
X482138Y-13879D01*
X481925Y-14379D01*
X481605Y-14795D01*
X481231Y-14962D01*
X480805Y-14795D01*
X480431Y-14295D01*
X480218Y-13545D01*
X480165Y-12712D01*
X480271Y-11629D01*
X480431Y-11045D01*
X480698Y-10462D01*
X481071Y-10045D01*
X481445Y-9962D01*
X481818Y-10129D01*
X482085Y-10545D01*
G01X467309Y54541D02*
X466999Y54081D01*
X466792Y53544D01*
Y52931D01*
X467102Y52241D01*
X467619Y51704D01*
X468239Y51321D01*
X469272Y51014D01*
X470202Y50937D01*
X471132Y51091D01*
X471752Y51321D01*
X472372Y51781D01*
X472785Y52317D01*
X472992Y52854D01*
Y53391D01*
X472785Y53927D01*
X472475Y54387D01*
X472062Y54771D01*
G01X467825Y57597D02*
X467205Y58057D01*
X466895Y58594D01*
X466792Y59207D01*
X466999Y59974D01*
X467515Y60511D01*
X468135Y60664D01*
X468755Y60587D01*
X469272Y60281D01*
X470305Y58747D01*
X471029Y58057D01*
X472062Y57597D01*
X472992Y57444D01*
Y60664D01*
G01X467825Y63797D02*
X467205Y64257D01*
X466895Y64794D01*
X466792Y65407D01*
X466999Y66174D01*
X467515Y66711D01*
X468135Y66864D01*
X468755Y66787D01*
X469272Y66481D01*
X470305Y64947D01*
X471029Y64257D01*
X472062Y63797D01*
X472992Y63644D01*
Y66864D01*
G01X471752Y69767D02*
X472475Y70227D01*
X472889Y70841D01*
X472992Y71531D01*
X472889Y72144D01*
X472372Y72757D01*
X471752Y73141D01*
X471132Y73217D01*
X470409Y73064D01*
X469892Y72527D01*
X469685Y71991D01*
Y71301D01*
G01Y71991D02*
X469375Y72451D01*
X468859Y72834D01*
X468239Y72987D01*
X467619Y72834D01*
X467102Y72451D01*
X466792Y71761D01*
X466895Y71071D01*
X467309Y70381D01*
G01X483678Y103705D02*
X477478D01*
Y105621D01*
X477788Y106235D01*
X478201Y106618D01*
X479028Y106771D01*
X479855Y106618D01*
X480371Y106158D01*
X480681Y105621D01*
Y103705D01*
G01Y105621D02*
X483678Y106771D01*
G01X478511Y109981D02*
X477891Y110441D01*
X477581Y110978D01*
X477478Y111591D01*
X477685Y112358D01*
X478201Y112895D01*
X478821Y113048D01*
X479441Y112971D01*
X479958Y112665D01*
X480991Y111131D01*
X481715Y110441D01*
X482748Y109981D01*
X483678Y109828D01*
Y113048D01*
G01X477478Y117638D02*
X477685Y117025D01*
X478201Y116565D01*
X478821Y116258D01*
X479648Y116028D01*
X480578Y115951D01*
X481508Y116028D01*
X482335Y116258D01*
X482955Y116565D01*
X483471Y117025D01*
X483678Y117638D01*
X483471Y118251D01*
X482955Y118711D01*
X482335Y119018D01*
X481508Y119248D01*
X480578Y119325D01*
X479648Y119248D01*
X478821Y119018D01*
X478201Y118711D01*
X477685Y118251D01*
X477478Y117638D01*
G01X483678Y123685D02*
X482335Y123838D01*
X481198Y124068D01*
X480165Y124375D01*
X479028Y124758D01*
X477478Y125371D01*
Y122305D01*
G01X474678Y103705D02*
X468478D01*
Y105621D01*
X468788Y106235D01*
X469201Y106618D01*
X470028Y106771D01*
X470855Y106618D01*
X471371Y106158D01*
X471681Y105621D01*
Y103705D01*
G01Y105621D02*
X474678Y106771D01*
G01X469511Y109981D02*
X468891Y110441D01*
X468581Y110978D01*
X468478Y111591D01*
X468685Y112358D01*
X469201Y112895D01*
X469821Y113048D01*
X470441Y112971D01*
X470958Y112665D01*
X471991Y111131D01*
X472715Y110441D01*
X473748Y109981D01*
X474678Y109828D01*
Y113048D01*
G01Y117638D02*
X468478D01*
X469718Y116718D01*
G01X474678D02*
Y118558D01*
G01X473955Y122535D02*
X474471Y123071D01*
X474678Y123685D01*
X474471Y124298D01*
X473852Y124835D01*
X472921Y125218D01*
X471991Y125371D01*
X470855D01*
X469925Y125218D01*
X469098Y124835D01*
X468685Y124375D01*
X468478Y123838D01*
X468685Y123225D01*
X469098Y122765D01*
X469718Y122458D01*
X470545Y122305D01*
X471268Y122458D01*
X471991Y122841D01*
X472405Y123301D01*
X472508Y123838D01*
X472301Y124451D01*
X471785Y124911D01*
X470855Y125371D01*
G01X470745Y219470D02*
Y225670D01*
X472661D01*
X473275Y225360D01*
X473658Y224947D01*
X473811Y224120D01*
X473658Y223293D01*
X473198Y222777D01*
X472661Y222467D01*
X470745D01*
G01X472661D02*
X473811Y219470D01*
G01X477021Y224637D02*
X477481Y225257D01*
X478018Y225567D01*
X478631Y225670D01*
X479398Y225463D01*
X479935Y224947D01*
X480088Y224327D01*
X480011Y223707D01*
X479705Y223190D01*
X478171Y222157D01*
X477481Y221433D01*
X477021Y220400D01*
X476868Y219470D01*
X480088D01*
G01X483375Y220193D02*
X483911Y219677D01*
X484525Y219470D01*
X485138Y219677D01*
X485675Y220296D01*
X486058Y221227D01*
X486211Y222157D01*
Y223293D01*
X486058Y224223D01*
X485675Y225050D01*
X485215Y225463D01*
X484678Y225670D01*
X484065Y225463D01*
X483605Y225050D01*
X483298Y224430D01*
X483145Y223603D01*
X483298Y222880D01*
X483681Y222157D01*
X484141Y221743D01*
X484678Y221640D01*
X485291Y221847D01*
X485751Y222363D01*
X486211Y223293D01*
G01X489191Y220400D02*
X489651Y219883D01*
X490188Y219573D01*
X490878Y219470D01*
X491568Y219677D01*
X492105Y220090D01*
X492488Y220813D01*
X492565Y221640D01*
X492411Y222467D01*
X492028Y222983D01*
X491491Y223397D01*
X490955Y223500D01*
X490418Y223397D01*
X489728Y222983D01*
X489958Y225670D01*
X492028D01*
G01X464745Y396438D02*
Y402638D01*
X466661D01*
X467275Y402328D01*
X467658Y401915D01*
X467811Y401088D01*
X467658Y400261D01*
X467198Y399745D01*
X466661Y399435D01*
X464745D01*
G01X466661D02*
X467811Y396438D01*
G01X470791Y397678D02*
X471251Y396955D01*
X471865Y396541D01*
X472555Y396438D01*
X473168Y396541D01*
X473781Y397058D01*
X474165Y397678D01*
X474241Y398298D01*
X474088Y399021D01*
X473551Y399538D01*
X473015Y399745D01*
X472325D01*
G01X473015D02*
X473475Y400055D01*
X473858Y400571D01*
X474011Y401191D01*
X473858Y401811D01*
X473475Y402328D01*
X472785Y402638D01*
X472095Y402535D01*
X471405Y402121D01*
G01X478678Y396438D02*
Y402638D01*
X477758Y401398D01*
G01Y396438D02*
X479598D01*
G01X483575Y397161D02*
X484111Y396645D01*
X484725Y396438D01*
X485338Y396645D01*
X485875Y397264D01*
X486258Y398195D01*
X486411Y399125D01*
Y400261D01*
X486258Y401191D01*
X485875Y402018D01*
X485415Y402431D01*
X484878Y402638D01*
X484265Y402431D01*
X483805Y402018D01*
X483498Y401398D01*
X483345Y400571D01*
X483498Y399848D01*
X483881Y399125D01*
X484341Y398711D01*
X484878Y398608D01*
X485491Y398815D01*
X485951Y399331D01*
X486411Y400261D01*
G01X467965Y422121D02*
X467505Y422431D01*
X466968Y422638D01*
X466355D01*
X465665Y422328D01*
X465128Y421811D01*
X464745Y421191D01*
X464438Y420158D01*
X464361Y419228D01*
X464515Y418298D01*
X464745Y417678D01*
X465205Y417058D01*
X465741Y416645D01*
X466278Y416438D01*
X466815D01*
X467351Y416645D01*
X467811Y416955D01*
X468195Y417368D01*
G01X470791Y417678D02*
X471251Y416955D01*
X471865Y416541D01*
X472555Y416438D01*
X473168Y416541D01*
X473781Y417058D01*
X474165Y417678D01*
X474241Y418298D01*
X474088Y419021D01*
X473551Y419538D01*
X473015Y419745D01*
X472325D01*
G01X473015D02*
X473475Y420055D01*
X473858Y420571D01*
X474011Y421191D01*
X473858Y421811D01*
X473475Y422328D01*
X472785Y422638D01*
X472095Y422535D01*
X471405Y422121D01*
G01X478678Y416438D02*
Y422638D01*
X477758Y421398D01*
G01Y416438D02*
X479598D01*
G01X483191Y417368D02*
X483651Y416851D01*
X484188Y416541D01*
X484878Y416438D01*
X485568Y416645D01*
X486105Y417058D01*
X486488Y417781D01*
X486565Y418608D01*
X486411Y419435D01*
X486028Y419951D01*
X485491Y420365D01*
X484955Y420468D01*
X484418Y420365D01*
X483728Y419951D01*
X483958Y422638D01*
X486028D01*
G01X464745Y438502D02*
Y444702D01*
X466661D01*
X467275Y444392D01*
X467658Y443979D01*
X467811Y443152D01*
X467658Y442325D01*
X467198Y441809D01*
X466661Y441499D01*
X464745D01*
G01X466661D02*
X467811Y438502D01*
G01X470791Y439742D02*
X471251Y439019D01*
X471865Y438605D01*
X472555Y438502D01*
X473168Y438605D01*
X473781Y439122D01*
X474165Y439742D01*
X474241Y440362D01*
X474088Y441085D01*
X473551Y441602D01*
X473015Y441809D01*
X472325D01*
G01X473015D02*
X473475Y442119D01*
X473858Y442635D01*
X474011Y443255D01*
X473858Y443875D01*
X473475Y444392D01*
X472785Y444702D01*
X472095Y444599D01*
X471405Y444185D01*
G01X477221Y443669D02*
X477681Y444289D01*
X478218Y444599D01*
X478831Y444702D01*
X479598Y444495D01*
X480135Y443979D01*
X480288Y443359D01*
X480211Y442739D01*
X479905Y442222D01*
X478371Y441189D01*
X477681Y440465D01*
X477221Y439432D01*
X477068Y438502D01*
X480288D01*
G01X484878D02*
Y444702D01*
X483958Y443462D01*
G01Y438502D02*
X485798D01*
G01X464745Y448502D02*
Y454702D01*
X466661D01*
X467275Y454392D01*
X467658Y453979D01*
X467811Y453152D01*
X467658Y452325D01*
X467198Y451809D01*
X466661Y451499D01*
X464745D01*
G01X466661D02*
X467811Y448502D01*
G01X470791Y449742D02*
X471251Y449019D01*
X471865Y448605D01*
X472555Y448502D01*
X473168Y448605D01*
X473781Y449122D01*
X474165Y449742D01*
X474241Y450362D01*
X474088Y451085D01*
X473551Y451602D01*
X473015Y451809D01*
X472325D01*
G01X473015D02*
X473475Y452119D01*
X473858Y452635D01*
X474011Y453255D01*
X473858Y453875D01*
X473475Y454392D01*
X472785Y454702D01*
X472095Y454599D01*
X471405Y454185D01*
G01X477221Y453669D02*
X477681Y454289D01*
X478218Y454599D01*
X478831Y454702D01*
X479598Y454495D01*
X480135Y453979D01*
X480288Y453359D01*
X480211Y452739D01*
X479905Y452222D01*
X478371Y451189D01*
X477681Y450465D01*
X477221Y449432D01*
X477068Y448502D01*
X480288D01*
G01X483421Y453669D02*
X483881Y454289D01*
X484418Y454599D01*
X485031Y454702D01*
X485798Y454495D01*
X486335Y453979D01*
X486488Y453359D01*
X486411Y452739D01*
X486105Y452222D01*
X484571Y451189D01*
X483881Y450465D01*
X483421Y449432D01*
X483268Y448502D01*
X486488D01*
G01X484965Y-224879D02*
X484505Y-224569D01*
X483968Y-224362D01*
X483355D01*
X482665Y-224672D01*
X482128Y-225189D01*
X481745Y-225809D01*
X481438Y-226842D01*
X481361Y-227772D01*
X481515Y-228702D01*
X481745Y-229322D01*
X482205Y-229942D01*
X482741Y-230355D01*
X483278Y-230562D01*
X483815D01*
X484351Y-230355D01*
X484811Y-230045D01*
X485195Y-229632D01*
G01X488021Y-225395D02*
X488481Y-224775D01*
X489018Y-224465D01*
X489631Y-224362D01*
X490398Y-224569D01*
X490935Y-225085D01*
X491088Y-225705D01*
X491011Y-226325D01*
X490705Y-226842D01*
X489171Y-227875D01*
X488481Y-228599D01*
X488021Y-229632D01*
X487868Y-230562D01*
X491088D01*
G01X496598D02*
Y-224362D01*
X493761Y-228805D01*
X497595D01*
G01X502798Y-230562D02*
Y-224362D01*
X499961Y-228805D01*
X503795D01*
G01X492446Y-220195D02*
X498646D01*
Y-217129D01*
G01Y-212462D02*
X492446D01*
X493686Y-213382D01*
G01X498646D02*
Y-211542D01*
G01Y-205342D02*
X492446D01*
X496889Y-208179D01*
Y-204345D01*
G01X492995Y-193075D02*
X492685Y-193535D01*
X492478Y-194072D01*
Y-194685D01*
X492788Y-195375D01*
X493305Y-195912D01*
X493925Y-196295D01*
X494958Y-196602D01*
X495888Y-196679D01*
X496818Y-196525D01*
X497438Y-196295D01*
X498058Y-195835D01*
X498471Y-195299D01*
X498678Y-194762D01*
Y-194225D01*
X498471Y-193689D01*
X498161Y-193229D01*
X497748Y-192845D01*
G01X493511Y-190019D02*
X492891Y-189559D01*
X492581Y-189022D01*
X492478Y-188409D01*
X492685Y-187642D01*
X493201Y-187105D01*
X493821Y-186952D01*
X494441Y-187029D01*
X494958Y-187335D01*
X495991Y-188869D01*
X496715Y-189559D01*
X497748Y-190019D01*
X498678Y-190172D01*
Y-186952D01*
G01Y-181442D02*
X492478D01*
X496921Y-184279D01*
Y-180445D01*
G01X496095Y-177619D02*
X495371Y-177082D01*
X494958Y-176622D01*
X494751Y-176009D01*
X494958Y-175472D01*
X495371Y-175089D01*
X495991Y-174782D01*
X496715Y-174705D01*
X497335Y-174782D01*
X497955Y-175089D01*
X498471Y-175549D01*
X498678Y-176085D01*
X498471Y-176699D01*
X497852Y-177235D01*
X496921Y-177542D01*
X495888Y-177619D01*
X494545Y-177465D01*
X493821Y-177235D01*
X493098Y-176852D01*
X492581Y-176315D01*
X492478Y-175779D01*
X492685Y-175242D01*
X493201Y-174859D01*
G01X483995Y-193075D02*
X483685Y-193535D01*
X483478Y-194072D01*
Y-194685D01*
X483788Y-195375D01*
X484305Y-195912D01*
X484925Y-196295D01*
X485958Y-196602D01*
X486888Y-196679D01*
X487818Y-196525D01*
X488438Y-196295D01*
X489058Y-195835D01*
X489471Y-195299D01*
X489678Y-194762D01*
Y-194225D01*
X489471Y-193689D01*
X489161Y-193229D01*
X488748Y-192845D01*
G01X484511Y-190019D02*
X483891Y-189559D01*
X483581Y-189022D01*
X483478Y-188409D01*
X483685Y-187642D01*
X484201Y-187105D01*
X484821Y-186952D01*
X485441Y-187029D01*
X485958Y-187335D01*
X486991Y-188869D01*
X487715Y-189559D01*
X488748Y-190019D01*
X489678Y-190172D01*
Y-186952D01*
G01Y-181442D02*
X483478D01*
X487921Y-184279D01*
Y-180445D01*
G01X489678Y-176162D02*
X489575Y-175625D01*
X489265Y-175012D01*
X488748Y-174629D01*
X488025Y-174475D01*
X487301Y-174629D01*
X486681Y-175089D01*
X486371Y-175779D01*
Y-176545D01*
X486165Y-177005D01*
X485648Y-177389D01*
X484925Y-177542D01*
X484201Y-177312D01*
X483685Y-176775D01*
X483478Y-176162D01*
X483685Y-175549D01*
X484201Y-175012D01*
X484925Y-174782D01*
X485648Y-174935D01*
X486165Y-175319D01*
X486371Y-175779D01*
Y-176545D01*
X486681Y-177235D01*
X487301Y-177695D01*
X488025Y-177849D01*
X488748Y-177695D01*
X489265Y-177312D01*
X489575Y-176699D01*
X489678Y-176162D01*
G01X487995Y-88889D02*
X487745Y-89209D01*
X487578Y-89582D01*
Y-90009D01*
X487828Y-90489D01*
X488245Y-90862D01*
X488745Y-91129D01*
X489578Y-91342D01*
X490328Y-91395D01*
X491078Y-91289D01*
X491578Y-91129D01*
X492078Y-90809D01*
X492411Y-90435D01*
X492578Y-90062D01*
Y-89689D01*
X492411Y-89315D01*
X492161Y-88995D01*
X491828Y-88729D01*
G01X492578Y-85662D02*
X487578D01*
X488578Y-86302D01*
G01X492578D02*
Y-85022D01*
G01Y-80622D02*
X487578D01*
X491161Y-82595D01*
Y-79929D01*
G01X488411Y-77875D02*
X487911Y-77555D01*
X487661Y-77182D01*
X487578Y-76755D01*
X487745Y-76222D01*
X488161Y-75849D01*
X488661Y-75742D01*
X489161Y-75795D01*
X489578Y-76009D01*
X490411Y-77075D01*
X490995Y-77555D01*
X491828Y-77875D01*
X492578Y-77982D01*
Y-75742D01*
G01X487995Y-66889D02*
X487745Y-67209D01*
X487578Y-67582D01*
Y-68009D01*
X487828Y-68489D01*
X488245Y-68862D01*
X488745Y-69129D01*
X489578Y-69342D01*
X490328Y-69395D01*
X491078Y-69289D01*
X491578Y-69129D01*
X492078Y-68809D01*
X492411Y-68435D01*
X492578Y-68062D01*
Y-67689D01*
X492411Y-67315D01*
X492161Y-66995D01*
X491828Y-66729D01*
G01X492578Y-63662D02*
X487578D01*
X488578Y-64302D01*
G01X492578D02*
Y-63022D01*
G01X491578Y-60435D02*
X492161Y-60115D01*
X492495Y-59689D01*
X492578Y-59209D01*
X492495Y-58782D01*
X492078Y-58355D01*
X491578Y-58089D01*
X491078Y-58035D01*
X490495Y-58142D01*
X490078Y-58515D01*
X489911Y-58889D01*
Y-59369D01*
G01Y-58889D02*
X489661Y-58569D01*
X489245Y-58302D01*
X488745Y-58195D01*
X488245Y-58302D01*
X487828Y-58569D01*
X487578Y-59049D01*
X487661Y-59529D01*
X487995Y-60009D01*
G01X491578Y-56035D02*
X492161Y-55715D01*
X492495Y-55289D01*
X492578Y-54809D01*
X492495Y-54382D01*
X492078Y-53955D01*
X491578Y-53689D01*
X491078Y-53635D01*
X490495Y-53742D01*
X490078Y-54115D01*
X489911Y-54489D01*
Y-54969D01*
G01Y-54489D02*
X489661Y-54169D01*
X489245Y-53902D01*
X488745Y-53795D01*
X488245Y-53902D01*
X487828Y-54169D01*
X487578Y-54649D01*
X487661Y-55129D01*
X487995Y-55609D01*
G01X500151Y-56879D02*
X499831Y-56629D01*
X499458Y-56462D01*
X499031D01*
X498551Y-56712D01*
X498178Y-57129D01*
X497911Y-57629D01*
X497698Y-58462D01*
X497645Y-59212D01*
X497751Y-59962D01*
X497911Y-60462D01*
X498231Y-60962D01*
X498605Y-61295D01*
X498978Y-61462D01*
X499351D01*
X499725Y-61295D01*
X500045Y-61045D01*
X500311Y-60712D01*
G01X503378Y-61462D02*
Y-56462D01*
X502738Y-57462D01*
G01Y-61462D02*
X504018D01*
G01X508418D02*
Y-56462D01*
X506445Y-60045D01*
X509111D01*
G01X512178Y-61462D02*
Y-56462D01*
X511538Y-57462D01*
G01Y-61462D02*
X512818D01*
G01X488095Y-44889D02*
X487845Y-45209D01*
X487678Y-45582D01*
Y-46009D01*
X487928Y-46489D01*
X488345Y-46862D01*
X488845Y-47129D01*
X489678Y-47342D01*
X490428Y-47395D01*
X491178Y-47289D01*
X491678Y-47129D01*
X492178Y-46809D01*
X492511Y-46435D01*
X492678Y-46062D01*
Y-45689D01*
X492511Y-45315D01*
X492261Y-44995D01*
X491928Y-44729D01*
G01X492678Y-41662D02*
X487678D01*
X488678Y-42302D01*
G01X492678D02*
Y-41022D01*
G01Y-37262D02*
X487678D01*
X488678Y-37902D01*
G01X492678D02*
Y-36622D01*
G01Y-32222D02*
X487678D01*
X491261Y-34195D01*
Y-31529D01*
G01X499151Y-32879D02*
X498831Y-32629D01*
X498458Y-32462D01*
X498031D01*
X497551Y-32712D01*
X497178Y-33129D01*
X496911Y-33629D01*
X496698Y-34462D01*
X496645Y-35212D01*
X496751Y-35962D01*
X496911Y-36462D01*
X497231Y-36962D01*
X497605Y-37295D01*
X497978Y-37462D01*
X498351D01*
X498725Y-37295D01*
X499045Y-37045D01*
X499311Y-36712D01*
G01X502378Y-37462D02*
Y-32462D01*
X501738Y-33462D01*
G01Y-37462D02*
X503018D01*
G01X506778Y-32462D02*
X506351Y-32629D01*
X506031Y-33045D01*
X505818Y-33545D01*
X505658Y-34212D01*
X505605Y-34962D01*
X505658Y-35712D01*
X505818Y-36379D01*
X506031Y-36879D01*
X506351Y-37295D01*
X506778Y-37462D01*
X507205Y-37295D01*
X507525Y-36879D01*
X507738Y-36379D01*
X507898Y-35712D01*
X507951Y-34962D01*
X507898Y-34212D01*
X507738Y-33545D01*
X507525Y-33045D01*
X507205Y-32629D01*
X506778Y-32462D01*
G01X510271Y-36879D02*
X510645Y-37295D01*
X511071Y-37462D01*
X511498Y-37295D01*
X511871Y-36795D01*
X512138Y-36045D01*
X512245Y-35295D01*
Y-34379D01*
X512138Y-33629D01*
X511871Y-32962D01*
X511551Y-32629D01*
X511178Y-32462D01*
X510751Y-32629D01*
X510431Y-32962D01*
X510218Y-33462D01*
X510111Y-34129D01*
X510218Y-34712D01*
X510485Y-35295D01*
X510805Y-35629D01*
X511178Y-35712D01*
X511605Y-35545D01*
X511925Y-35129D01*
X512245Y-34379D01*
G01X487895Y-15689D02*
X487645Y-16009D01*
X487478Y-16382D01*
Y-16809D01*
X487728Y-17289D01*
X488145Y-17662D01*
X488645Y-17929D01*
X489478Y-18142D01*
X490228Y-18195D01*
X490978Y-18089D01*
X491478Y-17929D01*
X491978Y-17609D01*
X492311Y-17235D01*
X492478Y-16862D01*
Y-16489D01*
X492311Y-16115D01*
X492061Y-15795D01*
X491728Y-15529D01*
G01X492478Y-12462D02*
X487478D01*
X488478Y-13102D01*
G01X492478D02*
Y-11822D01*
G01Y-8062D02*
X487478D01*
X488478Y-8702D01*
G01X492478D02*
Y-7422D01*
G01X491728Y-4835D02*
X492145Y-4515D01*
X492395Y-4142D01*
X492478Y-3662D01*
X492311Y-3182D01*
X491978Y-2809D01*
X491395Y-2542D01*
X490728Y-2489D01*
X490061Y-2595D01*
X489645Y-2862D01*
X489311Y-3235D01*
X489228Y-3609D01*
X489311Y-3982D01*
X489645Y-4462D01*
X487478Y-4302D01*
Y-2862D01*
G01X499899Y-11167D02*
X499579Y-10917D01*
X499206Y-10750D01*
X498779D01*
X498299Y-11000D01*
X497926Y-11417D01*
X497659Y-11917D01*
X497446Y-12750D01*
X497393Y-13500D01*
X497499Y-14250D01*
X497659Y-14750D01*
X497979Y-15250D01*
X498353Y-15583D01*
X498726Y-15750D01*
X499099D01*
X499473Y-15583D01*
X499793Y-15333D01*
X500059Y-15000D01*
G01X502113Y-11583D02*
X502433Y-11083D01*
X502806Y-10833D01*
X503233Y-10750D01*
X503766Y-10917D01*
X504139Y-11333D01*
X504246Y-11833D01*
X504193Y-12333D01*
X503979Y-12750D01*
X502913Y-13583D01*
X502433Y-14167D01*
X502113Y-15000D01*
X502006Y-15750D01*
X504246D01*
G01X507526Y-10750D02*
X507099Y-10917D01*
X506779Y-11333D01*
X506566Y-11833D01*
X506406Y-12500D01*
X506353Y-13250D01*
X506406Y-14000D01*
X506566Y-14667D01*
X506779Y-15167D01*
X507099Y-15583D01*
X507526Y-15750D01*
X507953Y-15583D01*
X508273Y-15167D01*
X508486Y-14667D01*
X508646Y-14000D01*
X508699Y-13250D01*
X508646Y-12500D01*
X508486Y-11833D01*
X508273Y-11333D01*
X507953Y-10917D01*
X507526Y-10750D01*
G01X511926D02*
X511499Y-10917D01*
X511179Y-11333D01*
X510966Y-11833D01*
X510806Y-12500D01*
X510753Y-13250D01*
X510806Y-14000D01*
X510966Y-14667D01*
X511179Y-15167D01*
X511499Y-15583D01*
X511926Y-15750D01*
X512353Y-15583D01*
X512673Y-15167D01*
X512886Y-14667D01*
X513046Y-14000D01*
X513099Y-13250D01*
X513046Y-12500D01*
X512886Y-11833D01*
X512673Y-11333D01*
X512353Y-10917D01*
X511926Y-10750D01*
G01X487995Y6111D02*
X487745Y5791D01*
X487578Y5418D01*
Y4991D01*
X487828Y4511D01*
X488245Y4138D01*
X488745Y3871D01*
X489578Y3658D01*
X490328Y3605D01*
X491078Y3711D01*
X491578Y3871D01*
X492078Y4191D01*
X492411Y4565D01*
X492578Y4938D01*
Y5311D01*
X492411Y5685D01*
X492161Y6005D01*
X491828Y6271D01*
G01X492578Y9338D02*
X487578D01*
X488578Y8698D01*
G01X492578D02*
Y9978D01*
G01Y14378D02*
X487578D01*
X491161Y12405D01*
Y15071D01*
G01X492578Y18778D02*
X487578D01*
X491161Y16805D01*
Y19471D01*
G01X488995Y30111D02*
X488745Y29791D01*
X488578Y29418D01*
Y28991D01*
X488828Y28511D01*
X489245Y28138D01*
X489745Y27871D01*
X490578Y27658D01*
X491328Y27605D01*
X492078Y27711D01*
X492578Y27871D01*
X493078Y28191D01*
X493411Y28565D01*
X493578Y28938D01*
Y29311D01*
X493411Y29685D01*
X493161Y30005D01*
X492828Y30271D01*
G01X493578Y33338D02*
X488578D01*
X489578Y32698D01*
G01X493578D02*
Y33978D01*
G01Y38378D02*
X488578D01*
X492161Y36405D01*
Y39071D01*
G01X492995Y41231D02*
X493411Y41605D01*
X493578Y42031D01*
X493411Y42458D01*
X492911Y42831D01*
X492161Y43098D01*
X491411Y43205D01*
X490495D01*
X489745Y43098D01*
X489078Y42831D01*
X488745Y42511D01*
X488578Y42138D01*
X488745Y41711D01*
X489078Y41391D01*
X489578Y41178D01*
X490245Y41071D01*
X490828Y41178D01*
X491411Y41445D01*
X491745Y41765D01*
X491828Y42138D01*
X491661Y42565D01*
X491245Y42885D01*
X490495Y43205D01*
G01X490745Y436438D02*
Y442638D01*
X492661D01*
X493275Y442328D01*
X493658Y441915D01*
X493811Y441088D01*
X493658Y440261D01*
X493198Y439745D01*
X492661Y439435D01*
X490745D01*
G01X492661D02*
X493811Y436438D01*
G01X496791Y437678D02*
X497251Y436955D01*
X497865Y436541D01*
X498555Y436438D01*
X499168Y436541D01*
X499781Y437058D01*
X500165Y437678D01*
X500241Y438298D01*
X500088Y439021D01*
X499551Y439538D01*
X499015Y439745D01*
X498325D01*
G01X499015D02*
X499475Y440055D01*
X499858Y440571D01*
X500011Y441191D01*
X499858Y441811D01*
X499475Y442328D01*
X498785Y442638D01*
X498095Y442535D01*
X497405Y442121D01*
G01X504678Y436438D02*
Y442638D01*
X503758Y441398D01*
G01Y436438D02*
X505598D01*
G01X510725D02*
X510878Y437781D01*
X511108Y438918D01*
X511415Y439951D01*
X511798Y441088D01*
X512411Y442638D01*
X509345D01*
G01X490745Y446438D02*
Y452638D01*
X492661D01*
X493275Y452328D01*
X493658Y451915D01*
X493811Y451088D01*
X493658Y450261D01*
X493198Y449745D01*
X492661Y449435D01*
X490745D01*
G01X492661D02*
X493811Y446438D01*
G01X496791Y447678D02*
X497251Y446955D01*
X497865Y446541D01*
X498555Y446438D01*
X499168Y446541D01*
X499781Y447058D01*
X500165Y447678D01*
X500241Y448298D01*
X500088Y449021D01*
X499551Y449538D01*
X499015Y449745D01*
X498325D01*
G01X499015D02*
X499475Y450055D01*
X499858Y450571D01*
X500011Y451191D01*
X499858Y451811D01*
X499475Y452328D01*
X498785Y452638D01*
X498095Y452535D01*
X497405Y452121D01*
G01X504678Y446438D02*
Y452638D01*
X503758Y451398D01*
G01Y446438D02*
X505598D01*
G01X510878D02*
X511415Y446541D01*
X512028Y446851D01*
X512411Y447368D01*
X512565Y448091D01*
X512411Y448815D01*
X511951Y449435D01*
X511261Y449745D01*
X510495D01*
X510035Y449951D01*
X509651Y450468D01*
X509498Y451191D01*
X509728Y451915D01*
X510265Y452431D01*
X510878Y452638D01*
X511491Y452431D01*
X512028Y451915D01*
X512258Y451191D01*
X512105Y450468D01*
X511721Y449951D01*
X511261Y449745D01*
X510495D01*
X509805Y449435D01*
X509345Y448815D01*
X509191Y448091D01*
X509345Y447368D01*
X509728Y446851D01*
X510341Y446541D01*
X510878Y446438D01*
G01X507995Y-99889D02*
X507745Y-100209D01*
X507578Y-100582D01*
Y-101009D01*
X507828Y-101489D01*
X508245Y-101862D01*
X508745Y-102129D01*
X509578Y-102342D01*
X510328Y-102395D01*
X511078Y-102289D01*
X511578Y-102129D01*
X512078Y-101809D01*
X512411Y-101435D01*
X512578Y-101062D01*
Y-100689D01*
X512411Y-100315D01*
X512161Y-99995D01*
X511828Y-99729D01*
G01X508411Y-97675D02*
X507911Y-97355D01*
X507661Y-96982D01*
X507578Y-96555D01*
X507745Y-96022D01*
X508161Y-95649D01*
X508661Y-95542D01*
X509161Y-95595D01*
X509578Y-95809D01*
X510411Y-96875D01*
X510995Y-97355D01*
X511828Y-97675D01*
X512578Y-97782D01*
Y-95542D01*
G01X507578Y-92262D02*
X507745Y-92689D01*
X508161Y-93009D01*
X508661Y-93222D01*
X509328Y-93382D01*
X510078Y-93435D01*
X510828Y-93382D01*
X511495Y-93222D01*
X511995Y-93009D01*
X512411Y-92689D01*
X512578Y-92262D01*
X512411Y-91835D01*
X511995Y-91515D01*
X511495Y-91302D01*
X510828Y-91142D01*
X510078Y-91089D01*
X509328Y-91142D01*
X508661Y-91302D01*
X508161Y-91515D01*
X507745Y-91835D01*
X507578Y-92262D01*
G01X512578Y-87862D02*
X512495Y-87489D01*
X512245Y-87062D01*
X511828Y-86795D01*
X511245Y-86689D01*
X510661Y-86795D01*
X510161Y-87115D01*
X509911Y-87595D01*
Y-88129D01*
X509745Y-88449D01*
X509328Y-88715D01*
X508745Y-88822D01*
X508161Y-88662D01*
X507745Y-88289D01*
X507578Y-87862D01*
X507745Y-87435D01*
X508161Y-87062D01*
X508745Y-86902D01*
X509328Y-87009D01*
X509745Y-87275D01*
X509911Y-87595D01*
Y-88129D01*
X510161Y-88609D01*
X510661Y-88929D01*
X511245Y-89035D01*
X511828Y-88929D01*
X512245Y-88662D01*
X512495Y-88235D01*
X512578Y-87862D01*
G01X515647Y-74159D02*
X515327Y-73909D01*
X514954Y-73742D01*
X514527D01*
X514047Y-73992D01*
X513674Y-74409D01*
X513407Y-74909D01*
X513194Y-75742D01*
X513141Y-76492D01*
X513247Y-77242D01*
X513407Y-77742D01*
X513727Y-78242D01*
X514101Y-78575D01*
X514474Y-78742D01*
X514847D01*
X515221Y-78575D01*
X515541Y-78325D01*
X515807Y-77992D01*
G01X518874Y-78742D02*
Y-73742D01*
X518234Y-74742D01*
G01Y-78742D02*
X519514D01*
G01X523914D02*
Y-73742D01*
X521941Y-77325D01*
X524607D01*
G01X526661Y-76659D02*
X527034Y-76075D01*
X527354Y-75742D01*
X527781Y-75575D01*
X528154Y-75742D01*
X528421Y-76075D01*
X528634Y-76575D01*
X528687Y-77159D01*
X528634Y-77659D01*
X528421Y-78159D01*
X528101Y-78575D01*
X527727Y-78742D01*
X527301Y-78575D01*
X526927Y-78075D01*
X526714Y-77325D01*
X526661Y-76492D01*
X526767Y-75409D01*
X526927Y-74825D01*
X527194Y-74242D01*
X527567Y-73825D01*
X527941Y-73742D01*
X528314Y-73909D01*
X528581Y-74325D01*
G01X515647Y-66285D02*
X515327Y-66035D01*
X514954Y-65868D01*
X514527D01*
X514047Y-66118D01*
X513674Y-66535D01*
X513407Y-67035D01*
X513194Y-67868D01*
X513141Y-68618D01*
X513247Y-69368D01*
X513407Y-69868D01*
X513727Y-70368D01*
X514101Y-70701D01*
X514474Y-70868D01*
X514847D01*
X515221Y-70701D01*
X515541Y-70451D01*
X515807Y-70118D01*
G01X517861Y-66701D02*
X518181Y-66201D01*
X518554Y-65951D01*
X518981Y-65868D01*
X519514Y-66035D01*
X519887Y-66451D01*
X519994Y-66951D01*
X519941Y-67451D01*
X519727Y-67868D01*
X518661Y-68701D01*
X518181Y-69285D01*
X517861Y-70118D01*
X517754Y-70868D01*
X519994D01*
G01X523274Y-65868D02*
X522847Y-66035D01*
X522527Y-66451D01*
X522314Y-66951D01*
X522154Y-67618D01*
X522101Y-68368D01*
X522154Y-69118D01*
X522314Y-69785D01*
X522527Y-70285D01*
X522847Y-70701D01*
X523274Y-70868D01*
X523701Y-70701D01*
X524021Y-70285D01*
X524234Y-69785D01*
X524394Y-69118D01*
X524447Y-68368D01*
X524394Y-67618D01*
X524234Y-66951D01*
X524021Y-66451D01*
X523701Y-66035D01*
X523274Y-65868D01*
G01X528314Y-70868D02*
Y-65868D01*
X526341Y-69451D01*
X529007D01*
G01X506495Y-76889D02*
X506245Y-77209D01*
X506078Y-77582D01*
Y-78009D01*
X506328Y-78489D01*
X506745Y-78862D01*
X507245Y-79129D01*
X508078Y-79342D01*
X508828Y-79395D01*
X509578Y-79289D01*
X510078Y-79129D01*
X510578Y-78809D01*
X510911Y-78435D01*
X511078Y-78062D01*
Y-77689D01*
X510911Y-77315D01*
X510661Y-76995D01*
X510328Y-76729D01*
G01X511078Y-73662D02*
X506078D01*
X507078Y-74302D01*
G01X511078D02*
Y-73022D01*
G01X508995Y-70275D02*
X508411Y-69902D01*
X508078Y-69582D01*
X507911Y-69155D01*
X508078Y-68782D01*
X508411Y-68515D01*
X508911Y-68302D01*
X509495Y-68249D01*
X509995Y-68302D01*
X510495Y-68515D01*
X510911Y-68835D01*
X511078Y-69209D01*
X510911Y-69635D01*
X510411Y-70009D01*
X509661Y-70222D01*
X508828Y-70275D01*
X507745Y-70169D01*
X507161Y-70009D01*
X506578Y-69742D01*
X506161Y-69369D01*
X506078Y-68995D01*
X506245Y-68622D01*
X506661Y-68355D01*
G01X510495Y-65769D02*
X510911Y-65395D01*
X511078Y-64969D01*
X510911Y-64542D01*
X510411Y-64169D01*
X509661Y-63902D01*
X508911Y-63795D01*
X507995D01*
X507245Y-63902D01*
X506578Y-64169D01*
X506245Y-64489D01*
X506078Y-64862D01*
X506245Y-65289D01*
X506578Y-65609D01*
X507078Y-65822D01*
X507745Y-65929D01*
X508328Y-65822D01*
X508911Y-65555D01*
X509245Y-65235D01*
X509328Y-64862D01*
X509161Y-64435D01*
X508745Y-64115D01*
X507995Y-63795D01*
G01X515653Y-61385D02*
X515403Y-61705D01*
X515236Y-62078D01*
Y-62505D01*
X515486Y-62985D01*
X515903Y-63358D01*
X516403Y-63625D01*
X517236Y-63838D01*
X517986Y-63891D01*
X518736Y-63785D01*
X519236Y-63625D01*
X519736Y-63305D01*
X520069Y-62931D01*
X520236Y-62558D01*
Y-62185D01*
X520069Y-61811D01*
X519819Y-61491D01*
X519486Y-61225D01*
G01X520236Y-58158D02*
X515236D01*
X516236Y-58798D01*
G01X520236D02*
Y-57518D01*
G01X516069Y-54771D02*
X515569Y-54451D01*
X515319Y-54078D01*
X515236Y-53651D01*
X515403Y-53118D01*
X515819Y-52745D01*
X516319Y-52638D01*
X516819Y-52691D01*
X517236Y-52905D01*
X518069Y-53971D01*
X518653Y-54451D01*
X519486Y-54771D01*
X520236Y-54878D01*
Y-52638D01*
G01Y-49358D02*
X515236D01*
X516236Y-49998D01*
G01X520236D02*
Y-48718D01*
G01X507779Y-52511D02*
X507529Y-52831D01*
X507362Y-53204D01*
Y-53631D01*
X507612Y-54111D01*
X508029Y-54484D01*
X508529Y-54751D01*
X509362Y-54964D01*
X510112Y-55017D01*
X510862Y-54911D01*
X511362Y-54751D01*
X511862Y-54431D01*
X512195Y-54057D01*
X512362Y-53684D01*
Y-53311D01*
X512195Y-52937D01*
X511945Y-52617D01*
X511612Y-52351D01*
G01X512362Y-49284D02*
X507362D01*
X508362Y-49924D01*
G01X512362D02*
Y-48644D01*
G01X508195Y-45897D02*
X507695Y-45577D01*
X507445Y-45204D01*
X507362Y-44777D01*
X507529Y-44244D01*
X507945Y-43871D01*
X508445Y-43764D01*
X508945Y-43817D01*
X509362Y-44031D01*
X510195Y-45097D01*
X510779Y-45577D01*
X511612Y-45897D01*
X512362Y-46004D01*
Y-43764D01*
G01X507362Y-40484D02*
X507529Y-40911D01*
X507945Y-41231D01*
X508445Y-41444D01*
X509112Y-41604D01*
X509862Y-41657D01*
X510612Y-41604D01*
X511279Y-41444D01*
X511779Y-41231D01*
X512195Y-40911D01*
X512362Y-40484D01*
X512195Y-40057D01*
X511779Y-39737D01*
X511279Y-39524D01*
X510612Y-39364D01*
X509862Y-39311D01*
X509112Y-39364D01*
X508445Y-39524D01*
X507945Y-39737D01*
X507529Y-40057D01*
X507362Y-40484D01*
G01X514653Y-43635D02*
X514403Y-43955D01*
X514236Y-44328D01*
Y-44755D01*
X514486Y-45235D01*
X514903Y-45608D01*
X515403Y-45875D01*
X516236Y-46088D01*
X516986Y-46141D01*
X517736Y-46035D01*
X518236Y-45875D01*
X518736Y-45555D01*
X519069Y-45181D01*
X519236Y-44808D01*
Y-44435D01*
X519069Y-44061D01*
X518819Y-43741D01*
X518486Y-43475D01*
G01X519236Y-40408D02*
X514236D01*
X515236Y-41048D01*
G01X519236D02*
Y-39768D01*
G01X518486Y-37181D02*
X518903Y-36861D01*
X519153Y-36488D01*
X519236Y-36008D01*
X519069Y-35528D01*
X518736Y-35155D01*
X518153Y-34888D01*
X517486Y-34835D01*
X516819Y-34941D01*
X516403Y-35208D01*
X516069Y-35581D01*
X515986Y-35955D01*
X516069Y-36328D01*
X516403Y-36808D01*
X514236Y-36648D01*
Y-35208D01*
G01X517153Y-32621D02*
X516569Y-32248D01*
X516236Y-31928D01*
X516069Y-31501D01*
X516236Y-31128D01*
X516569Y-30861D01*
X517069Y-30648D01*
X517653Y-30595D01*
X518153Y-30648D01*
X518653Y-30861D01*
X519069Y-31181D01*
X519236Y-31555D01*
X519069Y-31981D01*
X518569Y-32355D01*
X517819Y-32568D01*
X516986Y-32621D01*
X515903Y-32515D01*
X515319Y-32355D01*
X514736Y-32088D01*
X514319Y-31715D01*
X514236Y-31341D01*
X514403Y-30968D01*
X514819Y-30701D01*
G01X499909Y-52509D02*
X499659Y-52829D01*
X499492Y-53202D01*
Y-53629D01*
X499742Y-54109D01*
X500159Y-54482D01*
X500659Y-54749D01*
X501492Y-54962D01*
X502242Y-55015D01*
X502992Y-54909D01*
X503492Y-54749D01*
X503992Y-54429D01*
X504325Y-54055D01*
X504492Y-53682D01*
Y-53309D01*
X504325Y-52935D01*
X504075Y-52615D01*
X503742Y-52349D01*
G01X504492Y-49282D02*
X499492D01*
X500492Y-49922D01*
G01X504492D02*
Y-48642D01*
G01X502409Y-45895D02*
X501825Y-45522D01*
X501492Y-45202D01*
X501325Y-44775D01*
X501492Y-44402D01*
X501825Y-44135D01*
X502325Y-43922D01*
X502909Y-43869D01*
X503409Y-43922D01*
X503909Y-44135D01*
X504325Y-44455D01*
X504492Y-44829D01*
X504325Y-45255D01*
X503825Y-45629D01*
X503075Y-45842D01*
X502242Y-45895D01*
X501159Y-45789D01*
X500575Y-45629D01*
X499992Y-45362D01*
X499575Y-44989D01*
X499492Y-44615D01*
X499659Y-44242D01*
X500075Y-43975D01*
G01X502409Y-41495D02*
X501825Y-41122D01*
X501492Y-40802D01*
X501325Y-40375D01*
X501492Y-40002D01*
X501825Y-39735D01*
X502325Y-39522D01*
X502909Y-39469D01*
X503409Y-39522D01*
X503909Y-39735D01*
X504325Y-40055D01*
X504492Y-40429D01*
X504325Y-40855D01*
X503825Y-41229D01*
X503075Y-41442D01*
X502242Y-41495D01*
X501159Y-41389D01*
X500575Y-41229D01*
X499992Y-40962D01*
X499575Y-40589D01*
X499492Y-40215D01*
X499659Y-39842D01*
X500075Y-39575D01*
G01X501151Y-21979D02*
X500831Y-21729D01*
X500458Y-21562D01*
X500031D01*
X499551Y-21812D01*
X499178Y-22229D01*
X498911Y-22729D01*
X498698Y-23562D01*
X498645Y-24312D01*
X498751Y-25062D01*
X498911Y-25562D01*
X499231Y-26062D01*
X499605Y-26395D01*
X499978Y-26562D01*
X500351D01*
X500725Y-26395D01*
X501045Y-26145D01*
X501311Y-25812D01*
G01X503365Y-22395D02*
X503685Y-21895D01*
X504058Y-21645D01*
X504485Y-21562D01*
X505018Y-21729D01*
X505391Y-22145D01*
X505498Y-22645D01*
X505445Y-23145D01*
X505231Y-23562D01*
X504165Y-24395D01*
X503685Y-24979D01*
X503365Y-25812D01*
X503258Y-26562D01*
X505498D01*
G01X508778D02*
Y-21562D01*
X508138Y-22562D01*
G01Y-26562D02*
X509418D01*
G01X512271Y-25979D02*
X512645Y-26395D01*
X513071Y-26562D01*
X513498Y-26395D01*
X513871Y-25895D01*
X514138Y-25145D01*
X514245Y-24395D01*
Y-23479D01*
X514138Y-22729D01*
X513871Y-22062D01*
X513551Y-21729D01*
X513178Y-21562D01*
X512751Y-21729D01*
X512431Y-22062D01*
X512218Y-22562D01*
X512111Y-23229D01*
X512218Y-23812D01*
X512485Y-24395D01*
X512805Y-24729D01*
X513178Y-24812D01*
X513605Y-24645D01*
X513925Y-24229D01*
X514245Y-23479D01*
G01X506995Y-889D02*
X506745Y-1209D01*
X506578Y-1582D01*
Y-2009D01*
X506828Y-2489D01*
X507245Y-2862D01*
X507745Y-3129D01*
X508578Y-3342D01*
X509328Y-3395D01*
X510078Y-3289D01*
X510578Y-3129D01*
X511078Y-2809D01*
X511411Y-2435D01*
X511578Y-2062D01*
Y-1689D01*
X511411Y-1315D01*
X511161Y-995D01*
X510828Y-729D01*
G01X507411Y1325D02*
X506911Y1645D01*
X506661Y2018D01*
X506578Y2445D01*
X506745Y2978D01*
X507161Y3351D01*
X507661Y3458D01*
X508161Y3405D01*
X508578Y3191D01*
X509411Y2125D01*
X509995Y1645D01*
X510828Y1325D01*
X511578Y1218D01*
Y3458D01*
G01X507411Y5725D02*
X506911Y6045D01*
X506661Y6418D01*
X506578Y6845D01*
X506745Y7378D01*
X507161Y7751D01*
X507661Y7858D01*
X508161Y7805D01*
X508578Y7591D01*
X509411Y6525D01*
X509995Y6045D01*
X510828Y5725D01*
X511578Y5618D01*
Y7858D01*
G01Y11138D02*
X506578D01*
X507578Y10498D01*
G01X511578D02*
Y11778D01*
G01X513995Y16111D02*
X513745Y15791D01*
X513578Y15418D01*
Y14991D01*
X513828Y14511D01*
X514245Y14138D01*
X514745Y13871D01*
X515578Y13658D01*
X516328Y13605D01*
X517078Y13711D01*
X517578Y13871D01*
X518078Y14191D01*
X518411Y14565D01*
X518578Y14938D01*
Y15311D01*
X518411Y15685D01*
X518161Y16005D01*
X517828Y16271D01*
G01X518578Y19338D02*
X513578D01*
X514578Y18698D01*
G01X518578D02*
Y19978D01*
G01Y23738D02*
X513578D01*
X514578Y23098D01*
G01X518578D02*
Y24378D01*
G01X517995Y27231D02*
X518411Y27605D01*
X518578Y28031D01*
X518411Y28458D01*
X517911Y28831D01*
X517161Y29098D01*
X516411Y29205D01*
X515495D01*
X514745Y29098D01*
X514078Y28831D01*
X513745Y28511D01*
X513578Y28138D01*
X513745Y27711D01*
X514078Y27391D01*
X514578Y27178D01*
X515245Y27071D01*
X515828Y27178D01*
X516411Y27445D01*
X516745Y27765D01*
X516828Y28138D01*
X516661Y28565D01*
X516245Y28885D01*
X515495Y29205D01*
G01X518151Y37121D02*
X517831Y37371D01*
X517458Y37538D01*
X517031D01*
X516551Y37288D01*
X516178Y36871D01*
X515911Y36371D01*
X515698Y35538D01*
X515645Y34788D01*
X515751Y34038D01*
X515911Y33538D01*
X516231Y33038D01*
X516605Y32705D01*
X516978Y32538D01*
X517351D01*
X517725Y32705D01*
X518045Y32955D01*
X518311Y33288D01*
G01X521378Y32538D02*
Y37538D01*
X520738Y36538D01*
G01Y32538D02*
X522018D01*
G01X525778D02*
Y37538D01*
X525138Y36538D01*
G01Y32538D02*
X526418D01*
G01X529165Y36705D02*
X529485Y37205D01*
X529858Y37455D01*
X530285Y37538D01*
X530818Y37371D01*
X531191Y36955D01*
X531298Y36455D01*
X531245Y35955D01*
X531031Y35538D01*
X529965Y34705D01*
X529485Y34121D01*
X529165Y33288D01*
X529058Y32538D01*
X531298D01*
G01X498809Y46667D02*
X498499Y46207D01*
X498292Y45670D01*
Y45057D01*
X498602Y44367D01*
X499119Y43830D01*
X499739Y43447D01*
X500772Y43140D01*
X501702Y43063D01*
X502632Y43217D01*
X503252Y43447D01*
X503872Y43907D01*
X504285Y44443D01*
X504492Y44980D01*
Y45517D01*
X504285Y46053D01*
X503975Y46513D01*
X503562Y46897D01*
G01X504492Y51180D02*
X498292D01*
X499532Y50260D01*
G01X504492D02*
Y52100D01*
G01X501909Y55923D02*
X501185Y56460D01*
X500772Y56920D01*
X500565Y57533D01*
X500772Y58070D01*
X501185Y58453D01*
X501805Y58760D01*
X502529Y58837D01*
X503149Y58760D01*
X503769Y58453D01*
X504285Y57993D01*
X504492Y57457D01*
X504285Y56843D01*
X503666Y56307D01*
X502735Y56000D01*
X501702Y55923D01*
X500359Y56077D01*
X499635Y56307D01*
X498912Y56690D01*
X498395Y57227D01*
X498292Y57763D01*
X498499Y58300D01*
X499015Y58683D01*
G01X499325Y62123D02*
X498705Y62583D01*
X498395Y63120D01*
X498292Y63733D01*
X498499Y64500D01*
X499015Y65037D01*
X499635Y65190D01*
X500255Y65113D01*
X500772Y64807D01*
X501805Y63273D01*
X502529Y62583D01*
X503562Y62123D01*
X504492Y61970D01*
Y65190D01*
G01X510846Y121905D02*
X504646D01*
Y123821D01*
X504956Y124435D01*
X505369Y124818D01*
X506196Y124971D01*
X507023Y124818D01*
X507539Y124358D01*
X507849Y123821D01*
Y121905D01*
G01Y123821D02*
X510846Y124971D01*
G01X509606Y127951D02*
X510329Y128411D01*
X510743Y129025D01*
X510846Y129715D01*
X510743Y130328D01*
X510226Y130941D01*
X509606Y131325D01*
X508986Y131401D01*
X508263Y131248D01*
X507746Y130711D01*
X507539Y130175D01*
Y129485D01*
G01Y130175D02*
X507229Y130635D01*
X506713Y131018D01*
X506093Y131171D01*
X505473Y131018D01*
X504956Y130635D01*
X504646Y129945D01*
X504749Y129255D01*
X505163Y128565D01*
G01X505679Y134381D02*
X505059Y134841D01*
X504749Y135378D01*
X504646Y135991D01*
X504853Y136758D01*
X505369Y137295D01*
X505989Y137448D01*
X506609Y137371D01*
X507126Y137065D01*
X508159Y135531D01*
X508883Y134841D01*
X509916Y134381D01*
X510846Y134228D01*
Y137448D01*
G01X508263Y140581D02*
X507539Y141118D01*
X507126Y141578D01*
X506919Y142191D01*
X507126Y142728D01*
X507539Y143111D01*
X508159Y143418D01*
X508883Y143495D01*
X509503Y143418D01*
X510123Y143111D01*
X510639Y142651D01*
X510846Y142115D01*
X510639Y141501D01*
X510020Y140965D01*
X509089Y140658D01*
X508056Y140581D01*
X506713Y140735D01*
X505989Y140965D01*
X505266Y141348D01*
X504749Y141885D01*
X504646Y142421D01*
X504853Y142958D01*
X505369Y143341D01*
G01X509565Y200121D02*
X509105Y200431D01*
X508568Y200638D01*
X507955D01*
X507265Y200328D01*
X506728Y199811D01*
X506345Y199191D01*
X506038Y198158D01*
X505961Y197228D01*
X506115Y196298D01*
X506345Y195678D01*
X506805Y195058D01*
X507341Y194645D01*
X507878Y194438D01*
X508415D01*
X508951Y194645D01*
X509411Y194955D01*
X509795Y195368D01*
G01X512621Y199605D02*
X513081Y200225D01*
X513618Y200535D01*
X514231Y200638D01*
X514998Y200431D01*
X515535Y199915D01*
X515688Y199295D01*
X515611Y198675D01*
X515305Y198158D01*
X513771Y197125D01*
X513081Y196401D01*
X512621Y195368D01*
X512468Y194438D01*
X515688D01*
G01X521198D02*
Y200638D01*
X518361Y196195D01*
X522195D01*
G01X524791Y195678D02*
X525251Y194955D01*
X525865Y194541D01*
X526555Y194438D01*
X527168Y194541D01*
X527781Y195058D01*
X528165Y195678D01*
X528241Y196298D01*
X528088Y197021D01*
X527551Y197538D01*
X527015Y197745D01*
X526325D01*
G01X527015D02*
X527475Y198055D01*
X527858Y198571D01*
X528011Y199191D01*
X527858Y199811D01*
X527475Y200328D01*
X526785Y200638D01*
X526095Y200535D01*
X525405Y200121D01*
G01X509565Y216321D02*
X509105Y216631D01*
X508568Y216838D01*
X507955D01*
X507265Y216528D01*
X506728Y216011D01*
X506345Y215391D01*
X506038Y214358D01*
X505961Y213428D01*
X506115Y212498D01*
X506345Y211878D01*
X506805Y211258D01*
X507341Y210845D01*
X507878Y210638D01*
X508415D01*
X508951Y210845D01*
X509411Y211155D01*
X509795Y211568D01*
G01X512621Y215805D02*
X513081Y216425D01*
X513618Y216735D01*
X514231Y216838D01*
X514998Y216631D01*
X515535Y216115D01*
X515688Y215495D01*
X515611Y214875D01*
X515305Y214358D01*
X513771Y213325D01*
X513081Y212601D01*
X512621Y211568D01*
X512468Y210638D01*
X515688D01*
G01X521198D02*
Y216838D01*
X518361Y212395D01*
X522195D01*
G01X526478Y210638D02*
Y216838D01*
X525558Y215598D01*
G01Y210638D02*
X527398D01*
G01X512963Y308925D02*
X512653Y308465D01*
X512446Y307928D01*
Y307315D01*
X512756Y306625D01*
X513273Y306088D01*
X513893Y305705D01*
X514926Y305398D01*
X515856Y305321D01*
X516786Y305475D01*
X517406Y305705D01*
X518026Y306165D01*
X518439Y306701D01*
X518646Y307238D01*
Y307775D01*
X518439Y308311D01*
X518129Y308771D01*
X517716Y309155D01*
G01X518646Y313438D02*
X512446D01*
X513686Y312518D01*
G01X518646D02*
Y314358D01*
G01X512446Y319638D02*
X512653Y319025D01*
X513169Y318565D01*
X513789Y318258D01*
X514616Y318028D01*
X515546Y317951D01*
X516476Y318028D01*
X517303Y318258D01*
X517923Y318565D01*
X518439Y319025D01*
X518646Y319638D01*
X518439Y320251D01*
X517923Y320711D01*
X517303Y321018D01*
X516476Y321248D01*
X515546Y321325D01*
X514616Y321248D01*
X513789Y321018D01*
X513169Y320711D01*
X512653Y320251D01*
X512446Y319638D01*
G01X513479Y324381D02*
X512859Y324841D01*
X512549Y325378D01*
X512446Y325991D01*
X512653Y326758D01*
X513169Y327295D01*
X513789Y327448D01*
X514409Y327371D01*
X514926Y327065D01*
X515959Y325531D01*
X516683Y324841D01*
X517716Y324381D01*
X518646Y324228D01*
Y327448D01*
G01X499995Y411325D02*
X499685Y410865D01*
X499478Y410328D01*
Y409715D01*
X499788Y409025D01*
X500305Y408488D01*
X500925Y408105D01*
X501958Y407798D01*
X502888Y407721D01*
X503818Y407875D01*
X504438Y408105D01*
X505058Y408565D01*
X505471Y409101D01*
X505678Y409638D01*
Y410175D01*
X505471Y410711D01*
X505161Y411171D01*
X504748Y411555D01*
G01X504438Y414151D02*
X505161Y414611D01*
X505575Y415225D01*
X505678Y415915D01*
X505575Y416528D01*
X505058Y417141D01*
X504438Y417525D01*
X503818Y417601D01*
X503095Y417448D01*
X502578Y416911D01*
X502371Y416375D01*
Y415685D01*
G01Y416375D02*
X502061Y416835D01*
X501545Y417218D01*
X500925Y417371D01*
X500305Y417218D01*
X499788Y416835D01*
X499478Y416145D01*
X499581Y415455D01*
X499995Y414765D01*
G01X505678Y422038D02*
X499478D01*
X500718Y421118D01*
G01X505678D02*
Y422958D01*
G01X503095Y426781D02*
X502371Y427318D01*
X501958Y427778D01*
X501751Y428391D01*
X501958Y428928D01*
X502371Y429311D01*
X502991Y429618D01*
X503715Y429695D01*
X504335Y429618D01*
X504955Y429311D01*
X505471Y428851D01*
X505678Y428315D01*
X505471Y427701D01*
X504852Y427165D01*
X503921Y426858D01*
X502888Y426781D01*
X501545Y426935D01*
X500821Y427165D01*
X500098Y427548D01*
X499581Y428085D01*
X499478Y428621D01*
X499685Y429158D01*
X500201Y429541D01*
G01X525519Y-58411D02*
X525199Y-58161D01*
X524826Y-57994D01*
X524399D01*
X523919Y-58244D01*
X523546Y-58661D01*
X523279Y-59161D01*
X523066Y-59994D01*
X523013Y-60744D01*
X523119Y-61494D01*
X523279Y-61994D01*
X523599Y-62494D01*
X523973Y-62827D01*
X524346Y-62994D01*
X524719D01*
X525093Y-62827D01*
X525413Y-62577D01*
X525679Y-62244D01*
G01X528746Y-62994D02*
Y-57994D01*
X528106Y-58994D01*
G01Y-62994D02*
X529386D01*
G01X533146D02*
Y-57994D01*
X532506Y-58994D01*
G01Y-62994D02*
X533786D01*
G01X537546D02*
X537919Y-62911D01*
X538346Y-62661D01*
X538613Y-62244D01*
X538719Y-61661D01*
X538613Y-61077D01*
X538293Y-60577D01*
X537813Y-60327D01*
X537279D01*
X536959Y-60161D01*
X536693Y-59744D01*
X536586Y-59161D01*
X536746Y-58577D01*
X537119Y-58161D01*
X537546Y-57994D01*
X537973Y-58161D01*
X538346Y-58577D01*
X538506Y-59161D01*
X538399Y-59744D01*
X538133Y-60161D01*
X537813Y-60327D01*
X537279D01*
X536799Y-60577D01*
X536479Y-61077D01*
X536373Y-61661D01*
X536479Y-62244D01*
X536746Y-62661D01*
X537173Y-62911D01*
X537546Y-62994D01*
G01X525519Y-50537D02*
X525199Y-50287D01*
X524826Y-50120D01*
X524399D01*
X523919Y-50370D01*
X523546Y-50787D01*
X523279Y-51287D01*
X523066Y-52120D01*
X523013Y-52870D01*
X523119Y-53620D01*
X523279Y-54120D01*
X523599Y-54620D01*
X523973Y-54953D01*
X524346Y-55120D01*
X524719D01*
X525093Y-54953D01*
X525413Y-54703D01*
X525679Y-54370D01*
G01X528746Y-55120D02*
Y-50120D01*
X528106Y-51120D01*
G01Y-55120D02*
X529386D01*
G01X533146D02*
Y-50120D01*
X532506Y-51120D01*
G01Y-55120D02*
X533786D01*
G01X537546D02*
Y-50120D01*
X536906Y-51120D01*
G01Y-55120D02*
X538186D01*
G01X522523Y-43637D02*
X522273Y-43957D01*
X522106Y-44330D01*
Y-44757D01*
X522356Y-45237D01*
X522773Y-45610D01*
X523273Y-45877D01*
X524106Y-46090D01*
X524856Y-46143D01*
X525606Y-46037D01*
X526106Y-45877D01*
X526606Y-45557D01*
X526939Y-45183D01*
X527106Y-44810D01*
Y-44437D01*
X526939Y-44063D01*
X526689Y-43743D01*
X526356Y-43477D01*
G01X522939Y-41423D02*
X522439Y-41103D01*
X522189Y-40730D01*
X522106Y-40303D01*
X522273Y-39770D01*
X522689Y-39397D01*
X523189Y-39290D01*
X523689Y-39343D01*
X524106Y-39557D01*
X524939Y-40623D01*
X525523Y-41103D01*
X526356Y-41423D01*
X527106Y-41530D01*
Y-39290D01*
G01X522939Y-37023D02*
X522439Y-36703D01*
X522189Y-36330D01*
X522106Y-35903D01*
X522273Y-35370D01*
X522689Y-34997D01*
X523189Y-34890D01*
X523689Y-34943D01*
X524106Y-35157D01*
X524939Y-36223D01*
X525523Y-36703D01*
X526356Y-37023D01*
X527106Y-37130D01*
Y-34890D01*
G01X522939Y-32623D02*
X522439Y-32303D01*
X522189Y-31930D01*
X522106Y-31503D01*
X522273Y-30970D01*
X522689Y-30597D01*
X523189Y-30490D01*
X523689Y-30543D01*
X524106Y-30757D01*
X524939Y-31823D01*
X525523Y-32303D01*
X526356Y-32623D01*
X527106Y-32730D01*
Y-30490D01*
G01X531911Y-37462D02*
Y-32462D01*
X533245D01*
X533671Y-32712D01*
X533938Y-33045D01*
X534045Y-33712D01*
X533938Y-34379D01*
X533618Y-34795D01*
X533245Y-35045D01*
X531911D01*
G01X533245D02*
X534045Y-37462D01*
G01X537378D02*
Y-32462D01*
X536738Y-33462D01*
G01Y-37462D02*
X538018D01*
G01X540871Y-36879D02*
X541245Y-37295D01*
X541671Y-37462D01*
X542098Y-37295D01*
X542471Y-36795D01*
X542738Y-36045D01*
X542845Y-35295D01*
Y-34379D01*
X542738Y-33629D01*
X542471Y-32962D01*
X542151Y-32629D01*
X541778Y-32462D01*
X541351Y-32629D01*
X541031Y-32962D01*
X540818Y-33462D01*
X540711Y-34129D01*
X540818Y-34712D01*
X541085Y-35295D01*
X541405Y-35629D01*
X541778Y-35712D01*
X542205Y-35545D01*
X542525Y-35129D01*
X542845Y-34379D01*
G01X546178Y-37462D02*
X546551Y-37379D01*
X546978Y-37129D01*
X547245Y-36712D01*
X547351Y-36129D01*
X547245Y-35545D01*
X546925Y-35045D01*
X546445Y-34795D01*
X545911D01*
X545591Y-34629D01*
X545325Y-34212D01*
X545218Y-33629D01*
X545378Y-33045D01*
X545751Y-32629D01*
X546178Y-32462D01*
X546605Y-32629D01*
X546978Y-33045D01*
X547138Y-33629D01*
X547031Y-34212D01*
X546765Y-34629D01*
X546445Y-34795D01*
X545911D01*
X545431Y-35045D01*
X545111Y-35545D01*
X545005Y-36129D01*
X545111Y-36712D01*
X545378Y-37129D01*
X545805Y-37379D01*
X546178Y-37462D01*
G01X525965Y-20779D02*
X525505Y-20469D01*
X524968Y-20262D01*
X524355D01*
X523665Y-20572D01*
X523128Y-21089D01*
X522745Y-21709D01*
X522438Y-22742D01*
X522361Y-23672D01*
X522515Y-24602D01*
X522745Y-25222D01*
X523205Y-25842D01*
X523741Y-26255D01*
X524278Y-26462D01*
X524815D01*
X525351Y-26255D01*
X525811Y-25945D01*
X526195Y-25532D01*
G01X530478Y-26462D02*
Y-20262D01*
X529558Y-21502D01*
G01Y-26462D02*
X531398D01*
G01X536678D02*
Y-20262D01*
X535758Y-21502D01*
G01Y-26462D02*
X537598D01*
G01X541191Y-25222D02*
X541651Y-25945D01*
X542265Y-26359D01*
X542955Y-26462D01*
X543568Y-26359D01*
X544181Y-25842D01*
X544565Y-25222D01*
X544641Y-24602D01*
X544488Y-23879D01*
X543951Y-23362D01*
X543415Y-23155D01*
X542725D01*
G01X543415D02*
X543875Y-22845D01*
X544258Y-22329D01*
X544411Y-21709D01*
X544258Y-21089D01*
X543875Y-20572D01*
X543185Y-20262D01*
X542495Y-20365D01*
X541805Y-20779D01*
G01X523521Y20329D02*
X523201Y20579D01*
X522828Y20746D01*
X522401D01*
X521921Y20496D01*
X521548Y20079D01*
X521281Y19579D01*
X521068Y18746D01*
X521015Y17996D01*
X521121Y17246D01*
X521281Y16746D01*
X521601Y16246D01*
X521975Y15913D01*
X522348Y15746D01*
X522721D01*
X523095Y15913D01*
X523415Y16163D01*
X523681Y16496D01*
G01X526748Y15746D02*
Y20746D01*
X526108Y19746D01*
G01Y15746D02*
X527388D01*
G01X529975Y16496D02*
X530295Y16079D01*
X530668Y15829D01*
X531148Y15746D01*
X531628Y15913D01*
X532001Y16246D01*
X532268Y16829D01*
X532321Y17496D01*
X532215Y18163D01*
X531948Y18579D01*
X531575Y18913D01*
X531201Y18996D01*
X530828Y18913D01*
X530348Y18579D01*
X530508Y20746D01*
X531948D01*
G01X534375Y16746D02*
X534695Y16163D01*
X535121Y15829D01*
X535601Y15746D01*
X536028Y15829D01*
X536455Y16246D01*
X536721Y16746D01*
X536775Y17246D01*
X536668Y17829D01*
X536295Y18246D01*
X535921Y18413D01*
X535441D01*
G01X535921D02*
X536241Y18663D01*
X536508Y19079D01*
X536615Y19579D01*
X536508Y20079D01*
X536241Y20496D01*
X535761Y20746D01*
X535281Y20663D01*
X534801Y20329D01*
G01X533965Y72121D02*
X533505Y72431D01*
X532968Y72638D01*
X532355D01*
X531665Y72328D01*
X531128Y71811D01*
X530745Y71191D01*
X530438Y70158D01*
X530361Y69228D01*
X530515Y68298D01*
X530745Y67678D01*
X531205Y67058D01*
X531741Y66645D01*
X532278Y66438D01*
X532815D01*
X533351Y66645D01*
X533811Y66955D01*
X534195Y67368D01*
G01X538478Y66438D02*
Y72638D01*
X537558Y71398D01*
G01Y66438D02*
X539398D01*
G01X542991Y67368D02*
X543451Y66851D01*
X543988Y66541D01*
X544678Y66438D01*
X545368Y66645D01*
X545905Y67058D01*
X546288Y67781D01*
X546365Y68608D01*
X546211Y69435D01*
X545828Y69951D01*
X545291Y70365D01*
X544755Y70468D01*
X544218Y70365D01*
X543528Y69951D01*
X543758Y72638D01*
X545828D01*
G01X549575Y67161D02*
X550111Y66645D01*
X550725Y66438D01*
X551338Y66645D01*
X551875Y67264D01*
X552258Y68195D01*
X552411Y69125D01*
Y70261D01*
X552258Y71191D01*
X551875Y72018D01*
X551415Y72431D01*
X550878Y72638D01*
X550265Y72431D01*
X549805Y72018D01*
X549498Y71398D01*
X549345Y70571D01*
X549498Y69848D01*
X549881Y69125D01*
X550341Y68711D01*
X550878Y68608D01*
X551491Y68815D01*
X551951Y69331D01*
X552411Y70261D01*
G01X535965Y94121D02*
X535505Y94431D01*
X534968Y94638D01*
X534355D01*
X533665Y94328D01*
X533128Y93811D01*
X532745Y93191D01*
X532438Y92158D01*
X532361Y91228D01*
X532515Y90298D01*
X532745Y89678D01*
X533205Y89058D01*
X533741Y88645D01*
X534278Y88438D01*
X534815D01*
X535351Y88645D01*
X535811Y88955D01*
X536195Y89368D01*
G01X540478Y88438D02*
Y94638D01*
X539558Y93398D01*
G01Y88438D02*
X541398D01*
G01X546525D02*
X546678Y89781D01*
X546908Y90918D01*
X547215Y91951D01*
X547598Y93088D01*
X548211Y94638D01*
X545145D01*
G01X551421Y93605D02*
X551881Y94225D01*
X552418Y94535D01*
X553031Y94638D01*
X553798Y94431D01*
X554335Y93915D01*
X554488Y93295D01*
X554411Y92675D01*
X554105Y92158D01*
X552571Y91125D01*
X551881Y90401D01*
X551421Y89368D01*
X551268Y88438D01*
X554488D01*
G01X534046Y121905D02*
X527846D01*
Y123821D01*
X528156Y124435D01*
X528569Y124818D01*
X529396Y124971D01*
X530223Y124818D01*
X530739Y124358D01*
X531049Y123821D01*
Y121905D01*
G01Y123821D02*
X534046Y124971D01*
G01X532806Y127951D02*
X533529Y128411D01*
X533943Y129025D01*
X534046Y129715D01*
X533943Y130328D01*
X533426Y130941D01*
X532806Y131325D01*
X532186Y131401D01*
X531463Y131248D01*
X530946Y130711D01*
X530739Y130175D01*
Y129485D01*
G01Y130175D02*
X530429Y130635D01*
X529913Y131018D01*
X529293Y131171D01*
X528673Y131018D01*
X528156Y130635D01*
X527846Y129945D01*
X527949Y129255D01*
X528363Y128565D01*
G01X527846Y135838D02*
X528053Y135225D01*
X528569Y134765D01*
X529189Y134458D01*
X530016Y134228D01*
X530946Y134151D01*
X531876Y134228D01*
X532703Y134458D01*
X533323Y134765D01*
X533839Y135225D01*
X534046Y135838D01*
X533839Y136451D01*
X533323Y136911D01*
X532703Y137218D01*
X531876Y137448D01*
X530946Y137525D01*
X530016Y137448D01*
X529189Y137218D01*
X528569Y136911D01*
X528053Y136451D01*
X527846Y135838D01*
G01X533323Y140735D02*
X533839Y141271D01*
X534046Y141885D01*
X533839Y142498D01*
X533220Y143035D01*
X532289Y143418D01*
X531359Y143571D01*
X530223D01*
X529293Y143418D01*
X528466Y143035D01*
X528053Y142575D01*
X527846Y142038D01*
X528053Y141425D01*
X528466Y140965D01*
X529086Y140658D01*
X529913Y140505D01*
X530636Y140658D01*
X531359Y141041D01*
X531773Y141501D01*
X531876Y142038D01*
X531669Y142651D01*
X531153Y143111D01*
X530223Y143571D01*
G01X522646Y121905D02*
X516446D01*
Y123821D01*
X516756Y124435D01*
X517169Y124818D01*
X517996Y124971D01*
X518823Y124818D01*
X519339Y124358D01*
X519649Y123821D01*
Y121905D01*
G01Y123821D02*
X522646Y124971D01*
G01X521406Y127951D02*
X522129Y128411D01*
X522543Y129025D01*
X522646Y129715D01*
X522543Y130328D01*
X522026Y130941D01*
X521406Y131325D01*
X520786Y131401D01*
X520063Y131248D01*
X519546Y130711D01*
X519339Y130175D01*
Y129485D01*
G01Y130175D02*
X519029Y130635D01*
X518513Y131018D01*
X517893Y131171D01*
X517273Y131018D01*
X516756Y130635D01*
X516446Y129945D01*
X516549Y129255D01*
X516963Y128565D01*
G01X517479Y134381D02*
X516859Y134841D01*
X516549Y135378D01*
X516446Y135991D01*
X516653Y136758D01*
X517169Y137295D01*
X517789Y137448D01*
X518409Y137371D01*
X518926Y137065D01*
X519959Y135531D01*
X520683Y134841D01*
X521716Y134381D01*
X522646Y134228D01*
Y137448D01*
G01Y142038D02*
X522543Y142575D01*
X522233Y143188D01*
X521716Y143571D01*
X520993Y143725D01*
X520269Y143571D01*
X519649Y143111D01*
X519339Y142421D01*
Y141655D01*
X519133Y141195D01*
X518616Y140811D01*
X517893Y140658D01*
X517169Y140888D01*
X516653Y141425D01*
X516446Y142038D01*
X516653Y142651D01*
X517169Y143188D01*
X517893Y143418D01*
X518616Y143265D01*
X519133Y142881D01*
X519339Y142421D01*
Y141655D01*
X519649Y140965D01*
X520269Y140505D01*
X520993Y140351D01*
X521716Y140505D01*
X522233Y140888D01*
X522543Y141501D01*
X522646Y142038D01*
G01X539275Y-100755D02*
X539025Y-101075D01*
X538858Y-101448D01*
Y-101875D01*
X539108Y-102355D01*
X539525Y-102728D01*
X540025Y-102995D01*
X540858Y-103208D01*
X541608Y-103261D01*
X542358Y-103155D01*
X542858Y-102995D01*
X543358Y-102675D01*
X543691Y-102301D01*
X543858Y-101928D01*
Y-101555D01*
X543691Y-101181D01*
X543441Y-100861D01*
X543108Y-100595D01*
G01X539691Y-98541D02*
X539191Y-98221D01*
X538941Y-97848D01*
X538858Y-97421D01*
X539025Y-96888D01*
X539441Y-96515D01*
X539941Y-96408D01*
X540441Y-96461D01*
X540858Y-96675D01*
X541691Y-97741D01*
X542275Y-98221D01*
X543108Y-98541D01*
X543858Y-98648D01*
Y-96408D01*
G01Y-93128D02*
X538858D01*
X539858Y-93768D01*
G01X543858D02*
Y-92488D01*
G01X542858Y-89901D02*
X543441Y-89581D01*
X543775Y-89155D01*
X543858Y-88675D01*
X543775Y-88248D01*
X543358Y-87821D01*
X542858Y-87555D01*
X542358Y-87501D01*
X541775Y-87608D01*
X541358Y-87981D01*
X541191Y-88355D01*
Y-88835D01*
G01Y-88355D02*
X540941Y-88035D01*
X540525Y-87768D01*
X540025Y-87661D01*
X539525Y-87768D01*
X539108Y-88035D01*
X538858Y-88515D01*
X538941Y-88995D01*
X539275Y-89475D01*
G01X539078Y-82129D02*
X534078D01*
Y-80795D01*
X534328Y-80369D01*
X534661Y-80102D01*
X535328Y-79995D01*
X535995Y-80102D01*
X536411Y-80422D01*
X536661Y-80795D01*
Y-82129D01*
G01Y-80795D02*
X539078Y-79995D01*
G01Y-76662D02*
X534078D01*
X535078Y-77302D01*
G01X539078D02*
Y-76022D01*
G01X538495Y-73169D02*
X538911Y-72795D01*
X539078Y-72369D01*
X538911Y-71942D01*
X538411Y-71569D01*
X537661Y-71302D01*
X536911Y-71195D01*
X535995D01*
X535245Y-71302D01*
X534578Y-71569D01*
X534245Y-71889D01*
X534078Y-72262D01*
X534245Y-72689D01*
X534578Y-73009D01*
X535078Y-73222D01*
X535745Y-73329D01*
X536328Y-73222D01*
X536911Y-72955D01*
X537245Y-72635D01*
X537328Y-72262D01*
X537161Y-71835D01*
X536745Y-71515D01*
X535995Y-71195D01*
G01X539078Y-67969D02*
X537995Y-67862D01*
X537078Y-67702D01*
X536245Y-67489D01*
X535328Y-67222D01*
X534078Y-66795D01*
Y-68929D01*
G01X546495Y-87889D02*
X546245Y-88209D01*
X546078Y-88582D01*
Y-89009D01*
X546328Y-89489D01*
X546745Y-89862D01*
X547245Y-90129D01*
X548078Y-90342D01*
X548828Y-90395D01*
X549578Y-90289D01*
X550078Y-90129D01*
X550578Y-89809D01*
X550911Y-89435D01*
X551078Y-89062D01*
Y-88689D01*
X550911Y-88315D01*
X550661Y-87995D01*
X550328Y-87729D01*
G01X551078Y-84662D02*
X546078D01*
X547078Y-85302D01*
G01X551078D02*
Y-84022D01*
G01X546911Y-81275D02*
X546411Y-80955D01*
X546161Y-80582D01*
X546078Y-80155D01*
X546245Y-79622D01*
X546661Y-79249D01*
X547161Y-79142D01*
X547661Y-79195D01*
X548078Y-79409D01*
X548911Y-80475D01*
X549495Y-80955D01*
X550328Y-81275D01*
X551078Y-81382D01*
Y-79142D01*
G01Y-75222D02*
X546078D01*
X549661Y-77195D01*
Y-74529D01*
G01X547149Y-69257D02*
X546899Y-69577D01*
X546732Y-69950D01*
Y-70377D01*
X546982Y-70857D01*
X547399Y-71230D01*
X547899Y-71497D01*
X548732Y-71710D01*
X549482Y-71763D01*
X550232Y-71657D01*
X550732Y-71497D01*
X551232Y-71177D01*
X551565Y-70803D01*
X551732Y-70430D01*
Y-70057D01*
X551565Y-69683D01*
X551315Y-69363D01*
X550982Y-69097D01*
G01X547565Y-67043D02*
X547065Y-66723D01*
X546815Y-66350D01*
X546732Y-65923D01*
X546899Y-65390D01*
X547315Y-65017D01*
X547815Y-64910D01*
X548315Y-64963D01*
X548732Y-65177D01*
X549565Y-66243D01*
X550149Y-66723D01*
X550982Y-67043D01*
X551732Y-67150D01*
Y-64910D01*
G01Y-61630D02*
X546732D01*
X547732Y-62270D01*
G01X551732D02*
Y-60990D01*
G01Y-57230D02*
X551649Y-56857D01*
X551399Y-56430D01*
X550982Y-56163D01*
X550399Y-56057D01*
X549815Y-56163D01*
X549315Y-56483D01*
X549065Y-56963D01*
Y-57497D01*
X548899Y-57817D01*
X548482Y-58083D01*
X547899Y-58190D01*
X547315Y-58030D01*
X546899Y-57657D01*
X546732Y-57230D01*
X546899Y-56803D01*
X547315Y-56430D01*
X547899Y-56270D01*
X548482Y-56377D01*
X548899Y-56643D01*
X549065Y-56963D01*
Y-57497D01*
X549315Y-57977D01*
X549815Y-58297D01*
X550399Y-58403D01*
X550982Y-58297D01*
X551399Y-58030D01*
X551649Y-57603D01*
X551732Y-57230D01*
G01X546995Y-50889D02*
X546745Y-51209D01*
X546578Y-51582D01*
Y-52009D01*
X546828Y-52489D01*
X547245Y-52862D01*
X547745Y-53129D01*
X548578Y-53342D01*
X549328Y-53395D01*
X550078Y-53289D01*
X550578Y-53129D01*
X551078Y-52809D01*
X551411Y-52435D01*
X551578Y-52062D01*
Y-51689D01*
X551411Y-51315D01*
X551161Y-50995D01*
X550828Y-50729D01*
G01X551578Y-47662D02*
X546578D01*
X547578Y-48302D01*
G01X551578D02*
Y-47022D01*
G01X550578Y-44435D02*
X551161Y-44115D01*
X551495Y-43689D01*
X551578Y-43209D01*
X551495Y-42782D01*
X551078Y-42355D01*
X550578Y-42089D01*
X550078Y-42035D01*
X549495Y-42142D01*
X549078Y-42515D01*
X548911Y-42889D01*
Y-43369D01*
G01Y-42889D02*
X548661Y-42569D01*
X548245Y-42302D01*
X547745Y-42195D01*
X547245Y-42302D01*
X546828Y-42569D01*
X546578Y-43049D01*
X546661Y-43529D01*
X546995Y-44009D01*
G01X551578Y-38862D02*
X546578D01*
X547578Y-39502D01*
G01X551578D02*
Y-38222D01*
G01X539275Y-53509D02*
X539025Y-53829D01*
X538858Y-54202D01*
Y-54629D01*
X539108Y-55109D01*
X539525Y-55482D01*
X540025Y-55749D01*
X540858Y-55962D01*
X541608Y-56015D01*
X542358Y-55909D01*
X542858Y-55749D01*
X543358Y-55429D01*
X543691Y-55055D01*
X543858Y-54682D01*
Y-54309D01*
X543691Y-53935D01*
X543441Y-53615D01*
X543108Y-53349D01*
G01X543858Y-50282D02*
X538858D01*
X539858Y-50922D01*
G01X543858D02*
Y-49642D01*
G01X538858Y-45882D02*
X539025Y-46309D01*
X539441Y-46629D01*
X539941Y-46842D01*
X540608Y-47002D01*
X541358Y-47055D01*
X542108Y-47002D01*
X542775Y-46842D01*
X543275Y-46629D01*
X543691Y-46309D01*
X543858Y-45882D01*
X543691Y-45455D01*
X543275Y-45135D01*
X542775Y-44922D01*
X542108Y-44762D01*
X541358Y-44709D01*
X540608Y-44762D01*
X539941Y-44922D01*
X539441Y-45135D01*
X539025Y-45455D01*
X538858Y-45882D01*
G01X543108Y-42655D02*
X543525Y-42335D01*
X543775Y-41962D01*
X543858Y-41482D01*
X543691Y-41002D01*
X543358Y-40629D01*
X542775Y-40362D01*
X542108Y-40309D01*
X541441Y-40415D01*
X541025Y-40682D01*
X540691Y-41055D01*
X540608Y-41429D01*
X540691Y-41802D01*
X541025Y-42282D01*
X538858Y-42122D01*
Y-40682D01*
G01X537083Y-10067D02*
X536623Y-9757D01*
X536086Y-9550D01*
X535473D01*
X534783Y-9860D01*
X534246Y-10377D01*
X533863Y-10997D01*
X533556Y-12030D01*
X533479Y-12960D01*
X533633Y-13890D01*
X533863Y-14510D01*
X534323Y-15130D01*
X534859Y-15543D01*
X535396Y-15750D01*
X535933D01*
X536469Y-15543D01*
X536929Y-15233D01*
X537313Y-14820D01*
G01X541596Y-15750D02*
Y-9550D01*
X540676Y-10790D01*
G01Y-15750D02*
X542516D01*
G01X547796Y-9550D02*
X547183Y-9757D01*
X546723Y-10273D01*
X546416Y-10893D01*
X546186Y-11720D01*
X546109Y-12650D01*
X546186Y-13580D01*
X546416Y-14407D01*
X546723Y-15027D01*
X547183Y-15543D01*
X547796Y-15750D01*
X548409Y-15543D01*
X548869Y-15027D01*
X549176Y-14407D01*
X549406Y-13580D01*
X549483Y-12650D01*
X549406Y-11720D01*
X549176Y-10893D01*
X548869Y-10273D01*
X548409Y-9757D01*
X547796Y-9550D01*
G01X552539Y-13167D02*
X553076Y-12443D01*
X553536Y-12030D01*
X554149Y-11823D01*
X554686Y-12030D01*
X555069Y-12443D01*
X555376Y-13063D01*
X555453Y-13787D01*
X555376Y-14407D01*
X555069Y-15027D01*
X554609Y-15543D01*
X554073Y-15750D01*
X553459Y-15543D01*
X552923Y-14924D01*
X552616Y-13993D01*
X552539Y-12960D01*
X552693Y-11617D01*
X552923Y-10893D01*
X553306Y-10170D01*
X553843Y-9653D01*
X554379Y-9550D01*
X554916Y-9757D01*
X555299Y-10273D01*
G01X552831Y-2193D02*
X552371Y-1883D01*
X551834Y-1676D01*
X551221D01*
X550531Y-1986D01*
X549994Y-2503D01*
X549611Y-3123D01*
X549304Y-4156D01*
X549227Y-5086D01*
X549381Y-6016D01*
X549611Y-6636D01*
X550071Y-7256D01*
X550607Y-7669D01*
X551144Y-7876D01*
X551681D01*
X552217Y-7669D01*
X552677Y-7359D01*
X553061Y-6946D01*
G01X555887Y-2709D02*
X556347Y-2089D01*
X556884Y-1779D01*
X557497Y-1676D01*
X558264Y-1883D01*
X558801Y-2399D01*
X558954Y-3019D01*
X558877Y-3639D01*
X558571Y-4156D01*
X557037Y-5189D01*
X556347Y-5913D01*
X555887Y-6946D01*
X555734Y-7876D01*
X558954D01*
G01X563544Y-1676D02*
X562931Y-1883D01*
X562471Y-2399D01*
X562164Y-3019D01*
X561934Y-3846D01*
X561857Y-4776D01*
X561934Y-5706D01*
X562164Y-6533D01*
X562471Y-7153D01*
X562931Y-7669D01*
X563544Y-7876D01*
X564157Y-7669D01*
X564617Y-7153D01*
X564924Y-6533D01*
X565154Y-5706D01*
X565231Y-4776D01*
X565154Y-3846D01*
X564924Y-3019D01*
X564617Y-2399D01*
X564157Y-1883D01*
X563544Y-1676D01*
G01X568057Y-6636D02*
X568517Y-7359D01*
X569131Y-7773D01*
X569821Y-7876D01*
X570434Y-7773D01*
X571047Y-7256D01*
X571431Y-6636D01*
X571507Y-6016D01*
X571354Y-5293D01*
X570817Y-4776D01*
X570281Y-4569D01*
X569591D01*
G01X570281D02*
X570741Y-4259D01*
X571124Y-3743D01*
X571277Y-3123D01*
X571124Y-2503D01*
X570741Y-1986D01*
X570051Y-1676D01*
X569361Y-1779D01*
X568671Y-2193D01*
G01X550965Y14221D02*
X550505Y14531D01*
X549968Y14738D01*
X549355D01*
X548665Y14428D01*
X548128Y13911D01*
X547745Y13291D01*
X547438Y12258D01*
X547361Y11328D01*
X547515Y10398D01*
X547745Y9778D01*
X548205Y9158D01*
X548741Y8745D01*
X549278Y8538D01*
X549815D01*
X550351Y8745D01*
X550811Y9055D01*
X551195Y9468D01*
G01X555478Y8538D02*
Y14738D01*
X554558Y13498D01*
G01Y8538D02*
X556398D01*
G01X560221Y11121D02*
X560758Y11845D01*
X561218Y12258D01*
X561831Y12465D01*
X562368Y12258D01*
X562751Y11845D01*
X563058Y11225D01*
X563135Y10501D01*
X563058Y9881D01*
X562751Y9261D01*
X562291Y8745D01*
X561755Y8538D01*
X561141Y8745D01*
X560605Y9364D01*
X560298Y10295D01*
X560221Y11328D01*
X560375Y12671D01*
X560605Y13395D01*
X560988Y14118D01*
X561525Y14635D01*
X562061Y14738D01*
X562598Y14531D01*
X562981Y14015D01*
G01X567725Y8538D02*
X567878Y9881D01*
X568108Y11018D01*
X568415Y12051D01*
X568798Y13188D01*
X569411Y14738D01*
X566345D01*
G01X552831Y29303D02*
X552371Y29613D01*
X551834Y29820D01*
X551221D01*
X550531Y29510D01*
X549994Y28993D01*
X549611Y28373D01*
X549304Y27340D01*
X549227Y26410D01*
X549381Y25480D01*
X549611Y24860D01*
X550071Y24240D01*
X550607Y23827D01*
X551144Y23620D01*
X551681D01*
X552217Y23827D01*
X552677Y24137D01*
X553061Y24550D01*
G01X555887Y28787D02*
X556347Y29407D01*
X556884Y29717D01*
X557497Y29820D01*
X558264Y29613D01*
X558801Y29097D01*
X558954Y28477D01*
X558877Y27857D01*
X558571Y27340D01*
X557037Y26307D01*
X556347Y25583D01*
X555887Y24550D01*
X555734Y23620D01*
X558954D01*
G01X563544D02*
Y29820D01*
X562624Y28580D01*
G01Y23620D02*
X564464D01*
G01X569744D02*
Y29820D01*
X568824Y28580D01*
G01Y23620D02*
X570664D01*
G01X540995Y10111D02*
X540745Y9791D01*
X540578Y9418D01*
Y8991D01*
X540828Y8511D01*
X541245Y8138D01*
X541745Y7871D01*
X542578Y7658D01*
X543328Y7605D01*
X544078Y7711D01*
X544578Y7871D01*
X545078Y8191D01*
X545411Y8565D01*
X545578Y8938D01*
Y9311D01*
X545411Y9685D01*
X545161Y10005D01*
X544828Y10271D01*
G01X545578Y13338D02*
X540578D01*
X541578Y12698D01*
G01X545578D02*
Y13978D01*
G01Y17631D02*
X544495Y17738D01*
X543578Y17898D01*
X542745Y18111D01*
X541828Y18378D01*
X540578Y18805D01*
Y16671D01*
G01Y22138D02*
X540745Y21711D01*
X541161Y21391D01*
X541661Y21178D01*
X542328Y21018D01*
X543078Y20965D01*
X543828Y21018D01*
X544495Y21178D01*
X544995Y21391D01*
X545411Y21711D01*
X545578Y22138D01*
X545411Y22565D01*
X544995Y22885D01*
X544495Y23098D01*
X543828Y23258D01*
X543078Y23311D01*
X542328Y23258D01*
X541661Y23098D01*
X541161Y22885D01*
X540745Y22565D01*
X540578Y22138D01*
G01X552833Y37177D02*
X552373Y37487D01*
X551836Y37694D01*
X551223D01*
X550533Y37384D01*
X549996Y36867D01*
X549613Y36247D01*
X549306Y35214D01*
X549229Y34284D01*
X549383Y33354D01*
X549613Y32734D01*
X550073Y32114D01*
X550609Y31701D01*
X551146Y31494D01*
X551683D01*
X552219Y31701D01*
X552679Y32011D01*
X553063Y32424D01*
G01X557346Y31494D02*
Y37694D01*
X556426Y36454D01*
G01Y31494D02*
X558266D01*
G01X561859Y32424D02*
X562319Y31907D01*
X562856Y31597D01*
X563546Y31494D01*
X564236Y31701D01*
X564773Y32114D01*
X565156Y32837D01*
X565233Y33664D01*
X565079Y34491D01*
X564696Y35007D01*
X564159Y35421D01*
X563623Y35524D01*
X563086Y35421D01*
X562396Y35007D01*
X562626Y37694D01*
X564696D01*
G01X569593Y31494D02*
X569746Y32837D01*
X569976Y33974D01*
X570283Y35007D01*
X570666Y36144D01*
X571279Y37694D01*
X568213D01*
G01X544214Y121905D02*
X538014D01*
Y123821D01*
X538324Y124435D01*
X538737Y124818D01*
X539564Y124971D01*
X540391Y124818D01*
X540907Y124358D01*
X541217Y123821D01*
Y121905D01*
G01Y123821D02*
X544214Y124971D01*
G01X539047Y128181D02*
X538427Y128641D01*
X538117Y129178D01*
X538014Y129791D01*
X538221Y130558D01*
X538737Y131095D01*
X539357Y131248D01*
X539977Y131171D01*
X540494Y130865D01*
X541527Y129331D01*
X542251Y128641D01*
X543284Y128181D01*
X544214Y128028D01*
Y131248D01*
G01X543491Y134535D02*
X544007Y135071D01*
X544214Y135685D01*
X544007Y136298D01*
X543388Y136835D01*
X542457Y137218D01*
X541527Y137371D01*
X540391D01*
X539461Y137218D01*
X538634Y136835D01*
X538221Y136375D01*
X538014Y135838D01*
X538221Y135225D01*
X538634Y134765D01*
X539254Y134458D01*
X540081Y134305D01*
X540804Y134458D01*
X541527Y134841D01*
X541941Y135301D01*
X542044Y135838D01*
X541837Y136451D01*
X541321Y136911D01*
X540391Y137371D01*
G01X542974Y140351D02*
X543697Y140811D01*
X544111Y141425D01*
X544214Y142115D01*
X544111Y142728D01*
X543594Y143341D01*
X542974Y143725D01*
X542354Y143801D01*
X541631Y143648D01*
X541114Y143111D01*
X540907Y142575D01*
Y141885D01*
G01Y142575D02*
X540597Y143035D01*
X540081Y143418D01*
X539461Y143571D01*
X538841Y143418D01*
X538324Y143035D01*
X538014Y142345D01*
X538117Y141655D01*
X538531Y140965D01*
G01X540945Y272270D02*
Y278470D01*
X542861D01*
X543475Y278160D01*
X543858Y277747D01*
X544011Y276920D01*
X543858Y276093D01*
X543398Y275577D01*
X542861Y275267D01*
X540945D01*
G01X542861D02*
X544011Y272270D01*
G01X549598D02*
Y278470D01*
X546761Y274027D01*
X550595D01*
G01X553191Y273200D02*
X553651Y272683D01*
X554188Y272373D01*
X554878Y272270D01*
X555568Y272477D01*
X556105Y272890D01*
X556488Y273613D01*
X556565Y274440D01*
X556411Y275267D01*
X556028Y275783D01*
X555491Y276197D01*
X554955Y276300D01*
X554418Y276197D01*
X553728Y275783D01*
X553958Y278470D01*
X556028D01*
G01X561078Y272270D02*
X561615Y272373D01*
X562228Y272683D01*
X562611Y273200D01*
X562765Y273923D01*
X562611Y274647D01*
X562151Y275267D01*
X561461Y275577D01*
X560695D01*
X560235Y275783D01*
X559851Y276300D01*
X559698Y277023D01*
X559928Y277747D01*
X560465Y278263D01*
X561078Y278470D01*
X561691Y278263D01*
X562228Y277747D01*
X562458Y277023D01*
X562305Y276300D01*
X561921Y275783D01*
X561461Y275577D01*
X560695D01*
X560005Y275267D01*
X559545Y274647D01*
X559391Y273923D01*
X559545Y273200D01*
X559928Y272683D01*
X560541Y272373D01*
X561078Y272270D01*
G01X540945Y282670D02*
Y288870D01*
X542861D01*
X543475Y288560D01*
X543858Y288147D01*
X544011Y287320D01*
X543858Y286493D01*
X543398Y285977D01*
X542861Y285667D01*
X540945D01*
G01X542861D02*
X544011Y282670D01*
G01X549598D02*
Y288870D01*
X546761Y284427D01*
X550595D01*
G01X553191Y283600D02*
X553651Y283083D01*
X554188Y282773D01*
X554878Y282670D01*
X555568Y282877D01*
X556105Y283290D01*
X556488Y284013D01*
X556565Y284840D01*
X556411Y285667D01*
X556028Y286183D01*
X555491Y286597D01*
X554955Y286700D01*
X554418Y286597D01*
X553728Y286183D01*
X553958Y288870D01*
X556028D01*
G01X560925Y282670D02*
X561078Y284013D01*
X561308Y285150D01*
X561615Y286183D01*
X561998Y287320D01*
X562611Y288870D01*
X559545D01*
G01X563507Y-112157D02*
X563047Y-111847D01*
X562510Y-111640D01*
X561897D01*
X561207Y-111950D01*
X560670Y-112467D01*
X560287Y-113087D01*
X559980Y-114120D01*
X559903Y-115050D01*
X560057Y-115980D01*
X560287Y-116600D01*
X560747Y-117220D01*
X561283Y-117633D01*
X561820Y-117840D01*
X562357D01*
X562893Y-117633D01*
X563353Y-117323D01*
X563737Y-116910D01*
G01X568020Y-117840D02*
Y-111640D01*
X567100Y-112880D01*
G01Y-117840D02*
X568940D01*
G01X574220D02*
Y-111640D01*
X573300Y-112880D01*
G01Y-117840D02*
X575140D01*
G01X578963Y-115257D02*
X579500Y-114533D01*
X579960Y-114120D01*
X580573Y-113913D01*
X581110Y-114120D01*
X581493Y-114533D01*
X581800Y-115153D01*
X581877Y-115877D01*
X581800Y-116497D01*
X581493Y-117117D01*
X581033Y-117633D01*
X580497Y-117840D01*
X579883Y-117633D01*
X579347Y-117014D01*
X579040Y-116083D01*
X578963Y-115050D01*
X579117Y-113707D01*
X579347Y-112983D01*
X579730Y-112260D01*
X580267Y-111743D01*
X580803Y-111640D01*
X581340Y-111847D01*
X581723Y-112363D01*
G01X553925Y-92191D02*
X553615Y-92651D01*
X553408Y-93188D01*
Y-93801D01*
X553718Y-94491D01*
X554235Y-95028D01*
X554855Y-95411D01*
X555888Y-95718D01*
X556818Y-95795D01*
X557748Y-95641D01*
X558368Y-95411D01*
X558988Y-94951D01*
X559401Y-94415D01*
X559608Y-93878D01*
Y-93341D01*
X559401Y-92805D01*
X559091Y-92345D01*
X558678Y-91961D01*
G01X554441Y-89135D02*
X553821Y-88675D01*
X553511Y-88138D01*
X553408Y-87525D01*
X553615Y-86758D01*
X554131Y-86221D01*
X554751Y-86068D01*
X555371Y-86145D01*
X555888Y-86451D01*
X556921Y-87985D01*
X557645Y-88675D01*
X558678Y-89135D01*
X559608Y-89288D01*
Y-86068D01*
G01Y-81478D02*
X553408D01*
X554648Y-82398D01*
G01X559608D02*
Y-80558D01*
G01Y-75431D02*
X558265Y-75278D01*
X557128Y-75048D01*
X556095Y-74741D01*
X554958Y-74358D01*
X553408Y-73745D01*
Y-76811D01*
G01X565965Y-72779D02*
X565505Y-72469D01*
X564968Y-72262D01*
X564355D01*
X563665Y-72572D01*
X563128Y-73089D01*
X562745Y-73709D01*
X562438Y-74742D01*
X562361Y-75672D01*
X562515Y-76602D01*
X562745Y-77222D01*
X563205Y-77842D01*
X563741Y-78255D01*
X564278Y-78462D01*
X564815D01*
X565351Y-78255D01*
X565811Y-77945D01*
X566195Y-77532D01*
G01X570478Y-78462D02*
Y-72262D01*
X569558Y-73502D01*
G01Y-78462D02*
X571398D01*
G01X576678D02*
Y-72262D01*
X575758Y-73502D01*
G01Y-78462D02*
X577598D01*
G01X582878Y-72262D02*
X582265Y-72469D01*
X581805Y-72985D01*
X581498Y-73605D01*
X581268Y-74432D01*
X581191Y-75362D01*
X581268Y-76292D01*
X581498Y-77119D01*
X581805Y-77739D01*
X582265Y-78255D01*
X582878Y-78462D01*
X583491Y-78255D01*
X583951Y-77739D01*
X584258Y-77119D01*
X584488Y-76292D01*
X584565Y-75362D01*
X584488Y-74432D01*
X584258Y-73605D01*
X583951Y-72985D01*
X583491Y-72469D01*
X582878Y-72262D01*
G01X559965Y-64779D02*
X559505Y-64469D01*
X558968Y-64262D01*
X558355D01*
X557665Y-64572D01*
X557128Y-65089D01*
X556745Y-65709D01*
X556438Y-66742D01*
X556361Y-67672D01*
X556515Y-68602D01*
X556745Y-69222D01*
X557205Y-69842D01*
X557741Y-70255D01*
X558278Y-70462D01*
X558815D01*
X559351Y-70255D01*
X559811Y-69945D01*
X560195Y-69532D01*
G01X564478Y-70462D02*
Y-64262D01*
X563558Y-65502D01*
G01Y-70462D02*
X565398D01*
G01X570678D02*
Y-64262D01*
X569758Y-65502D01*
G01Y-70462D02*
X571598D01*
G01X576725D02*
X576878Y-69119D01*
X577108Y-67982D01*
X577415Y-66949D01*
X577798Y-65812D01*
X578411Y-64262D01*
X575345D01*
G01X558965Y-40779D02*
X558505Y-40469D01*
X557968Y-40262D01*
X557355D01*
X556665Y-40572D01*
X556128Y-41089D01*
X555745Y-41709D01*
X555438Y-42742D01*
X555361Y-43672D01*
X555515Y-44602D01*
X555745Y-45222D01*
X556205Y-45842D01*
X556741Y-46255D01*
X557278Y-46462D01*
X557815D01*
X558351Y-46255D01*
X558811Y-45945D01*
X559195Y-45532D01*
G01X562021Y-41295D02*
X562481Y-40675D01*
X563018Y-40365D01*
X563631Y-40262D01*
X564398Y-40469D01*
X564935Y-40985D01*
X565088Y-41605D01*
X565011Y-42225D01*
X564705Y-42742D01*
X563171Y-43775D01*
X562481Y-44499D01*
X562021Y-45532D01*
X561868Y-46462D01*
X565088D01*
G01X569678Y-40262D02*
X569065Y-40469D01*
X568605Y-40985D01*
X568298Y-41605D01*
X568068Y-42432D01*
X567991Y-43362D01*
X568068Y-44292D01*
X568298Y-45119D01*
X568605Y-45739D01*
X569065Y-46255D01*
X569678Y-46462D01*
X570291Y-46255D01*
X570751Y-45739D01*
X571058Y-45119D01*
X571288Y-44292D01*
X571365Y-43362D01*
X571288Y-42432D01*
X571058Y-41605D01*
X570751Y-40985D01*
X570291Y-40469D01*
X569678Y-40262D01*
G01X574575Y-45739D02*
X575111Y-46255D01*
X575725Y-46462D01*
X576338Y-46255D01*
X576875Y-45636D01*
X577258Y-44705D01*
X577411Y-43775D01*
Y-42639D01*
X577258Y-41709D01*
X576875Y-40882D01*
X576415Y-40469D01*
X575878Y-40262D01*
X575265Y-40469D01*
X574805Y-40882D01*
X574498Y-41502D01*
X574345Y-42329D01*
X574498Y-43052D01*
X574881Y-43775D01*
X575341Y-44189D01*
X575878Y-44292D01*
X576491Y-44085D01*
X576951Y-43569D01*
X577411Y-42639D01*
G01X561799Y-32073D02*
X561489Y-32533D01*
X561282Y-33070D01*
Y-33683D01*
X561592Y-34373D01*
X562109Y-34910D01*
X562729Y-35293D01*
X563762Y-35600D01*
X564692Y-35677D01*
X565622Y-35523D01*
X566242Y-35293D01*
X566862Y-34833D01*
X567275Y-34297D01*
X567482Y-33760D01*
Y-33223D01*
X567275Y-32687D01*
X566965Y-32227D01*
X566552Y-31843D01*
G01X562315Y-29017D02*
X561695Y-28557D01*
X561385Y-28020D01*
X561282Y-27407D01*
X561489Y-26640D01*
X562005Y-26103D01*
X562625Y-25950D01*
X563245Y-26027D01*
X563762Y-26333D01*
X564795Y-27867D01*
X565519Y-28557D01*
X566552Y-29017D01*
X567482Y-29170D01*
Y-25950D01*
G01X561282Y-21360D02*
X561489Y-21973D01*
X562005Y-22433D01*
X562625Y-22740D01*
X563452Y-22970D01*
X564382Y-23047D01*
X565312Y-22970D01*
X566139Y-22740D01*
X566759Y-22433D01*
X567275Y-21973D01*
X567482Y-21360D01*
X567275Y-20747D01*
X566759Y-20287D01*
X566139Y-19980D01*
X565312Y-19750D01*
X564382Y-19673D01*
X563452Y-19750D01*
X562625Y-19980D01*
X562005Y-20287D01*
X561489Y-20747D01*
X561282Y-21360D01*
G01X566552Y-16847D02*
X567069Y-16387D01*
X567379Y-15850D01*
X567482Y-15160D01*
X567275Y-14470D01*
X566862Y-13933D01*
X566139Y-13550D01*
X565312Y-13473D01*
X564485Y-13627D01*
X563969Y-14010D01*
X563555Y-14547D01*
X563452Y-15083D01*
X563555Y-15620D01*
X563969Y-16310D01*
X561282Y-16080D01*
Y-14010D01*
G01X560707Y60799D02*
X560247Y61109D01*
X559710Y61316D01*
X559097D01*
X558407Y61006D01*
X557870Y60489D01*
X557487Y59869D01*
X557180Y58836D01*
X557103Y57906D01*
X557257Y56976D01*
X557487Y56356D01*
X557947Y55736D01*
X558483Y55323D01*
X559020Y55116D01*
X559557D01*
X560093Y55323D01*
X560553Y55633D01*
X560937Y56046D01*
G01X563763Y60283D02*
X564223Y60903D01*
X564760Y61213D01*
X565373Y61316D01*
X566140Y61109D01*
X566677Y60593D01*
X566830Y59973D01*
X566753Y59353D01*
X566447Y58836D01*
X564913Y57803D01*
X564223Y57079D01*
X563763Y56046D01*
X563610Y55116D01*
X566830D01*
G01X571420D02*
Y61316D01*
X570500Y60076D01*
G01Y55116D02*
X572340D01*
G01X576163Y57699D02*
X576700Y58423D01*
X577160Y58836D01*
X577773Y59043D01*
X578310Y58836D01*
X578693Y58423D01*
X579000Y57803D01*
X579077Y57079D01*
X579000Y56459D01*
X578693Y55839D01*
X578233Y55323D01*
X577697Y55116D01*
X577083Y55323D01*
X576547Y55942D01*
X576240Y56873D01*
X576163Y57906D01*
X576317Y59249D01*
X576547Y59973D01*
X576930Y60696D01*
X577467Y61213D01*
X578003Y61316D01*
X578540Y61109D01*
X578923Y60593D01*
G01X557965Y50221D02*
X557505Y50531D01*
X556968Y50738D01*
X556355D01*
X555665Y50428D01*
X555128Y49911D01*
X554745Y49291D01*
X554438Y48258D01*
X554361Y47328D01*
X554515Y46398D01*
X554745Y45778D01*
X555205Y45158D01*
X555741Y44745D01*
X556278Y44538D01*
X556815D01*
X557351Y44745D01*
X557811Y45055D01*
X558195Y45468D01*
G01X562478Y44538D02*
Y50738D01*
X561558Y49498D01*
G01Y44538D02*
X563398D01*
G01X569598D02*
Y50738D01*
X566761Y46295D01*
X570595D01*
G01X574878Y50738D02*
X574265Y50531D01*
X573805Y50015D01*
X573498Y49395D01*
X573268Y48568D01*
X573191Y47638D01*
X573268Y46708D01*
X573498Y45881D01*
X573805Y45261D01*
X574265Y44745D01*
X574878Y44538D01*
X575491Y44745D01*
X575951Y45261D01*
X576258Y45881D01*
X576488Y46708D01*
X576565Y47638D01*
X576488Y48568D01*
X576258Y49395D01*
X575951Y50015D01*
X575491Y50531D01*
X574878Y50738D01*
G01X568846Y121905D02*
X562646D01*
Y123821D01*
X562956Y124435D01*
X563369Y124818D01*
X564196Y124971D01*
X565023Y124818D01*
X565539Y124358D01*
X565849Y123821D01*
Y121905D01*
G01Y123821D02*
X568846Y124971D01*
G01Y129638D02*
X562646D01*
X563886Y128718D01*
G01X568846D02*
Y130558D01*
G01Y135685D02*
X567503Y135838D01*
X566366Y136068D01*
X565333Y136375D01*
X564196Y136758D01*
X562646Y137371D01*
Y134305D01*
G01X567606Y140351D02*
X568329Y140811D01*
X568743Y141425D01*
X568846Y142115D01*
X568743Y142728D01*
X568226Y143341D01*
X567606Y143725D01*
X566986Y143801D01*
X566263Y143648D01*
X565746Y143111D01*
X565539Y142575D01*
Y141885D01*
G01Y142575D02*
X565229Y143035D01*
X564713Y143418D01*
X564093Y143571D01*
X563473Y143418D01*
X562956Y143035D01*
X562646Y142345D01*
X562749Y141655D01*
X563163Y140965D01*
G01X558078Y121905D02*
X551878D01*
Y123821D01*
X552188Y124435D01*
X552601Y124818D01*
X553428Y124971D01*
X554255Y124818D01*
X554771Y124358D01*
X555081Y123821D01*
Y121905D01*
G01Y123821D02*
X558078Y124971D01*
G01Y129638D02*
X551878D01*
X553118Y128718D01*
G01X558078D02*
Y130558D01*
G01Y135685D02*
X556735Y135838D01*
X555598Y136068D01*
X554565Y136375D01*
X553428Y136758D01*
X551878Y137371D01*
Y134305D01*
G01X558078Y142038D02*
X551878D01*
X553118Y141118D01*
G01X558078D02*
Y142958D01*
G01X552745Y241538D02*
Y247738D01*
X554661D01*
X555275Y247428D01*
X555658Y247015D01*
X555811Y246188D01*
X555658Y245361D01*
X555198Y244845D01*
X554661Y244535D01*
X552745D01*
G01X554661D02*
X555811Y241538D01*
G01X560478D02*
Y247738D01*
X559558Y246498D01*
G01Y241538D02*
X561398D01*
G01X565221Y244121D02*
X565758Y244845D01*
X566218Y245258D01*
X566831Y245465D01*
X567368Y245258D01*
X567751Y244845D01*
X568058Y244225D01*
X568135Y243501D01*
X568058Y242881D01*
X567751Y242261D01*
X567291Y241745D01*
X566755Y241538D01*
X566141Y241745D01*
X565605Y242364D01*
X565298Y243295D01*
X565221Y244328D01*
X565375Y245671D01*
X565605Y246395D01*
X565988Y247118D01*
X566525Y247635D01*
X567061Y247738D01*
X567598Y247531D01*
X567981Y247015D01*
G01X571191Y242468D02*
X571651Y241951D01*
X572188Y241641D01*
X572878Y241538D01*
X573568Y241745D01*
X574105Y242158D01*
X574488Y242881D01*
X574565Y243708D01*
X574411Y244535D01*
X574028Y245051D01*
X573491Y245465D01*
X572955Y245568D01*
X572418Y245465D01*
X571728Y245051D01*
X571958Y247738D01*
X574028D01*
G01X550963Y308925D02*
X550653Y308465D01*
X550446Y307928D01*
Y307315D01*
X550756Y306625D01*
X551273Y306088D01*
X551893Y305705D01*
X552926Y305398D01*
X553856Y305321D01*
X554786Y305475D01*
X555406Y305705D01*
X556026Y306165D01*
X556439Y306701D01*
X556646Y307238D01*
Y307775D01*
X556439Y308311D01*
X556129Y308771D01*
X555716Y309155D01*
G01X556646Y313438D02*
X550446D01*
X551686Y312518D01*
G01X556646D02*
Y314358D01*
G01X551479Y318181D02*
X550859Y318641D01*
X550549Y319178D01*
X550446Y319791D01*
X550653Y320558D01*
X551169Y321095D01*
X551789Y321248D01*
X552409Y321171D01*
X552926Y320865D01*
X553959Y319331D01*
X554683Y318641D01*
X555716Y318181D01*
X556646Y318028D01*
Y321248D01*
G01X555406Y324151D02*
X556129Y324611D01*
X556543Y325225D01*
X556646Y325915D01*
X556543Y326528D01*
X556026Y327141D01*
X555406Y327525D01*
X554786Y327601D01*
X554063Y327448D01*
X553546Y326911D01*
X553339Y326375D01*
Y325685D01*
G01Y326375D02*
X553029Y326835D01*
X552513Y327218D01*
X551893Y327371D01*
X551273Y327218D01*
X550756Y326835D01*
X550446Y326145D01*
X550549Y325455D01*
X550963Y324765D01*
G01X567745Y386470D02*
Y392670D01*
X569661D01*
X570275Y392360D01*
X570658Y391947D01*
X570811Y391120D01*
X570658Y390293D01*
X570198Y389777D01*
X569661Y389467D01*
X567745D01*
G01X569661D02*
X570811Y386470D01*
G01X576398D02*
Y392670D01*
X573561Y388227D01*
X577395D01*
G01X579991Y387400D02*
X580451Y386883D01*
X580988Y386573D01*
X581678Y386470D01*
X582368Y386677D01*
X582905Y387090D01*
X583288Y387813D01*
X583365Y388640D01*
X583211Y389467D01*
X582828Y389983D01*
X582291Y390397D01*
X581755Y390500D01*
X581218Y390397D01*
X580528Y389983D01*
X580758Y392670D01*
X582828D01*
G01X587878D02*
X587265Y392463D01*
X586805Y391947D01*
X586498Y391327D01*
X586268Y390500D01*
X586191Y389570D01*
X586268Y388640D01*
X586498Y387813D01*
X586805Y387193D01*
X587265Y386677D01*
X587878Y386470D01*
X588491Y386677D01*
X588951Y387193D01*
X589258Y387813D01*
X589488Y388640D01*
X589565Y389570D01*
X589488Y390500D01*
X589258Y391327D01*
X588951Y391947D01*
X588491Y392463D01*
X587878Y392670D01*
G01X567745Y376070D02*
Y382270D01*
X569661D01*
X570275Y381960D01*
X570658Y381547D01*
X570811Y380720D01*
X570658Y379893D01*
X570198Y379377D01*
X569661Y379067D01*
X567745D01*
G01X569661D02*
X570811Y376070D01*
G01X576398D02*
Y382270D01*
X573561Y377827D01*
X577395D01*
G01X579991Y377000D02*
X580451Y376483D01*
X580988Y376173D01*
X581678Y376070D01*
X582368Y376277D01*
X582905Y376690D01*
X583288Y377413D01*
X583365Y378240D01*
X583211Y379067D01*
X582828Y379583D01*
X582291Y379997D01*
X581755Y380100D01*
X581218Y379997D01*
X580528Y379583D01*
X580758Y382270D01*
X582828D01*
G01X587878Y376070D02*
Y382270D01*
X586958Y381030D01*
G01Y376070D02*
X588798D01*
G01X574965Y-20779D02*
X574505Y-20469D01*
X573968Y-20262D01*
X573355D01*
X572665Y-20572D01*
X572128Y-21089D01*
X571745Y-21709D01*
X571438Y-22742D01*
X571361Y-23672D01*
X571515Y-24602D01*
X571745Y-25222D01*
X572205Y-25842D01*
X572741Y-26255D01*
X573278Y-26462D01*
X573815D01*
X574351Y-26255D01*
X574811Y-25945D01*
X575195Y-25532D01*
G01X579478Y-26462D02*
Y-20262D01*
X578558Y-21502D01*
G01Y-26462D02*
X580398D01*
G01X585678Y-20262D02*
X585065Y-20469D01*
X584605Y-20985D01*
X584298Y-21605D01*
X584068Y-22432D01*
X583991Y-23362D01*
X584068Y-24292D01*
X584298Y-25119D01*
X584605Y-25739D01*
X585065Y-26255D01*
X585678Y-26462D01*
X586291Y-26255D01*
X586751Y-25739D01*
X587058Y-25119D01*
X587288Y-24292D01*
X587365Y-23362D01*
X587288Y-22432D01*
X587058Y-21605D01*
X586751Y-20985D01*
X586291Y-20469D01*
X585678Y-20262D01*
G01X592798Y-26462D02*
Y-20262D01*
X589961Y-24705D01*
X593795D01*
G01X580646Y121905D02*
X574446D01*
Y123821D01*
X574756Y124435D01*
X575169Y124818D01*
X575996Y124971D01*
X576823Y124818D01*
X577339Y124358D01*
X577649Y123821D01*
Y121905D01*
G01Y123821D02*
X580646Y124971D01*
G01X575479Y128181D02*
X574859Y128641D01*
X574549Y129178D01*
X574446Y129791D01*
X574653Y130558D01*
X575169Y131095D01*
X575789Y131248D01*
X576409Y131171D01*
X576926Y130865D01*
X577959Y129331D01*
X578683Y128641D01*
X579716Y128181D01*
X580646Y128028D01*
Y131248D01*
G01Y135838D02*
X580543Y136375D01*
X580233Y136988D01*
X579716Y137371D01*
X578993Y137525D01*
X578269Y137371D01*
X577649Y136911D01*
X577339Y136221D01*
Y135455D01*
X577133Y134995D01*
X576616Y134611D01*
X575893Y134458D01*
X575169Y134688D01*
X574653Y135225D01*
X574446Y135838D01*
X574653Y136451D01*
X575169Y136988D01*
X575893Y137218D01*
X576616Y137065D01*
X577133Y136681D01*
X577339Y136221D01*
Y135455D01*
X577649Y134765D01*
X578269Y134305D01*
X578993Y134151D01*
X579716Y134305D01*
X580233Y134688D01*
X580543Y135301D01*
X580646Y135838D01*
G01Y142958D02*
X574446D01*
X578889Y140121D01*
Y143955D01*
G01X581745Y241538D02*
Y247738D01*
X583661D01*
X584275Y247428D01*
X584658Y247015D01*
X584811Y246188D01*
X584658Y245361D01*
X584198Y244845D01*
X583661Y244535D01*
X581745D01*
G01X583661D02*
X584811Y241538D01*
G01X589478D02*
Y247738D01*
X588558Y246498D01*
G01Y241538D02*
X590398D01*
G01X595525D02*
X595678Y242881D01*
X595908Y244018D01*
X596215Y245051D01*
X596598Y246188D01*
X597211Y247738D01*
X594145D01*
G01X601725Y241538D02*
X601878Y242881D01*
X602108Y244018D01*
X602415Y245051D01*
X602798Y246188D01*
X603411Y247738D01*
X600345D01*
G01X593895Y-225075D02*
X593585Y-225535D01*
X593378Y-226072D01*
Y-226685D01*
X593688Y-227375D01*
X594205Y-227912D01*
X594825Y-228295D01*
X595858Y-228602D01*
X596788Y-228679D01*
X597718Y-228525D01*
X598338Y-228295D01*
X598958Y-227835D01*
X599371Y-227299D01*
X599578Y-226762D01*
Y-226225D01*
X599371Y-225689D01*
X599061Y-225229D01*
X598648Y-224845D01*
G01X594411Y-222019D02*
X593791Y-221559D01*
X593481Y-221022D01*
X593378Y-220409D01*
X593585Y-219642D01*
X594101Y-219105D01*
X594721Y-218952D01*
X595341Y-219029D01*
X595858Y-219335D01*
X596891Y-220869D01*
X597615Y-221559D01*
X598648Y-222019D01*
X599578Y-222172D01*
Y-218952D01*
G01Y-213442D02*
X593378D01*
X597821Y-216279D01*
Y-212445D01*
G01X598648Y-209849D02*
X599165Y-209389D01*
X599475Y-208852D01*
X599578Y-208162D01*
X599371Y-207472D01*
X598958Y-206935D01*
X598235Y-206552D01*
X597408Y-206475D01*
X596581Y-206629D01*
X596065Y-207012D01*
X595651Y-207549D01*
X595548Y-208085D01*
X595651Y-208622D01*
X596065Y-209312D01*
X593378Y-209082D01*
Y-207012D01*
G01X592446Y-203195D02*
X598646D01*
Y-200129D01*
G01Y-195462D02*
X592446D01*
X593686Y-196382D01*
G01X598646D02*
Y-194542D01*
G01X592446Y-189262D02*
X592653Y-189875D01*
X593169Y-190335D01*
X593789Y-190642D01*
X594616Y-190872D01*
X595546Y-190949D01*
X596476Y-190872D01*
X597303Y-190642D01*
X597923Y-190335D01*
X598439Y-189875D01*
X598646Y-189262D01*
X598439Y-188649D01*
X597923Y-188189D01*
X597303Y-187882D01*
X596476Y-187652D01*
X595546Y-187575D01*
X594616Y-187652D01*
X593789Y-187882D01*
X593169Y-188189D01*
X592653Y-188649D01*
X592446Y-189262D01*
G01X589965Y-158879D02*
X589505Y-158569D01*
X588968Y-158362D01*
X588355D01*
X587665Y-158672D01*
X587128Y-159189D01*
X586745Y-159809D01*
X586438Y-160842D01*
X586361Y-161772D01*
X586515Y-162702D01*
X586745Y-163322D01*
X587205Y-163942D01*
X587741Y-164355D01*
X588278Y-164562D01*
X588815D01*
X589351Y-164355D01*
X589811Y-164045D01*
X590195Y-163632D01*
G01X594478Y-164562D02*
Y-158362D01*
X593558Y-159602D01*
G01Y-164562D02*
X595398D01*
G01X599221Y-161979D02*
X599758Y-161255D01*
X600218Y-160842D01*
X600831Y-160635D01*
X601368Y-160842D01*
X601751Y-161255D01*
X602058Y-161875D01*
X602135Y-162599D01*
X602058Y-163219D01*
X601751Y-163839D01*
X601291Y-164355D01*
X600755Y-164562D01*
X600141Y-164355D01*
X599605Y-163736D01*
X599298Y-162805D01*
X599221Y-161772D01*
X599375Y-160429D01*
X599605Y-159705D01*
X599988Y-158982D01*
X600525Y-158465D01*
X601061Y-158362D01*
X601598Y-158569D01*
X601981Y-159085D01*
G01X607798Y-164562D02*
Y-158362D01*
X604961Y-162805D01*
X608795D01*
G01X590995Y-114075D02*
X590685Y-114535D01*
X590478Y-115072D01*
Y-115685D01*
X590788Y-116375D01*
X591305Y-116912D01*
X591925Y-117295D01*
X592958Y-117602D01*
X593888Y-117679D01*
X594818Y-117525D01*
X595438Y-117295D01*
X596058Y-116835D01*
X596471Y-116299D01*
X596678Y-115762D01*
Y-115225D01*
X596471Y-114689D01*
X596161Y-114229D01*
X595748Y-113845D01*
G01X596678Y-109562D02*
X590478D01*
X591718Y-110482D01*
G01X596678D02*
Y-108642D01*
G01X591511Y-104819D02*
X590891Y-104359D01*
X590581Y-103822D01*
X590478Y-103209D01*
X590685Y-102442D01*
X591201Y-101905D01*
X591821Y-101752D01*
X592441Y-101829D01*
X592958Y-102135D01*
X593991Y-103669D01*
X594715Y-104359D01*
X595748Y-104819D01*
X596678Y-104972D01*
Y-101752D01*
G01X595748Y-98849D02*
X596265Y-98389D01*
X596575Y-97852D01*
X596678Y-97162D01*
X596471Y-96472D01*
X596058Y-95935D01*
X595335Y-95552D01*
X594508Y-95475D01*
X593681Y-95629D01*
X593165Y-96012D01*
X592751Y-96549D01*
X592648Y-97085D01*
X592751Y-97622D01*
X593165Y-98312D01*
X590478Y-98082D01*
Y-96012D01*
G01X594745Y-32562D02*
Y-26362D01*
X596661D01*
X597275Y-26672D01*
X597658Y-27085D01*
X597811Y-27912D01*
X597658Y-28739D01*
X597198Y-29255D01*
X596661Y-29565D01*
X594745D01*
G01X596661D02*
X597811Y-32562D01*
G01X602478D02*
Y-26362D01*
X601558Y-27602D01*
G01Y-32562D02*
X603398D01*
G01X607375Y-31839D02*
X607911Y-32355D01*
X608525Y-32562D01*
X609138Y-32355D01*
X609675Y-31736D01*
X610058Y-30805D01*
X610211Y-29875D01*
Y-28739D01*
X610058Y-27809D01*
X609675Y-26982D01*
X609215Y-26569D01*
X608678Y-26362D01*
X608065Y-26569D01*
X607605Y-26982D01*
X607298Y-27602D01*
X607145Y-28429D01*
X607298Y-29152D01*
X607681Y-29875D01*
X608141Y-30289D01*
X608678Y-30392D01*
X609291Y-30185D01*
X609751Y-29669D01*
X610211Y-28739D01*
G01X613421Y-29979D02*
X613958Y-29255D01*
X614418Y-28842D01*
X615031Y-28635D01*
X615568Y-28842D01*
X615951Y-29255D01*
X616258Y-29875D01*
X616335Y-30599D01*
X616258Y-31219D01*
X615951Y-31839D01*
X615491Y-32355D01*
X614955Y-32562D01*
X614341Y-32355D01*
X613805Y-31736D01*
X613498Y-30805D01*
X613421Y-29772D01*
X613575Y-28429D01*
X613805Y-27705D01*
X614188Y-26982D01*
X614725Y-26465D01*
X615261Y-26362D01*
X615798Y-26569D01*
X616181Y-27085D01*
G01X592446Y121905D02*
X586246D01*
Y123821D01*
X586556Y124435D01*
X586969Y124818D01*
X587796Y124971D01*
X588623Y124818D01*
X589139Y124358D01*
X589449Y123821D01*
Y121905D01*
G01Y123821D02*
X592446Y124971D01*
G01X587279Y128181D02*
X586659Y128641D01*
X586349Y129178D01*
X586246Y129791D01*
X586453Y130558D01*
X586969Y131095D01*
X587589Y131248D01*
X588209Y131171D01*
X588726Y130865D01*
X589759Y129331D01*
X590483Y128641D01*
X591516Y128181D01*
X592446Y128028D01*
Y131248D01*
G01Y135838D02*
X592343Y136375D01*
X592033Y136988D01*
X591516Y137371D01*
X590793Y137525D01*
X590069Y137371D01*
X589449Y136911D01*
X589139Y136221D01*
Y135455D01*
X588933Y134995D01*
X588416Y134611D01*
X587693Y134458D01*
X586969Y134688D01*
X586453Y135225D01*
X586246Y135838D01*
X586453Y136451D01*
X586969Y136988D01*
X587693Y137218D01*
X588416Y137065D01*
X588933Y136681D01*
X589139Y136221D01*
Y135455D01*
X589449Y134765D01*
X590069Y134305D01*
X590793Y134151D01*
X591516Y134305D01*
X592033Y134688D01*
X592343Y135301D01*
X592446Y135838D01*
G01X589863Y140581D02*
X589139Y141118D01*
X588726Y141578D01*
X588519Y142191D01*
X588726Y142728D01*
X589139Y143111D01*
X589759Y143418D01*
X590483Y143495D01*
X591103Y143418D01*
X591723Y143111D01*
X592239Y142651D01*
X592446Y142115D01*
X592239Y141501D01*
X591620Y140965D01*
X590689Y140658D01*
X589656Y140581D01*
X588313Y140735D01*
X587589Y140965D01*
X586866Y141348D01*
X586349Y141885D01*
X586246Y142421D01*
X586453Y142958D01*
X586969Y143341D01*
G01X586745Y270438D02*
Y276638D01*
X588661D01*
X589275Y276328D01*
X589658Y275915D01*
X589811Y275088D01*
X589658Y274261D01*
X589198Y273745D01*
X588661Y273435D01*
X586745D01*
G01X588661D02*
X589811Y270438D01*
G01X594478D02*
Y276638D01*
X593558Y275398D01*
G01Y270438D02*
X595398D01*
G01X599375Y271161D02*
X599911Y270645D01*
X600525Y270438D01*
X601138Y270645D01*
X601675Y271264D01*
X602058Y272195D01*
X602211Y273125D01*
Y274261D01*
X602058Y275191D01*
X601675Y276018D01*
X601215Y276431D01*
X600678Y276638D01*
X600065Y276431D01*
X599605Y276018D01*
X599298Y275398D01*
X599145Y274571D01*
X599298Y273848D01*
X599681Y273125D01*
X600141Y272711D01*
X600678Y272608D01*
X601291Y272815D01*
X601751Y273331D01*
X602211Y274261D01*
G01X606878Y270438D02*
Y276638D01*
X605958Y275398D01*
G01Y270438D02*
X607798D01*
G01X586745Y279438D02*
Y285638D01*
X588661D01*
X589275Y285328D01*
X589658Y284915D01*
X589811Y284088D01*
X589658Y283261D01*
X589198Y282745D01*
X588661Y282435D01*
X586745D01*
G01X588661D02*
X589811Y279438D01*
G01X593021Y284605D02*
X593481Y285225D01*
X594018Y285535D01*
X594631Y285638D01*
X595398Y285431D01*
X595935Y284915D01*
X596088Y284295D01*
X596011Y283675D01*
X595705Y283158D01*
X594171Y282125D01*
X593481Y281401D01*
X593021Y280368D01*
X592868Y279438D01*
X596088D01*
G01X600678Y285638D02*
X600065Y285431D01*
X599605Y284915D01*
X599298Y284295D01*
X599068Y283468D01*
X598991Y282538D01*
X599068Y281608D01*
X599298Y280781D01*
X599605Y280161D01*
X600065Y279645D01*
X600678Y279438D01*
X601291Y279645D01*
X601751Y280161D01*
X602058Y280781D01*
X602288Y281608D01*
X602365Y282538D01*
X602288Y283468D01*
X602058Y284295D01*
X601751Y284915D01*
X601291Y285431D01*
X600678Y285638D01*
G01X606878D02*
X606265Y285431D01*
X605805Y284915D01*
X605498Y284295D01*
X605268Y283468D01*
X605191Y282538D01*
X605268Y281608D01*
X605498Y280781D01*
X605805Y280161D01*
X606265Y279645D01*
X606878Y279438D01*
X607491Y279645D01*
X607951Y280161D01*
X608258Y280781D01*
X608488Y281608D01*
X608565Y282538D01*
X608488Y283468D01*
X608258Y284295D01*
X607951Y284915D01*
X607491Y285431D01*
X606878Y285638D01*
G01X586745Y297438D02*
Y303638D01*
X588661D01*
X589275Y303328D01*
X589658Y302915D01*
X589811Y302088D01*
X589658Y301261D01*
X589198Y300745D01*
X588661Y300435D01*
X586745D01*
G01X588661D02*
X589811Y297438D01*
G01X593021Y302605D02*
X593481Y303225D01*
X594018Y303535D01*
X594631Y303638D01*
X595398Y303431D01*
X595935Y302915D01*
X596088Y302295D01*
X596011Y301675D01*
X595705Y301158D01*
X594171Y300125D01*
X593481Y299401D01*
X593021Y298368D01*
X592868Y297438D01*
X596088D01*
G01X600678Y303638D02*
X600065Y303431D01*
X599605Y302915D01*
X599298Y302295D01*
X599068Y301468D01*
X598991Y300538D01*
X599068Y299608D01*
X599298Y298781D01*
X599605Y298161D01*
X600065Y297645D01*
X600678Y297438D01*
X601291Y297645D01*
X601751Y298161D01*
X602058Y298781D01*
X602288Y299608D01*
X602365Y300538D01*
X602288Y301468D01*
X602058Y302295D01*
X601751Y302915D01*
X601291Y303431D01*
X600678Y303638D01*
G01X606878Y297438D02*
Y303638D01*
X605958Y302398D01*
G01Y297438D02*
X607798D01*
G01X586745Y288438D02*
Y294638D01*
X588661D01*
X589275Y294328D01*
X589658Y293915D01*
X589811Y293088D01*
X589658Y292261D01*
X589198Y291745D01*
X588661Y291435D01*
X586745D01*
G01X588661D02*
X589811Y288438D01*
G01X593021Y293605D02*
X593481Y294225D01*
X594018Y294535D01*
X594631Y294638D01*
X595398Y294431D01*
X595935Y293915D01*
X596088Y293295D01*
X596011Y292675D01*
X595705Y292158D01*
X594171Y291125D01*
X593481Y290401D01*
X593021Y289368D01*
X592868Y288438D01*
X596088D01*
G01X600678Y294638D02*
X600065Y294431D01*
X599605Y293915D01*
X599298Y293295D01*
X599068Y292468D01*
X598991Y291538D01*
X599068Y290608D01*
X599298Y289781D01*
X599605Y289161D01*
X600065Y288645D01*
X600678Y288438D01*
X601291Y288645D01*
X601751Y289161D01*
X602058Y289781D01*
X602288Y290608D01*
X602365Y291538D01*
X602288Y292468D01*
X602058Y293295D01*
X601751Y293915D01*
X601291Y294431D01*
X600678Y294638D01*
G01X607798Y288438D02*
Y294638D01*
X604961Y290195D01*
X608795D01*
G01X586745Y306438D02*
Y312638D01*
X588661D01*
X589275Y312328D01*
X589658Y311915D01*
X589811Y311088D01*
X589658Y310261D01*
X589198Y309745D01*
X588661Y309435D01*
X586745D01*
G01X588661D02*
X589811Y306438D01*
G01X593021Y311605D02*
X593481Y312225D01*
X594018Y312535D01*
X594631Y312638D01*
X595398Y312431D01*
X595935Y311915D01*
X596088Y311295D01*
X596011Y310675D01*
X595705Y310158D01*
X594171Y309125D01*
X593481Y308401D01*
X593021Y307368D01*
X592868Y306438D01*
X596088D01*
G01X600678Y312638D02*
X600065Y312431D01*
X599605Y311915D01*
X599298Y311295D01*
X599068Y310468D01*
X598991Y309538D01*
X599068Y308608D01*
X599298Y307781D01*
X599605Y307161D01*
X600065Y306645D01*
X600678Y306438D01*
X601291Y306645D01*
X601751Y307161D01*
X602058Y307781D01*
X602288Y308608D01*
X602365Y309538D01*
X602288Y310468D01*
X602058Y311295D01*
X601751Y311915D01*
X601291Y312431D01*
X600678Y312638D01*
G01X605191Y307368D02*
X605651Y306851D01*
X606188Y306541D01*
X606878Y306438D01*
X607568Y306645D01*
X608105Y307058D01*
X608488Y307781D01*
X608565Y308608D01*
X608411Y309435D01*
X608028Y309951D01*
X607491Y310365D01*
X606955Y310468D01*
X606418Y310365D01*
X605728Y309951D01*
X605958Y312638D01*
X608028D01*
G01X614283Y-91196D02*
Y-97396D01*
X617349D01*
G01X620329Y-96156D02*
X620789Y-96879D01*
X621403Y-97293D01*
X622093Y-97396D01*
X622706Y-97293D01*
X623319Y-96776D01*
X623703Y-96156D01*
X623779Y-95536D01*
X623626Y-94813D01*
X623089Y-94296D01*
X622553Y-94089D01*
X621863D01*
G01X622553D02*
X623013Y-93779D01*
X623396Y-93263D01*
X623549Y-92643D01*
X623396Y-92023D01*
X623013Y-91506D01*
X622323Y-91196D01*
X621633Y-91299D01*
X620943Y-91713D01*
G01X626529Y-96466D02*
X626989Y-96983D01*
X627526Y-97293D01*
X628216Y-97396D01*
X628906Y-97189D01*
X629443Y-96776D01*
X629826Y-96053D01*
X629903Y-95226D01*
X629749Y-94399D01*
X629366Y-93883D01*
X628829Y-93469D01*
X628293Y-93366D01*
X627756Y-93469D01*
X627066Y-93883D01*
X627296Y-91196D01*
X629366D01*
G01X616965Y63121D02*
X616505Y63431D01*
X615968Y63638D01*
X615355D01*
X614665Y63328D01*
X614128Y62811D01*
X613745Y62191D01*
X613438Y61158D01*
X613361Y60228D01*
X613515Y59298D01*
X613745Y58678D01*
X614205Y58058D01*
X614741Y57645D01*
X615278Y57438D01*
X615815D01*
X616351Y57645D01*
X616811Y57955D01*
X617195Y58368D01*
G01X621478Y57438D02*
Y63638D01*
X620558Y62398D01*
G01Y57438D02*
X622398D01*
G01X625991Y58368D02*
X626451Y57851D01*
X626988Y57541D01*
X627678Y57438D01*
X628368Y57645D01*
X628905Y58058D01*
X629288Y58781D01*
X629365Y59608D01*
X629211Y60435D01*
X628828Y60951D01*
X628291Y61365D01*
X627755Y61468D01*
X627218Y61365D01*
X626528Y60951D01*
X626758Y63638D01*
X628828D01*
G01X633878D02*
X633265Y63431D01*
X632805Y62915D01*
X632498Y62295D01*
X632268Y61468D01*
X632191Y60538D01*
X632268Y59608D01*
X632498Y58781D01*
X632805Y58161D01*
X633265Y57645D01*
X633878Y57438D01*
X634491Y57645D01*
X634951Y58161D01*
X635258Y58781D01*
X635488Y59608D01*
X635565Y60538D01*
X635488Y61468D01*
X635258Y62295D01*
X634951Y62915D01*
X634491Y63431D01*
X633878Y63638D01*
G01X613965Y75121D02*
X613505Y75431D01*
X612968Y75638D01*
X612355D01*
X611665Y75328D01*
X611128Y74811D01*
X610745Y74191D01*
X610438Y73158D01*
X610361Y72228D01*
X610515Y71298D01*
X610745Y70678D01*
X611205Y70058D01*
X611741Y69645D01*
X612278Y69438D01*
X612815D01*
X613351Y69645D01*
X613811Y69955D01*
X614195Y70368D01*
G01X618478Y69438D02*
Y75638D01*
X617558Y74398D01*
G01Y69438D02*
X619398D01*
G01X622991Y70368D02*
X623451Y69851D01*
X623988Y69541D01*
X624678Y69438D01*
X625368Y69645D01*
X625905Y70058D01*
X626288Y70781D01*
X626365Y71608D01*
X626211Y72435D01*
X625828Y72951D01*
X625291Y73365D01*
X624755Y73468D01*
X624218Y73365D01*
X623528Y72951D01*
X623758Y75638D01*
X625828D01*
G01X630878Y69438D02*
X631415Y69541D01*
X632028Y69851D01*
X632411Y70368D01*
X632565Y71091D01*
X632411Y71815D01*
X631951Y72435D01*
X631261Y72745D01*
X630495D01*
X630035Y72951D01*
X629651Y73468D01*
X629498Y74191D01*
X629728Y74915D01*
X630265Y75431D01*
X630878Y75638D01*
X631491Y75431D01*
X632028Y74915D01*
X632258Y74191D01*
X632105Y73468D01*
X631721Y72951D01*
X631261Y72745D01*
X630495D01*
X629805Y72435D01*
X629345Y71815D01*
X629191Y71091D01*
X629345Y70368D01*
X629728Y69851D01*
X630341Y69541D01*
X630878Y69438D01*
G01X615595Y215925D02*
X615285Y215465D01*
X615078Y214928D01*
Y214315D01*
X615388Y213625D01*
X615905Y213088D01*
X616525Y212705D01*
X617558Y212398D01*
X618488Y212321D01*
X619418Y212475D01*
X620038Y212705D01*
X620658Y213165D01*
X621071Y213701D01*
X621278Y214238D01*
Y214775D01*
X621071Y215311D01*
X620761Y215771D01*
X620348Y216155D01*
G01X621278Y220438D02*
X615078D01*
X616318Y219518D01*
G01X621278D02*
Y221358D01*
G01Y226638D02*
X621175Y227175D01*
X620865Y227788D01*
X620348Y228171D01*
X619625Y228325D01*
X618901Y228171D01*
X618281Y227711D01*
X617971Y227021D01*
Y226255D01*
X617765Y225795D01*
X617248Y225411D01*
X616525Y225258D01*
X615801Y225488D01*
X615285Y226025D01*
X615078Y226638D01*
X615285Y227251D01*
X615801Y227788D01*
X616525Y228018D01*
X617248Y227865D01*
X617765Y227481D01*
X617971Y227021D01*
Y226255D01*
X618281Y225565D01*
X618901Y225105D01*
X619625Y224951D01*
X620348Y225105D01*
X620865Y225488D01*
X621175Y226101D01*
X621278Y226638D01*
G01X615078Y232838D02*
X615285Y232225D01*
X615801Y231765D01*
X616421Y231458D01*
X617248Y231228D01*
X618178Y231151D01*
X619108Y231228D01*
X619935Y231458D01*
X620555Y231765D01*
X621071Y232225D01*
X621278Y232838D01*
X621071Y233451D01*
X620555Y233911D01*
X619935Y234218D01*
X619108Y234448D01*
X618178Y234525D01*
X617248Y234448D01*
X616421Y234218D01*
X615801Y233911D01*
X615285Y233451D01*
X615078Y232838D01*
G01X628945Y736D02*
Y6936D01*
X630861D01*
X631475Y6626D01*
X631858Y6213D01*
X632011Y5386D01*
X631858Y4559D01*
X631398Y4043D01*
X630861Y3733D01*
X628945D01*
G01X630861D02*
X632011Y736D01*
G01X636678D02*
Y6936D01*
X635758Y5696D01*
G01Y736D02*
X637598D01*
G01X642878Y6936D02*
X642265Y6729D01*
X641805Y6213D01*
X641498Y5593D01*
X641268Y4766D01*
X641191Y3836D01*
X641268Y2906D01*
X641498Y2079D01*
X641805Y1459D01*
X642265Y943D01*
X642878Y736D01*
X643491Y943D01*
X643951Y1459D01*
X644258Y2079D01*
X644488Y2906D01*
X644565Y3836D01*
X644488Y4766D01*
X644258Y5593D01*
X643951Y6213D01*
X643491Y6729D01*
X642878Y6936D01*
G01X647621Y3319D02*
X648158Y4043D01*
X648618Y4456D01*
X649231Y4663D01*
X649768Y4456D01*
X650151Y4043D01*
X650458Y3423D01*
X650535Y2699D01*
X650458Y2079D01*
X650151Y1459D01*
X649691Y943D01*
X649155Y736D01*
X648541Y943D01*
X648005Y1562D01*
X647698Y2493D01*
X647621Y3526D01*
X647775Y4869D01*
X648005Y5593D01*
X648388Y6316D01*
X648925Y6833D01*
X649461Y6936D01*
X649998Y6729D01*
X650381Y6213D01*
G01X628945Y9736D02*
Y15936D01*
X630861D01*
X631475Y15626D01*
X631858Y15213D01*
X632011Y14386D01*
X631858Y13559D01*
X631398Y13043D01*
X630861Y12733D01*
X628945D01*
G01X630861D02*
X632011Y9736D01*
G01X636678D02*
Y15936D01*
X635758Y14696D01*
G01Y9736D02*
X637598D01*
G01X642878Y15936D02*
X642265Y15729D01*
X641805Y15213D01*
X641498Y14593D01*
X641268Y13766D01*
X641191Y12836D01*
X641268Y11906D01*
X641498Y11079D01*
X641805Y10459D01*
X642265Y9943D01*
X642878Y9736D01*
X643491Y9943D01*
X643951Y10459D01*
X644258Y11079D01*
X644488Y11906D01*
X644565Y12836D01*
X644488Y13766D01*
X644258Y14593D01*
X643951Y15213D01*
X643491Y15729D01*
X642878Y15936D01*
G01X647391Y10666D02*
X647851Y10149D01*
X648388Y9839D01*
X649078Y9736D01*
X649768Y9943D01*
X650305Y10356D01*
X650688Y11079D01*
X650765Y11906D01*
X650611Y12733D01*
X650228Y13249D01*
X649691Y13663D01*
X649155Y13766D01*
X648618Y13663D01*
X647928Y13249D01*
X648158Y15936D01*
X650228D01*
G01X634245Y400838D02*
Y407038D01*
X636161D01*
X636775Y406728D01*
X637158Y406315D01*
X637311Y405488D01*
X637158Y404661D01*
X636698Y404145D01*
X636161Y403835D01*
X634245D01*
G01X636161D02*
X637311Y400838D01*
G01X640291Y401768D02*
X640751Y401251D01*
X641288Y400941D01*
X641978Y400838D01*
X642668Y401045D01*
X643205Y401458D01*
X643588Y402181D01*
X643665Y403008D01*
X643511Y403835D01*
X643128Y404351D01*
X642591Y404765D01*
X642055Y404868D01*
X641518Y404765D01*
X640828Y404351D01*
X641058Y407038D01*
X643128D01*
G01X649098Y400838D02*
Y407038D01*
X646261Y402595D01*
X650095D01*
G01X634245Y420838D02*
Y427038D01*
X636161D01*
X636775Y426728D01*
X637158Y426315D01*
X637311Y425488D01*
X637158Y424661D01*
X636698Y424145D01*
X636161Y423835D01*
X634245D01*
G01X636161D02*
X637311Y420838D01*
G01X640291Y422078D02*
X640751Y421355D01*
X641365Y420941D01*
X642055Y420838D01*
X642668Y420941D01*
X643281Y421458D01*
X643665Y422078D01*
X643741Y422698D01*
X643588Y423421D01*
X643051Y423938D01*
X642515Y424145D01*
X641825D01*
G01X642515D02*
X642975Y424455D01*
X643358Y424971D01*
X643511Y425591D01*
X643358Y426211D01*
X642975Y426728D01*
X642285Y427038D01*
X641595Y426935D01*
X640905Y426521D01*
G01X646721Y423421D02*
X647258Y424145D01*
X647718Y424558D01*
X648331Y424765D01*
X648868Y424558D01*
X649251Y424145D01*
X649558Y423525D01*
X649635Y422801D01*
X649558Y422181D01*
X649251Y421561D01*
X648791Y421045D01*
X648255Y420838D01*
X647641Y421045D01*
X647105Y421664D01*
X646798Y422595D01*
X646721Y423628D01*
X646875Y424971D01*
X647105Y425695D01*
X647488Y426418D01*
X648025Y426935D01*
X648561Y427038D01*
X649098Y426831D01*
X649481Y426315D01*
G01X637465Y417521D02*
X637005Y417831D01*
X636468Y418038D01*
X635855D01*
X635165Y417728D01*
X634628Y417211D01*
X634245Y416591D01*
X633938Y415558D01*
X633861Y414628D01*
X634015Y413698D01*
X634245Y413078D01*
X634705Y412458D01*
X635241Y412045D01*
X635778Y411838D01*
X636315D01*
X636851Y412045D01*
X637311Y412355D01*
X637695Y412768D01*
G01X640291D02*
X640751Y412251D01*
X641288Y411941D01*
X641978Y411838D01*
X642668Y412045D01*
X643205Y412458D01*
X643588Y413181D01*
X643665Y414008D01*
X643511Y414835D01*
X643128Y415351D01*
X642591Y415765D01*
X642055Y415868D01*
X641518Y415765D01*
X640828Y415351D01*
X641058Y418038D01*
X643128D01*
G01X649098Y411838D02*
Y418038D01*
X646261Y413595D01*
X650095D01*
G01X634245Y438838D02*
Y445038D01*
X636161D01*
X636775Y444728D01*
X637158Y444315D01*
X637311Y443488D01*
X637158Y442661D01*
X636698Y442145D01*
X636161Y441835D01*
X634245D01*
G01X636161D02*
X637311Y438838D01*
G01X640291Y439768D02*
X640751Y439251D01*
X641288Y438941D01*
X641978Y438838D01*
X642668Y439045D01*
X643205Y439458D01*
X643588Y440181D01*
X643665Y441008D01*
X643511Y441835D01*
X643128Y442351D01*
X642591Y442765D01*
X642055Y442868D01*
X641518Y442765D01*
X640828Y442351D01*
X641058Y445038D01*
X643128D01*
G01X646491Y440078D02*
X646951Y439355D01*
X647565Y438941D01*
X648255Y438838D01*
X648868Y438941D01*
X649481Y439458D01*
X649865Y440078D01*
X649941Y440698D01*
X649788Y441421D01*
X649251Y441938D01*
X648715Y442145D01*
X648025D01*
G01X648715D02*
X649175Y442455D01*
X649558Y442971D01*
X649711Y443591D01*
X649558Y444211D01*
X649175Y444728D01*
X648485Y445038D01*
X647795Y444935D01*
X647105Y444521D01*
G01X634365Y435521D02*
X633905Y435831D01*
X633368Y436038D01*
X632755D01*
X632065Y435728D01*
X631528Y435211D01*
X631145Y434591D01*
X630838Y433558D01*
X630761Y432628D01*
X630915Y431698D01*
X631145Y431078D01*
X631605Y430458D01*
X632141Y430045D01*
X632678Y429838D01*
X633215D01*
X633751Y430045D01*
X634211Y430355D01*
X634595Y430768D01*
G01X637421Y435005D02*
X637881Y435625D01*
X638418Y435935D01*
X639031Y436038D01*
X639798Y435831D01*
X640335Y435315D01*
X640488Y434695D01*
X640411Y434075D01*
X640105Y433558D01*
X638571Y432525D01*
X637881Y431801D01*
X637421Y430768D01*
X637268Y429838D01*
X640488D01*
G01X645078D02*
X645615Y429941D01*
X646228Y430251D01*
X646611Y430768D01*
X646765Y431491D01*
X646611Y432215D01*
X646151Y432835D01*
X645461Y433145D01*
X644695D01*
X644235Y433351D01*
X643851Y433868D01*
X643698Y434591D01*
X643928Y435315D01*
X644465Y435831D01*
X645078Y436038D01*
X645691Y435831D01*
X646228Y435315D01*
X646458Y434591D01*
X646305Y433868D01*
X645921Y433351D01*
X645461Y433145D01*
X644695D01*
X644005Y432835D01*
X643545Y432215D01*
X643391Y431491D01*
X643545Y430768D01*
X643928Y430251D01*
X644541Y429941D01*
X645078Y429838D01*
G01X649821Y432421D02*
X650358Y433145D01*
X650818Y433558D01*
X651431Y433765D01*
X651968Y433558D01*
X652351Y433145D01*
X652658Y432525D01*
X652735Y431801D01*
X652658Y431181D01*
X652351Y430561D01*
X651891Y430045D01*
X651355Y429838D01*
X650741Y430045D01*
X650205Y430664D01*
X649898Y431595D01*
X649821Y432628D01*
X649975Y433971D01*
X650205Y434695D01*
X650588Y435418D01*
X651125Y435935D01*
X651661Y436038D01*
X652198Y435831D01*
X652581Y435315D01*
G01X630845Y450470D02*
Y456670D01*
X632761D01*
X633375Y456360D01*
X633758Y455947D01*
X633911Y455120D01*
X633758Y454293D01*
X633298Y453777D01*
X632761Y453467D01*
X630845D01*
G01X632761D02*
X633911Y450470D01*
G01X636891Y451400D02*
X637351Y450883D01*
X637888Y450573D01*
X638578Y450470D01*
X639268Y450677D01*
X639805Y451090D01*
X640188Y451813D01*
X640265Y452640D01*
X640111Y453467D01*
X639728Y453983D01*
X639191Y454397D01*
X638655Y454500D01*
X638118Y454397D01*
X637428Y453983D01*
X637658Y456670D01*
X639728D01*
G01X644778Y450470D02*
Y456670D01*
X643858Y455430D01*
G01Y450470D02*
X645698D01*
G01X625145Y464902D02*
Y471102D01*
X627061D01*
X627675Y470792D01*
X628058Y470379D01*
X628211Y469552D01*
X628058Y468725D01*
X627598Y468209D01*
X627061Y467899D01*
X625145D01*
G01X627061D02*
X628211Y464902D01*
G01X631421Y470069D02*
X631881Y470689D01*
X632418Y470999D01*
X633031Y471102D01*
X633798Y470895D01*
X634335Y470379D01*
X634488Y469759D01*
X634411Y469139D01*
X634105Y468622D01*
X632571Y467589D01*
X631881Y466865D01*
X631421Y465832D01*
X631268Y464902D01*
X634488D01*
G01X637621Y467485D02*
X638158Y468209D01*
X638618Y468622D01*
X639231Y468829D01*
X639768Y468622D01*
X640151Y468209D01*
X640458Y467589D01*
X640535Y466865D01*
X640458Y466245D01*
X640151Y465625D01*
X639691Y465109D01*
X639155Y464902D01*
X638541Y465109D01*
X638005Y465728D01*
X637698Y466659D01*
X637621Y467692D01*
X637775Y469035D01*
X638005Y469759D01*
X638388Y470482D01*
X638925Y470999D01*
X639461Y471102D01*
X639998Y470895D01*
X640381Y470379D01*
G01X643591Y466142D02*
X644051Y465419D01*
X644665Y465005D01*
X645355Y464902D01*
X645968Y465005D01*
X646581Y465522D01*
X646965Y466142D01*
X647041Y466762D01*
X646888Y467485D01*
X646351Y468002D01*
X645815Y468209D01*
X645125D01*
G01X645815D02*
X646275Y468519D01*
X646658Y469035D01*
X646811Y469655D01*
X646658Y470275D01*
X646275Y470792D01*
X645585Y471102D01*
X644895Y470999D01*
X644205Y470585D01*
G01X643995Y-110075D02*
X643685Y-110535D01*
X643478Y-111072D01*
Y-111685D01*
X643788Y-112375D01*
X644305Y-112912D01*
X644925Y-113295D01*
X645958Y-113602D01*
X646888Y-113679D01*
X647818Y-113525D01*
X648438Y-113295D01*
X649058Y-112835D01*
X649471Y-112299D01*
X649678Y-111762D01*
Y-111225D01*
X649471Y-110689D01*
X649161Y-110229D01*
X648748Y-109845D01*
G01X649678Y-105562D02*
X643478D01*
X644718Y-106482D01*
G01X649678D02*
Y-104642D01*
G01X648438Y-101049D02*
X649161Y-100589D01*
X649575Y-99975D01*
X649678Y-99285D01*
X649575Y-98672D01*
X649058Y-98059D01*
X648438Y-97675D01*
X647818Y-97599D01*
X647095Y-97752D01*
X646578Y-98289D01*
X646371Y-98825D01*
Y-99515D01*
G01Y-98825D02*
X646061Y-98365D01*
X645545Y-97982D01*
X644925Y-97829D01*
X644305Y-97982D01*
X643788Y-98365D01*
X643478Y-99055D01*
X643581Y-99745D01*
X643995Y-100435D01*
G01X647095Y-94619D02*
X646371Y-94082D01*
X645958Y-93622D01*
X645751Y-93009D01*
X645958Y-92472D01*
X646371Y-92089D01*
X646991Y-91782D01*
X647715Y-91705D01*
X648335Y-91782D01*
X648955Y-92089D01*
X649471Y-92549D01*
X649678Y-93085D01*
X649471Y-93699D01*
X648852Y-94235D01*
X647921Y-94542D01*
X646888Y-94619D01*
X645545Y-94465D01*
X644821Y-94235D01*
X644098Y-93852D01*
X643581Y-93315D01*
X643478Y-92779D01*
X643685Y-92242D01*
X644201Y-91859D01*
G01X646995Y-15975D02*
X646685Y-16435D01*
X646478Y-16972D01*
Y-17585D01*
X646788Y-18275D01*
X647305Y-18812D01*
X647925Y-19195D01*
X648958Y-19502D01*
X649888Y-19579D01*
X650818Y-19425D01*
X651438Y-19195D01*
X652058Y-18735D01*
X652471Y-18199D01*
X652678Y-17662D01*
Y-17125D01*
X652471Y-16589D01*
X652161Y-16129D01*
X651748Y-15745D01*
G01X650095Y-12919D02*
X649371Y-12382D01*
X648958Y-11922D01*
X648751Y-11309D01*
X648958Y-10772D01*
X649371Y-10389D01*
X649991Y-10082D01*
X650715Y-10005D01*
X651335Y-10082D01*
X651955Y-10389D01*
X652471Y-10849D01*
X652678Y-11385D01*
X652471Y-11999D01*
X651852Y-12535D01*
X650921Y-12842D01*
X649888Y-12919D01*
X648545Y-12765D01*
X647821Y-12535D01*
X647098Y-12152D01*
X646581Y-11615D01*
X646478Y-11079D01*
X646685Y-10542D01*
X647201Y-10159D01*
G01X652678Y-5415D02*
X651335Y-5262D01*
X650198Y-5032D01*
X649165Y-4725D01*
X648028Y-4342D01*
X646478Y-3729D01*
Y-6795D01*
G01X653845Y74438D02*
Y80638D01*
X655761D01*
X656375Y80328D01*
X656758Y79915D01*
X656911Y79088D01*
X656758Y78261D01*
X656298Y77745D01*
X655761Y77435D01*
X653845D01*
G01X655761D02*
X656911Y74438D01*
G01X661425D02*
X661578Y75781D01*
X661808Y76918D01*
X662115Y77951D01*
X662498Y79088D01*
X663111Y80638D01*
X660045D01*
G01X668698Y74438D02*
Y80638D01*
X665861Y76195D01*
X669695D01*
G01X653845Y65438D02*
Y71638D01*
X655761D01*
X656375Y71328D01*
X656758Y70915D01*
X656911Y70088D01*
X656758Y69261D01*
X656298Y68745D01*
X655761Y68435D01*
X653845D01*
G01X655761D02*
X656911Y65438D01*
G01X661425D02*
X661578Y66781D01*
X661808Y67918D01*
X662115Y68951D01*
X662498Y70088D01*
X663111Y71638D01*
X660045D01*
G01X666321Y68021D02*
X666858Y68745D01*
X667318Y69158D01*
X667931Y69365D01*
X668468Y69158D01*
X668851Y68745D01*
X669158Y68125D01*
X669235Y67401D01*
X669158Y66781D01*
X668851Y66161D01*
X668391Y65645D01*
X667855Y65438D01*
X667241Y65645D01*
X666705Y66264D01*
X666398Y67195D01*
X666321Y68228D01*
X666475Y69571D01*
X666705Y70295D01*
X667088Y71018D01*
X667625Y71535D01*
X668161Y71638D01*
X668698Y71431D01*
X669081Y70915D01*
G01X659678Y86705D02*
X653478D01*
Y88621D01*
X653788Y89235D01*
X654201Y89618D01*
X655028Y89771D01*
X655855Y89618D01*
X656371Y89158D01*
X656681Y88621D01*
Y86705D01*
G01Y88621D02*
X659678Y89771D01*
G01Y94438D02*
X653478D01*
X654718Y93518D01*
G01X659678D02*
Y95358D01*
G01X657095Y99181D02*
X656371Y99718D01*
X655958Y100178D01*
X655751Y100791D01*
X655958Y101328D01*
X656371Y101711D01*
X656991Y102018D01*
X657715Y102095D01*
X658335Y102018D01*
X658955Y101711D01*
X659471Y101251D01*
X659678Y100715D01*
X659471Y100101D01*
X658852Y99565D01*
X657921Y99258D01*
X656888Y99181D01*
X655545Y99335D01*
X654821Y99565D01*
X654098Y99948D01*
X653581Y100485D01*
X653478Y101021D01*
X653685Y101558D01*
X654201Y101941D01*
G01X659678Y106838D02*
X659575Y107375D01*
X659265Y107988D01*
X658748Y108371D01*
X658025Y108525D01*
X657301Y108371D01*
X656681Y107911D01*
X656371Y107221D01*
Y106455D01*
X656165Y105995D01*
X655648Y105611D01*
X654925Y105458D01*
X654201Y105688D01*
X653685Y106225D01*
X653478Y106838D01*
X653685Y107451D01*
X654201Y107988D01*
X654925Y108218D01*
X655648Y108065D01*
X656165Y107681D01*
X656371Y107221D01*
Y106455D01*
X656681Y105765D01*
X657301Y105305D01*
X658025Y105151D01*
X658748Y105305D01*
X659265Y105688D01*
X659575Y106301D01*
X659678Y106838D01*
G01X656678Y192705D02*
X650478D01*
Y194621D01*
X650788Y195235D01*
X651201Y195618D01*
X652028Y195771D01*
X652855Y195618D01*
X653371Y195158D01*
X653681Y194621D01*
Y192705D01*
G01Y194621D02*
X656678Y195771D01*
G01X655438Y198751D02*
X656161Y199211D01*
X656575Y199825D01*
X656678Y200515D01*
X656575Y201128D01*
X656058Y201741D01*
X655438Y202125D01*
X654818Y202201D01*
X654095Y202048D01*
X653578Y201511D01*
X653371Y200975D01*
Y200285D01*
G01Y200975D02*
X653061Y201435D01*
X652545Y201818D01*
X651925Y201971D01*
X651305Y201818D01*
X650788Y201435D01*
X650478Y200745D01*
X650581Y200055D01*
X650995Y199365D01*
G01X656678Y207558D02*
X650478D01*
X654921Y204721D01*
Y208555D01*
G01X656678Y212838D02*
X650478D01*
X651718Y211918D01*
G01X656678D02*
Y213758D01*
G01X642745Y270438D02*
Y276638D01*
X644661D01*
X645275Y276328D01*
X645658Y275915D01*
X645811Y275088D01*
X645658Y274261D01*
X645198Y273745D01*
X644661Y273435D01*
X642745D01*
G01X644661D02*
X645811Y270438D01*
G01X649021Y275605D02*
X649481Y276225D01*
X650018Y276535D01*
X650631Y276638D01*
X651398Y276431D01*
X651935Y275915D01*
X652088Y275295D01*
X652011Y274675D01*
X651705Y274158D01*
X650171Y273125D01*
X649481Y272401D01*
X649021Y271368D01*
X648868Y270438D01*
X652088D01*
G01X656678Y276638D02*
X656065Y276431D01*
X655605Y275915D01*
X655298Y275295D01*
X655068Y274468D01*
X654991Y273538D01*
X655068Y272608D01*
X655298Y271781D01*
X655605Y271161D01*
X656065Y270645D01*
X656678Y270438D01*
X657291Y270645D01*
X657751Y271161D01*
X658058Y271781D01*
X658288Y272608D01*
X658365Y273538D01*
X658288Y274468D01*
X658058Y275295D01*
X657751Y275915D01*
X657291Y276431D01*
X656678Y276638D01*
G01X661421Y273021D02*
X661958Y273745D01*
X662418Y274158D01*
X663031Y274365D01*
X663568Y274158D01*
X663951Y273745D01*
X664258Y273125D01*
X664335Y272401D01*
X664258Y271781D01*
X663951Y271161D01*
X663491Y270645D01*
X662955Y270438D01*
X662341Y270645D01*
X661805Y271264D01*
X661498Y272195D01*
X661421Y273228D01*
X661575Y274571D01*
X661805Y275295D01*
X662188Y276018D01*
X662725Y276535D01*
X663261Y276638D01*
X663798Y276431D01*
X664181Y275915D01*
G01X642745Y279438D02*
Y285638D01*
X644661D01*
X645275Y285328D01*
X645658Y284915D01*
X645811Y284088D01*
X645658Y283261D01*
X645198Y282745D01*
X644661Y282435D01*
X642745D01*
G01X644661D02*
X645811Y279438D01*
G01X649021Y284605D02*
X649481Y285225D01*
X650018Y285535D01*
X650631Y285638D01*
X651398Y285431D01*
X651935Y284915D01*
X652088Y284295D01*
X652011Y283675D01*
X651705Y283158D01*
X650171Y282125D01*
X649481Y281401D01*
X649021Y280368D01*
X648868Y279438D01*
X652088D01*
G01X656678Y285638D02*
X656065Y285431D01*
X655605Y284915D01*
X655298Y284295D01*
X655068Y283468D01*
X654991Y282538D01*
X655068Y281608D01*
X655298Y280781D01*
X655605Y280161D01*
X656065Y279645D01*
X656678Y279438D01*
X657291Y279645D01*
X657751Y280161D01*
X658058Y280781D01*
X658288Y281608D01*
X658365Y282538D01*
X658288Y283468D01*
X658058Y284295D01*
X657751Y284915D01*
X657291Y285431D01*
X656678Y285638D01*
G01X661421Y284605D02*
X661881Y285225D01*
X662418Y285535D01*
X663031Y285638D01*
X663798Y285431D01*
X664335Y284915D01*
X664488Y284295D01*
X664411Y283675D01*
X664105Y283158D01*
X662571Y282125D01*
X661881Y281401D01*
X661421Y280368D01*
X661268Y279438D01*
X664488D01*
G01X642745Y288438D02*
Y294638D01*
X644661D01*
X645275Y294328D01*
X645658Y293915D01*
X645811Y293088D01*
X645658Y292261D01*
X645198Y291745D01*
X644661Y291435D01*
X642745D01*
G01X644661D02*
X645811Y288438D01*
G01X650478D02*
Y294638D01*
X649558Y293398D01*
G01Y288438D02*
X651398D01*
G01X655375Y289161D02*
X655911Y288645D01*
X656525Y288438D01*
X657138Y288645D01*
X657675Y289264D01*
X658058Y290195D01*
X658211Y291125D01*
Y292261D01*
X658058Y293191D01*
X657675Y294018D01*
X657215Y294431D01*
X656678Y294638D01*
X656065Y294431D01*
X655605Y294018D01*
X655298Y293398D01*
X655145Y292571D01*
X655298Y291848D01*
X655681Y291125D01*
X656141Y290711D01*
X656678Y290608D01*
X657291Y290815D01*
X657751Y291331D01*
X658211Y292261D01*
G01X661421Y293605D02*
X661881Y294225D01*
X662418Y294535D01*
X663031Y294638D01*
X663798Y294431D01*
X664335Y293915D01*
X664488Y293295D01*
X664411Y292675D01*
X664105Y292158D01*
X662571Y291125D01*
X661881Y290401D01*
X661421Y289368D01*
X661268Y288438D01*
X664488D01*
G01X642745Y297438D02*
Y303638D01*
X644661D01*
X645275Y303328D01*
X645658Y302915D01*
X645811Y302088D01*
X645658Y301261D01*
X645198Y300745D01*
X644661Y300435D01*
X642745D01*
G01X644661D02*
X645811Y297438D01*
G01X650478D02*
Y303638D01*
X649558Y302398D01*
G01Y297438D02*
X651398D01*
G01X655375Y298161D02*
X655911Y297645D01*
X656525Y297438D01*
X657138Y297645D01*
X657675Y298264D01*
X658058Y299195D01*
X658211Y300125D01*
Y301261D01*
X658058Y302191D01*
X657675Y303018D01*
X657215Y303431D01*
X656678Y303638D01*
X656065Y303431D01*
X655605Y303018D01*
X655298Y302398D01*
X655145Y301571D01*
X655298Y300848D01*
X655681Y300125D01*
X656141Y299711D01*
X656678Y299608D01*
X657291Y299815D01*
X657751Y300331D01*
X658211Y301261D01*
G01X661575Y298161D02*
X662111Y297645D01*
X662725Y297438D01*
X663338Y297645D01*
X663875Y298264D01*
X664258Y299195D01*
X664411Y300125D01*
Y301261D01*
X664258Y302191D01*
X663875Y303018D01*
X663415Y303431D01*
X662878Y303638D01*
X662265Y303431D01*
X661805Y303018D01*
X661498Y302398D01*
X661345Y301571D01*
X661498Y300848D01*
X661881Y300125D01*
X662341Y299711D01*
X662878Y299608D01*
X663491Y299815D01*
X663951Y300331D01*
X664411Y301261D01*
G01X642745Y306438D02*
Y312638D01*
X644661D01*
X645275Y312328D01*
X645658Y311915D01*
X645811Y311088D01*
X645658Y310261D01*
X645198Y309745D01*
X644661Y309435D01*
X642745D01*
G01X644661D02*
X645811Y306438D01*
G01X649021Y311605D02*
X649481Y312225D01*
X650018Y312535D01*
X650631Y312638D01*
X651398Y312431D01*
X651935Y311915D01*
X652088Y311295D01*
X652011Y310675D01*
X651705Y310158D01*
X650171Y309125D01*
X649481Y308401D01*
X649021Y307368D01*
X648868Y306438D01*
X652088D01*
G01X656678Y312638D02*
X656065Y312431D01*
X655605Y311915D01*
X655298Y311295D01*
X655068Y310468D01*
X654991Y309538D01*
X655068Y308608D01*
X655298Y307781D01*
X655605Y307161D01*
X656065Y306645D01*
X656678Y306438D01*
X657291Y306645D01*
X657751Y307161D01*
X658058Y307781D01*
X658288Y308608D01*
X658365Y309538D01*
X658288Y310468D01*
X658058Y311295D01*
X657751Y311915D01*
X657291Y312431D01*
X656678Y312638D01*
G01X661191Y307678D02*
X661651Y306955D01*
X662265Y306541D01*
X662955Y306438D01*
X663568Y306541D01*
X664181Y307058D01*
X664565Y307678D01*
X664641Y308298D01*
X664488Y309021D01*
X663951Y309538D01*
X663415Y309745D01*
X662725D01*
G01X663415D02*
X663875Y310055D01*
X664258Y310571D01*
X664411Y311191D01*
X664258Y311811D01*
X663875Y312328D01*
X663185Y312638D01*
X662495Y312535D01*
X661805Y312121D01*
G01X655995Y-112075D02*
X655685Y-112535D01*
X655478Y-113072D01*
Y-113685D01*
X655788Y-114375D01*
X656305Y-114912D01*
X656925Y-115295D01*
X657958Y-115602D01*
X658888Y-115679D01*
X659818Y-115525D01*
X660438Y-115295D01*
X661058Y-114835D01*
X661471Y-114299D01*
X661678Y-113762D01*
Y-113225D01*
X661471Y-112689D01*
X661161Y-112229D01*
X660748Y-111845D01*
G01X661678Y-107562D02*
X655478D01*
X656718Y-108482D01*
G01X661678D02*
Y-106642D01*
G01Y-100442D02*
X655478D01*
X659921Y-103279D01*
Y-99445D01*
G01X660438Y-96849D02*
X661161Y-96389D01*
X661575Y-95775D01*
X661678Y-95085D01*
X661575Y-94472D01*
X661058Y-93859D01*
X660438Y-93475D01*
X659818Y-93399D01*
X659095Y-93552D01*
X658578Y-94089D01*
X658371Y-94625D01*
Y-95315D01*
G01Y-94625D02*
X658061Y-94165D01*
X657545Y-93782D01*
X656925Y-93629D01*
X656305Y-93782D01*
X655788Y-94165D01*
X655478Y-94855D01*
X655581Y-95545D01*
X655995Y-96235D01*
G01X665678Y192705D02*
X659478D01*
Y194621D01*
X659788Y195235D01*
X660201Y195618D01*
X661028Y195771D01*
X661855Y195618D01*
X662371Y195158D01*
X662681Y194621D01*
Y192705D01*
G01Y194621D02*
X665678Y195771D01*
G01X664438Y198751D02*
X665161Y199211D01*
X665575Y199825D01*
X665678Y200515D01*
X665575Y201128D01*
X665058Y201741D01*
X664438Y202125D01*
X663818Y202201D01*
X663095Y202048D01*
X662578Y201511D01*
X662371Y200975D01*
Y200285D01*
G01Y200975D02*
X662061Y201435D01*
X661545Y201818D01*
X660925Y201971D01*
X660305Y201818D01*
X659788Y201435D01*
X659478Y200745D01*
X659581Y200055D01*
X659995Y199365D01*
G01X664438Y204951D02*
X665161Y205411D01*
X665575Y206025D01*
X665678Y206715D01*
X665575Y207328D01*
X665058Y207941D01*
X664438Y208325D01*
X663818Y208401D01*
X663095Y208248D01*
X662578Y207711D01*
X662371Y207175D01*
Y206485D01*
G01Y207175D02*
X662061Y207635D01*
X661545Y208018D01*
X660925Y208171D01*
X660305Y208018D01*
X659788Y207635D01*
X659478Y206945D01*
X659581Y206255D01*
X659995Y205565D01*
G01X659478Y212838D02*
X659685Y212225D01*
X660201Y211765D01*
X660821Y211458D01*
X661648Y211228D01*
X662578Y211151D01*
X663508Y211228D01*
X664335Y211458D01*
X664955Y211765D01*
X665471Y212225D01*
X665678Y212838D01*
X665471Y213451D01*
X664955Y213911D01*
X664335Y214218D01*
X663508Y214448D01*
X662578Y214525D01*
X661648Y214448D01*
X660821Y214218D01*
X660201Y213911D01*
X659685Y213451D01*
X659478Y212838D01*
G01X674678Y192705D02*
X668478D01*
Y194621D01*
X668788Y195235D01*
X669201Y195618D01*
X670028Y195771D01*
X670855Y195618D01*
X671371Y195158D01*
X671681Y194621D01*
Y192705D01*
G01Y194621D02*
X674678Y195771D01*
G01X673438Y198751D02*
X674161Y199211D01*
X674575Y199825D01*
X674678Y200515D01*
X674575Y201128D01*
X674058Y201741D01*
X673438Y202125D01*
X672818Y202201D01*
X672095Y202048D01*
X671578Y201511D01*
X671371Y200975D01*
Y200285D01*
G01Y200975D02*
X671061Y201435D01*
X670545Y201818D01*
X669925Y201971D01*
X669305Y201818D01*
X668788Y201435D01*
X668478Y200745D01*
X668581Y200055D01*
X668995Y199365D01*
G01X674678Y207558D02*
X668478D01*
X672921Y204721D01*
Y208555D01*
G01X669511Y211381D02*
X668891Y211841D01*
X668581Y212378D01*
X668478Y212991D01*
X668685Y213758D01*
X669201Y214295D01*
X669821Y214448D01*
X670441Y214371D01*
X670958Y214065D01*
X671991Y212531D01*
X672715Y211841D01*
X673748Y211381D01*
X674678Y211228D01*
Y214448D01*
G01X669168Y413664D02*
X669781Y413148D01*
X670471Y412838D01*
X671085D01*
X671698Y413148D01*
X672158Y413664D01*
X672388Y414388D01*
X672235Y415111D01*
X671851Y415731D01*
X671161Y416145D01*
X670241Y416351D01*
X669705Y416765D01*
X669475Y417488D01*
X669628Y418211D01*
X670011Y418728D01*
X670548Y419038D01*
X671085D01*
X671621Y418831D01*
X672081Y418315D01*
G01X675445Y412838D02*
Y419038D01*
X677285D01*
X677898Y418728D01*
X678358Y418005D01*
X678511Y417178D01*
X678358Y416351D01*
X677975Y415731D01*
X677285Y415421D01*
X675445D01*
G01X681721Y418005D02*
X682181Y418625D01*
X682718Y418935D01*
X683331Y419038D01*
X684098Y418831D01*
X684635Y418315D01*
X684788Y417695D01*
X684711Y417075D01*
X684405Y416558D01*
X682871Y415525D01*
X682181Y414801D01*
X681721Y413768D01*
X681568Y412838D01*
X684788D01*
G01X669845Y443470D02*
Y449670D01*
X671761D01*
X672375Y449360D01*
X672758Y448947D01*
X672911Y448120D01*
X672758Y447293D01*
X672298Y446777D01*
X671761Y446467D01*
X669845D01*
G01X671761D02*
X672911Y443470D01*
G01X675891Y444710D02*
X676351Y443987D01*
X676965Y443573D01*
X677655Y443470D01*
X678268Y443573D01*
X678881Y444090D01*
X679265Y444710D01*
X679341Y445330D01*
X679188Y446053D01*
X678651Y446570D01*
X678115Y446777D01*
X677425D01*
G01X678115D02*
X678575Y447087D01*
X678958Y447603D01*
X679111Y448223D01*
X678958Y448843D01*
X678575Y449360D01*
X677885Y449670D01*
X677195Y449567D01*
X676505Y449153D01*
G01X683625Y443470D02*
X683778Y444813D01*
X684008Y445950D01*
X684315Y446983D01*
X684698Y448120D01*
X685311Y449670D01*
X682245D01*
G01X674845Y74438D02*
Y80638D01*
X676761D01*
X677375Y80328D01*
X677758Y79915D01*
X677911Y79088D01*
X677758Y78261D01*
X677298Y77745D01*
X676761Y77435D01*
X674845D01*
G01X676761D02*
X677911Y74438D01*
G01X682425D02*
X682578Y75781D01*
X682808Y76918D01*
X683115Y77951D01*
X683498Y79088D01*
X684111Y80638D01*
X681045D01*
G01X687091Y75368D02*
X687551Y74851D01*
X688088Y74541D01*
X688778Y74438D01*
X689468Y74645D01*
X690005Y75058D01*
X690388Y75781D01*
X690465Y76608D01*
X690311Y77435D01*
X689928Y77951D01*
X689391Y78365D01*
X688855Y78468D01*
X688318Y78365D01*
X687628Y77951D01*
X687858Y80638D01*
X689928D01*
G01X674845Y65438D02*
Y71638D01*
X676761D01*
X677375Y71328D01*
X677758Y70915D01*
X677911Y70088D01*
X677758Y69261D01*
X677298Y68745D01*
X676761Y68435D01*
X674845D01*
G01X676761D02*
X677911Y65438D01*
G01X682425D02*
X682578Y66781D01*
X682808Y67918D01*
X683115Y68951D01*
X683498Y70088D01*
X684111Y71638D01*
X681045D01*
G01X688625Y65438D02*
X688778Y66781D01*
X689008Y67918D01*
X689315Y68951D01*
X689698Y70088D01*
X690311Y71638D01*
X687245D01*
G01X686678Y125205D02*
X680478D01*
Y127121D01*
X680788Y127735D01*
X681201Y128118D01*
X682028Y128271D01*
X682855Y128118D01*
X683371Y127658D01*
X683681Y127121D01*
Y125205D01*
G01Y127121D02*
X686678Y128271D01*
G01Y132938D02*
X686575Y133475D01*
X686265Y134088D01*
X685748Y134471D01*
X685025Y134625D01*
X684301Y134471D01*
X683681Y134011D01*
X683371Y133321D01*
Y132555D01*
X683165Y132095D01*
X682648Y131711D01*
X681925Y131558D01*
X681201Y131788D01*
X680685Y132325D01*
X680478Y132938D01*
X680685Y133551D01*
X681201Y134088D01*
X681925Y134318D01*
X682648Y134165D01*
X683165Y133781D01*
X683371Y133321D01*
Y132555D01*
X683681Y131865D01*
X684301Y131405D01*
X685025Y131251D01*
X685748Y131405D01*
X686265Y131788D01*
X686575Y132401D01*
X686678Y132938D01*
G01X680478Y139138D02*
X680685Y138525D01*
X681201Y138065D01*
X681821Y137758D01*
X682648Y137528D01*
X683578Y137451D01*
X684508Y137528D01*
X685335Y137758D01*
X685955Y138065D01*
X686471Y138525D01*
X686678Y139138D01*
X686471Y139751D01*
X685955Y140211D01*
X685335Y140518D01*
X684508Y140748D01*
X683578Y140825D01*
X682648Y140748D01*
X681821Y140518D01*
X681201Y140211D01*
X680685Y139751D01*
X680478Y139138D01*
G01X683678Y192705D02*
X677478D01*
Y194621D01*
X677788Y195235D01*
X678201Y195618D01*
X679028Y195771D01*
X679855Y195618D01*
X680371Y195158D01*
X680681Y194621D01*
Y192705D01*
G01Y194621D02*
X683678Y195771D01*
G01X682438Y198751D02*
X683161Y199211D01*
X683575Y199825D01*
X683678Y200515D01*
X683575Y201128D01*
X683058Y201741D01*
X682438Y202125D01*
X681818Y202201D01*
X681095Y202048D01*
X680578Y201511D01*
X680371Y200975D01*
Y200285D01*
G01Y200975D02*
X680061Y201435D01*
X679545Y201818D01*
X678925Y201971D01*
X678305Y201818D01*
X677788Y201435D01*
X677478Y200745D01*
X677581Y200055D01*
X677995Y199365D01*
G01X681095Y205181D02*
X680371Y205718D01*
X679958Y206178D01*
X679751Y206791D01*
X679958Y207328D01*
X680371Y207711D01*
X680991Y208018D01*
X681715Y208095D01*
X682335Y208018D01*
X682955Y207711D01*
X683471Y207251D01*
X683678Y206715D01*
X683471Y206101D01*
X682852Y205565D01*
X681921Y205258D01*
X680888Y205181D01*
X679545Y205335D01*
X678821Y205565D01*
X678098Y205948D01*
X677581Y206485D01*
X677478Y207021D01*
X677685Y207558D01*
X678201Y207941D01*
G01X682438Y211151D02*
X683161Y211611D01*
X683575Y212225D01*
X683678Y212915D01*
X683575Y213528D01*
X683058Y214141D01*
X682438Y214525D01*
X681818Y214601D01*
X681095Y214448D01*
X680578Y213911D01*
X680371Y213375D01*
Y212685D01*
G01Y213375D02*
X680061Y213835D01*
X679545Y214218D01*
X678925Y214371D01*
X678305Y214218D01*
X677788Y213835D01*
X677478Y213145D01*
X677581Y212455D01*
X677995Y211765D01*
G01X684345Y264438D02*
Y270638D01*
X686261D01*
X686875Y270328D01*
X687258Y269915D01*
X687411Y269088D01*
X687258Y268261D01*
X686798Y267745D01*
X686261Y267435D01*
X684345D01*
G01X686261D02*
X687411Y264438D01*
G01X692078D02*
Y270638D01*
X691158Y269398D01*
G01Y264438D02*
X692998D01*
G01X699198D02*
Y270638D01*
X696361Y266195D01*
X700195D01*
G01X703175Y265161D02*
X703711Y264645D01*
X704325Y264438D01*
X704938Y264645D01*
X705475Y265264D01*
X705858Y266195D01*
X706011Y267125D01*
Y268261D01*
X705858Y269191D01*
X705475Y270018D01*
X705015Y270431D01*
X704478Y270638D01*
X703865Y270431D01*
X703405Y270018D01*
X703098Y269398D01*
X702945Y268571D01*
X703098Y267848D01*
X703481Y267125D01*
X703941Y266711D01*
X704478Y266608D01*
X705091Y266815D01*
X705551Y267331D01*
X706011Y268261D01*
G01X684345Y273438D02*
Y279638D01*
X686261D01*
X686875Y279328D01*
X687258Y278915D01*
X687411Y278088D01*
X687258Y277261D01*
X686798Y276745D01*
X686261Y276435D01*
X684345D01*
G01X686261D02*
X687411Y273438D01*
G01X692078D02*
Y279638D01*
X691158Y278398D01*
G01Y273438D02*
X692998D01*
G01X696591Y274368D02*
X697051Y273851D01*
X697588Y273541D01*
X698278Y273438D01*
X698968Y273645D01*
X699505Y274058D01*
X699888Y274781D01*
X699965Y275608D01*
X699811Y276435D01*
X699428Y276951D01*
X698891Y277365D01*
X698355Y277468D01*
X697818Y277365D01*
X697128Y276951D01*
X697358Y279638D01*
X699428D01*
G01X703021Y278605D02*
X703481Y279225D01*
X704018Y279535D01*
X704631Y279638D01*
X705398Y279431D01*
X705935Y278915D01*
X706088Y278295D01*
X706011Y277675D01*
X705705Y277158D01*
X704171Y276125D01*
X703481Y275401D01*
X703021Y274368D01*
X702868Y273438D01*
X706088D01*
G01X684345Y282438D02*
Y288638D01*
X686261D01*
X686875Y288328D01*
X687258Y287915D01*
X687411Y287088D01*
X687258Y286261D01*
X686798Y285745D01*
X686261Y285435D01*
X684345D01*
G01X686261D02*
X687411Y282438D01*
G01X692078D02*
Y288638D01*
X691158Y287398D01*
G01Y282438D02*
X692998D01*
G01X696591Y283368D02*
X697051Y282851D01*
X697588Y282541D01*
X698278Y282438D01*
X698968Y282645D01*
X699505Y283058D01*
X699888Y283781D01*
X699965Y284608D01*
X699811Y285435D01*
X699428Y285951D01*
X698891Y286365D01*
X698355Y286468D01*
X697818Y286365D01*
X697128Y285951D01*
X697358Y288638D01*
X699428D01*
G01X702791Y283678D02*
X703251Y282955D01*
X703865Y282541D01*
X704555Y282438D01*
X705168Y282541D01*
X705781Y283058D01*
X706165Y283678D01*
X706241Y284298D01*
X706088Y285021D01*
X705551Y285538D01*
X705015Y285745D01*
X704325D01*
G01X705015D02*
X705475Y286055D01*
X705858Y286571D01*
X706011Y287191D01*
X705858Y287811D01*
X705475Y288328D01*
X704785Y288638D01*
X704095Y288535D01*
X703405Y288121D01*
G01X684345Y300438D02*
Y306638D01*
X686261D01*
X686875Y306328D01*
X687258Y305915D01*
X687411Y305088D01*
X687258Y304261D01*
X686798Y303745D01*
X686261Y303435D01*
X684345D01*
G01X686261D02*
X687411Y300438D01*
G01X692078D02*
Y306638D01*
X691158Y305398D01*
G01Y300438D02*
X692998D01*
G01X699198D02*
Y306638D01*
X696361Y302195D01*
X700195D01*
G01X703021Y303021D02*
X703558Y303745D01*
X704018Y304158D01*
X704631Y304365D01*
X705168Y304158D01*
X705551Y303745D01*
X705858Y303125D01*
X705935Y302401D01*
X705858Y301781D01*
X705551Y301161D01*
X705091Y300645D01*
X704555Y300438D01*
X703941Y300645D01*
X703405Y301264D01*
X703098Y302195D01*
X703021Y303228D01*
X703175Y304571D01*
X703405Y305295D01*
X703788Y306018D01*
X704325Y306535D01*
X704861Y306638D01*
X705398Y306431D01*
X705781Y305915D01*
G01X684345Y291438D02*
Y297638D01*
X686261D01*
X686875Y297328D01*
X687258Y296915D01*
X687411Y296088D01*
X687258Y295261D01*
X686798Y294745D01*
X686261Y294435D01*
X684345D01*
G01X686261D02*
X687411Y291438D01*
G01X692078D02*
Y297638D01*
X691158Y296398D01*
G01Y291438D02*
X692998D01*
G01X696591Y292368D02*
X697051Y291851D01*
X697588Y291541D01*
X698278Y291438D01*
X698968Y291645D01*
X699505Y292058D01*
X699888Y292781D01*
X699965Y293608D01*
X699811Y294435D01*
X699428Y294951D01*
X698891Y295365D01*
X698355Y295468D01*
X697818Y295365D01*
X697128Y294951D01*
X697358Y297638D01*
X699428D01*
G01X704478D02*
X703865Y297431D01*
X703405Y296915D01*
X703098Y296295D01*
X702868Y295468D01*
X702791Y294538D01*
X702868Y293608D01*
X703098Y292781D01*
X703405Y292161D01*
X703865Y291645D01*
X704478Y291438D01*
X705091Y291645D01*
X705551Y292161D01*
X705858Y292781D01*
X706088Y293608D01*
X706165Y294538D01*
X706088Y295468D01*
X705858Y296295D01*
X705551Y296915D01*
X705091Y297431D01*
X704478Y297638D01*
G01X684345Y309438D02*
Y315638D01*
X686261D01*
X686875Y315328D01*
X687258Y314915D01*
X687411Y314088D01*
X687258Y313261D01*
X686798Y312745D01*
X686261Y312435D01*
X684345D01*
G01X686261D02*
X687411Y309438D01*
G01X692078D02*
Y315638D01*
X691158Y314398D01*
G01Y309438D02*
X692998D01*
G01X696591Y310368D02*
X697051Y309851D01*
X697588Y309541D01*
X698278Y309438D01*
X698968Y309645D01*
X699505Y310058D01*
X699888Y310781D01*
X699965Y311608D01*
X699811Y312435D01*
X699428Y312951D01*
X698891Y313365D01*
X698355Y313468D01*
X697818Y313365D01*
X697128Y312951D01*
X697358Y315638D01*
X699428D01*
G01X702791Y310368D02*
X703251Y309851D01*
X703788Y309541D01*
X704478Y309438D01*
X705168Y309645D01*
X705705Y310058D01*
X706088Y310781D01*
X706165Y311608D01*
X706011Y312435D01*
X705628Y312951D01*
X705091Y313365D01*
X704555Y313468D01*
X704018Y313365D01*
X703328Y312951D01*
X703558Y315638D01*
X705628D01*
G01X687445Y318438D02*
Y324638D01*
X689361D01*
X689975Y324328D01*
X690358Y323915D01*
X690511Y323088D01*
X690358Y322261D01*
X689898Y321745D01*
X689361Y321435D01*
X687445D01*
G01X689361D02*
X690511Y318438D01*
G01X693721Y321021D02*
X694258Y321745D01*
X694718Y322158D01*
X695331Y322365D01*
X695868Y322158D01*
X696251Y321745D01*
X696558Y321125D01*
X696635Y320401D01*
X696558Y319781D01*
X696251Y319161D01*
X695791Y318645D01*
X695255Y318438D01*
X694641Y318645D01*
X694105Y319264D01*
X693798Y320195D01*
X693721Y321228D01*
X693875Y322571D01*
X694105Y323295D01*
X694488Y324018D01*
X695025Y324535D01*
X695561Y324638D01*
X696098Y324431D01*
X696481Y323915D01*
G01X701378Y324638D02*
X700765Y324431D01*
X700305Y323915D01*
X699998Y323295D01*
X699768Y322468D01*
X699691Y321538D01*
X699768Y320608D01*
X699998Y319781D01*
X700305Y319161D01*
X700765Y318645D01*
X701378Y318438D01*
X701991Y318645D01*
X702451Y319161D01*
X702758Y319781D01*
X702988Y320608D01*
X703065Y321538D01*
X702988Y322468D01*
X702758Y323295D01*
X702451Y323915D01*
X701991Y324431D01*
X701378Y324638D01*
G01X693065Y443121D02*
X692605Y443431D01*
X692068Y443638D01*
X691455D01*
X690765Y443328D01*
X690228Y442811D01*
X689845Y442191D01*
X689538Y441158D01*
X689461Y440228D01*
X689615Y439298D01*
X689845Y438678D01*
X690305Y438058D01*
X690841Y437645D01*
X691378Y437438D01*
X691915D01*
X692451Y437645D01*
X692911Y437955D01*
X693295Y438368D01*
G01X695891D02*
X696351Y437851D01*
X696888Y437541D01*
X697578Y437438D01*
X698268Y437645D01*
X698805Y438058D01*
X699188Y438781D01*
X699265Y439608D01*
X699111Y440435D01*
X698728Y440951D01*
X698191Y441365D01*
X697655Y441468D01*
X697118Y441365D01*
X696428Y440951D01*
X696658Y443638D01*
X698728D01*
G01X702321Y440021D02*
X702858Y440745D01*
X703318Y441158D01*
X703931Y441365D01*
X704468Y441158D01*
X704851Y440745D01*
X705158Y440125D01*
X705235Y439401D01*
X705158Y438781D01*
X704851Y438161D01*
X704391Y437645D01*
X703855Y437438D01*
X703241Y437645D01*
X702705Y438264D01*
X702398Y439195D01*
X702321Y440228D01*
X702475Y441571D01*
X702705Y442295D01*
X703088Y443018D01*
X703625Y443535D01*
X704161Y443638D01*
X704698Y443431D01*
X705081Y442915D01*
G01X698995Y198025D02*
X698685Y197565D01*
X698478Y197028D01*
Y196415D01*
X698788Y195725D01*
X699305Y195188D01*
X699925Y194805D01*
X700958Y194498D01*
X701888Y194421D01*
X702818Y194575D01*
X703438Y194805D01*
X704058Y195265D01*
X704471Y195801D01*
X704678Y196338D01*
Y196875D01*
X704471Y197411D01*
X704161Y197871D01*
X703748Y198255D01*
G01X702095Y201081D02*
X701371Y201618D01*
X700958Y202078D01*
X700751Y202691D01*
X700958Y203228D01*
X701371Y203611D01*
X701991Y203918D01*
X702715Y203995D01*
X703335Y203918D01*
X703955Y203611D01*
X704471Y203151D01*
X704678Y202615D01*
X704471Y202001D01*
X703852Y201465D01*
X702921Y201158D01*
X701888Y201081D01*
X700545Y201235D01*
X699821Y201465D01*
X699098Y201848D01*
X698581Y202385D01*
X698478Y202921D01*
X698685Y203458D01*
X699201Y203841D01*
G01X699511Y207281D02*
X698891Y207741D01*
X698581Y208278D01*
X698478Y208891D01*
X698685Y209658D01*
X699201Y210195D01*
X699821Y210348D01*
X700441Y210271D01*
X700958Y209965D01*
X701991Y208431D01*
X702715Y207741D01*
X703748Y207281D01*
X704678Y207128D01*
Y210348D01*
G01X710312Y195243D02*
X716512D01*
Y198309D01*
G01X715272Y201289D02*
X715995Y201749D01*
X716409Y202363D01*
X716512Y203053D01*
X716409Y203666D01*
X715892Y204279D01*
X715272Y204663D01*
X714652Y204739D01*
X713929Y204586D01*
X713412Y204049D01*
X713205Y203513D01*
Y202823D01*
G01Y203513D02*
X712895Y203973D01*
X712379Y204356D01*
X711759Y204509D01*
X711139Y204356D01*
X710622Y203973D01*
X710312Y203283D01*
X710415Y202593D01*
X710829Y201903D01*
G01X716678Y376805D02*
X710478D01*
Y378721D01*
X710788Y379335D01*
X711201Y379718D01*
X712028Y379871D01*
X712855Y379718D01*
X713371Y379258D01*
X713681Y378721D01*
Y376805D01*
G01Y378721D02*
X716678Y379871D01*
G01X715438Y382851D02*
X716161Y383311D01*
X716575Y383925D01*
X716678Y384615D01*
X716575Y385228D01*
X716058Y385841D01*
X715438Y386225D01*
X714818Y386301D01*
X714095Y386148D01*
X713578Y385611D01*
X713371Y385075D01*
Y384385D01*
G01Y385075D02*
X713061Y385535D01*
X712545Y385918D01*
X711925Y386071D01*
X711305Y385918D01*
X710788Y385535D01*
X710478Y384845D01*
X710581Y384155D01*
X710995Y383465D01*
G01X715955Y389435D02*
X716471Y389971D01*
X716678Y390585D01*
X716471Y391198D01*
X715852Y391735D01*
X714921Y392118D01*
X713991Y392271D01*
X712855D01*
X711925Y392118D01*
X711098Y391735D01*
X710685Y391275D01*
X710478Y390738D01*
X710685Y390125D01*
X711098Y389665D01*
X711718Y389358D01*
X712545Y389205D01*
X713268Y389358D01*
X713991Y389741D01*
X714405Y390201D01*
X714508Y390738D01*
X714301Y391351D01*
X713785Y391811D01*
X712855Y392271D01*
G01X710995Y402025D02*
X710685Y401565D01*
X710478Y401028D01*
Y400415D01*
X710788Y399725D01*
X711305Y399188D01*
X711925Y398805D01*
X712958Y398498D01*
X713888Y398421D01*
X714818Y398575D01*
X715438Y398805D01*
X716058Y399265D01*
X716471Y399801D01*
X716678Y400338D01*
Y400875D01*
X716471Y401411D01*
X716161Y401871D01*
X715748Y402255D01*
G01Y404851D02*
X716265Y405311D01*
X716575Y405848D01*
X716678Y406538D01*
X716471Y407228D01*
X716058Y407765D01*
X715335Y408148D01*
X714508Y408225D01*
X713681Y408071D01*
X713165Y407688D01*
X712751Y407151D01*
X712648Y406615D01*
X712751Y406078D01*
X713165Y405388D01*
X710478Y405618D01*
Y407688D01*
G01X716678Y412585D02*
X715335Y412738D01*
X714198Y412968D01*
X713165Y413275D01*
X712028Y413658D01*
X710478Y414271D01*
Y411205D01*
G01X728461Y-317462D02*
X730378Y-311262D01*
X732295Y-317462D01*
G01X731605Y-315292D02*
X729151D01*
G01X734891Y-316222D02*
X735351Y-316945D01*
X735965Y-317359D01*
X736655Y-317462D01*
X737268Y-317359D01*
X737881Y-316842D01*
X738265Y-316222D01*
X738341Y-315602D01*
X738188Y-314879D01*
X737651Y-314362D01*
X737115Y-314155D01*
X736425D01*
G01X737115D02*
X737575Y-313845D01*
X737958Y-313329D01*
X738111Y-312709D01*
X737958Y-312089D01*
X737575Y-311572D01*
X736885Y-311262D01*
X736195Y-311365D01*
X735505Y-311779D01*
G01X741321Y-312295D02*
X741781Y-311675D01*
X742318Y-311365D01*
X742931Y-311262D01*
X743698Y-311469D01*
X744235Y-311985D01*
X744388Y-312605D01*
X744311Y-313225D01*
X744005Y-313742D01*
X742471Y-314775D01*
X741781Y-315499D01*
X741321Y-316532D01*
X741168Y-317462D01*
X744388D01*
G01X739065Y18121D02*
X738605Y18431D01*
X738068Y18638D01*
X737455D01*
X736765Y18328D01*
X736228Y17811D01*
X735845Y17191D01*
X735538Y16158D01*
X735461Y15228D01*
X735615Y14298D01*
X735845Y13678D01*
X736305Y13058D01*
X736841Y12645D01*
X737378Y12438D01*
X737915D01*
X738451Y12645D01*
X738911Y12955D01*
X739295Y13368D01*
G01X742121Y15021D02*
X742658Y15745D01*
X743118Y16158D01*
X743731Y16365D01*
X744268Y16158D01*
X744651Y15745D01*
X744958Y15125D01*
X745035Y14401D01*
X744958Y13781D01*
X744651Y13161D01*
X744191Y12645D01*
X743655Y12438D01*
X743041Y12645D01*
X742505Y13264D01*
X742198Y14195D01*
X742121Y15228D01*
X742275Y16571D01*
X742505Y17295D01*
X742888Y18018D01*
X743425Y18535D01*
X743961Y18638D01*
X744498Y18431D01*
X744881Y17915D01*
G01X750698Y12438D02*
Y18638D01*
X747861Y14195D01*
X751695D01*
G01X742065Y30121D02*
X741605Y30431D01*
X741068Y30638D01*
X740455D01*
X739765Y30328D01*
X739228Y29811D01*
X738845Y29191D01*
X738538Y28158D01*
X738461Y27228D01*
X738615Y26298D01*
X738845Y25678D01*
X739305Y25058D01*
X739841Y24645D01*
X740378Y24438D01*
X740915D01*
X741451Y24645D01*
X741911Y24955D01*
X742295Y25368D01*
G01X745121Y27021D02*
X745658Y27745D01*
X746118Y28158D01*
X746731Y28365D01*
X747268Y28158D01*
X747651Y27745D01*
X747958Y27125D01*
X748035Y26401D01*
X747958Y25781D01*
X747651Y25161D01*
X747191Y24645D01*
X746655Y24438D01*
X746041Y24645D01*
X745505Y25264D01*
X745198Y26195D01*
X745121Y27228D01*
X745275Y28571D01*
X745505Y29295D01*
X745888Y30018D01*
X746425Y30535D01*
X746961Y30638D01*
X747498Y30431D01*
X747881Y29915D01*
G01X751091Y25368D02*
X751551Y24851D01*
X752088Y24541D01*
X752778Y24438D01*
X753468Y24645D01*
X754005Y25058D01*
X754388Y25781D01*
X754465Y26608D01*
X754311Y27435D01*
X753928Y27951D01*
X753391Y28365D01*
X752855Y28468D01*
X752318Y28365D01*
X751628Y27951D01*
X751858Y30638D01*
X753928D01*
G01X742065Y39121D02*
X741605Y39431D01*
X741068Y39638D01*
X740455D01*
X739765Y39328D01*
X739228Y38811D01*
X738845Y38191D01*
X738538Y37158D01*
X738461Y36228D01*
X738615Y35298D01*
X738845Y34678D01*
X739305Y34058D01*
X739841Y33645D01*
X740378Y33438D01*
X740915D01*
X741451Y33645D01*
X741911Y33955D01*
X742295Y34368D01*
G01X745121Y36021D02*
X745658Y36745D01*
X746118Y37158D01*
X746731Y37365D01*
X747268Y37158D01*
X747651Y36745D01*
X747958Y36125D01*
X748035Y35401D01*
X747958Y34781D01*
X747651Y34161D01*
X747191Y33645D01*
X746655Y33438D01*
X746041Y33645D01*
X745505Y34264D01*
X745198Y35195D01*
X745121Y36228D01*
X745275Y37571D01*
X745505Y38295D01*
X745888Y39018D01*
X746425Y39535D01*
X746961Y39638D01*
X747498Y39431D01*
X747881Y38915D01*
G01X751321Y36021D02*
X751858Y36745D01*
X752318Y37158D01*
X752931Y37365D01*
X753468Y37158D01*
X753851Y36745D01*
X754158Y36125D01*
X754235Y35401D01*
X754158Y34781D01*
X753851Y34161D01*
X753391Y33645D01*
X752855Y33438D01*
X752241Y33645D01*
X751705Y34264D01*
X751398Y35195D01*
X751321Y36228D01*
X751475Y37571D01*
X751705Y38295D01*
X752088Y39018D01*
X752625Y39535D01*
X753161Y39638D01*
X753698Y39431D01*
X754081Y38915D01*
G01X727121Y56605D02*
X727581Y57225D01*
X728118Y57535D01*
X728731Y57638D01*
X729498Y57431D01*
X730035Y56915D01*
X730188Y56295D01*
X730111Y55675D01*
X729805Y55158D01*
X728271Y54125D01*
X727581Y53401D01*
X727121Y52368D01*
X726968Y51438D01*
X730188D01*
G01X740995Y194925D02*
X740685Y194465D01*
X740478Y193928D01*
Y193315D01*
X740788Y192625D01*
X741305Y192088D01*
X741925Y191705D01*
X742958Y191398D01*
X743888Y191321D01*
X744818Y191475D01*
X745438Y191705D01*
X746058Y192165D01*
X746471Y192701D01*
X746678Y193238D01*
Y193775D01*
X746471Y194311D01*
X746161Y194771D01*
X745748Y195155D01*
G01X741511Y197981D02*
X740891Y198441D01*
X740581Y198978D01*
X740478Y199591D01*
X740685Y200358D01*
X741201Y200895D01*
X741821Y201048D01*
X742441Y200971D01*
X742958Y200665D01*
X743991Y199131D01*
X744715Y198441D01*
X745748Y197981D01*
X746678Y197828D01*
Y201048D01*
G01Y205638D02*
X746575Y206175D01*
X746265Y206788D01*
X745748Y207171D01*
X745025Y207325D01*
X744301Y207171D01*
X743681Y206711D01*
X743371Y206021D01*
Y205255D01*
X743165Y204795D01*
X742648Y204411D01*
X741925Y204258D01*
X741201Y204488D01*
X740685Y205025D01*
X740478Y205638D01*
X740685Y206251D01*
X741201Y206788D01*
X741925Y207018D01*
X742648Y206865D01*
X743165Y206481D01*
X743371Y206021D01*
Y205255D01*
X743681Y204565D01*
X744301Y204105D01*
X745025Y203951D01*
X745748Y204105D01*
X746265Y204488D01*
X746575Y205101D01*
X746678Y205638D01*
G01X741511Y210381D02*
X740891Y210841D01*
X740581Y211378D01*
X740478Y211991D01*
X740685Y212758D01*
X741201Y213295D01*
X741821Y213448D01*
X742441Y213371D01*
X742958Y213065D01*
X743991Y211531D01*
X744715Y210841D01*
X745748Y210381D01*
X746678Y210228D01*
Y213448D01*
G01X725995Y194925D02*
X725685Y194465D01*
X725478Y193928D01*
Y193315D01*
X725788Y192625D01*
X726305Y192088D01*
X726925Y191705D01*
X727958Y191398D01*
X728888Y191321D01*
X729818Y191475D01*
X730438Y191705D01*
X731058Y192165D01*
X731471Y192701D01*
X731678Y193238D01*
Y193775D01*
X731471Y194311D01*
X731161Y194771D01*
X730748Y195155D01*
G01X726511Y197981D02*
X725891Y198441D01*
X725581Y198978D01*
X725478Y199591D01*
X725685Y200358D01*
X726201Y200895D01*
X726821Y201048D01*
X727441Y200971D01*
X727958Y200665D01*
X728991Y199131D01*
X729715Y198441D01*
X730748Y197981D01*
X731678Y197828D01*
Y201048D01*
G01Y205638D02*
X731575Y206175D01*
X731265Y206788D01*
X730748Y207171D01*
X730025Y207325D01*
X729301Y207171D01*
X728681Y206711D01*
X728371Y206021D01*
Y205255D01*
X728165Y204795D01*
X727648Y204411D01*
X726925Y204258D01*
X726201Y204488D01*
X725685Y205025D01*
X725478Y205638D01*
X725685Y206251D01*
X726201Y206788D01*
X726925Y207018D01*
X727648Y206865D01*
X728165Y206481D01*
X728371Y206021D01*
Y205255D01*
X728681Y204565D01*
X729301Y204105D01*
X730025Y203951D01*
X730748Y204105D01*
X731265Y204488D01*
X731575Y205101D01*
X731678Y205638D01*
G01X730438Y210151D02*
X731161Y210611D01*
X731575Y211225D01*
X731678Y211915D01*
X731575Y212528D01*
X731058Y213141D01*
X730438Y213525D01*
X729818Y213601D01*
X729095Y213448D01*
X728578Y212911D01*
X728371Y212375D01*
Y211685D01*
G01Y212375D02*
X728061Y212835D01*
X727545Y213218D01*
X726925Y213371D01*
X726305Y213218D01*
X725788Y212835D01*
X725478Y212145D01*
X725581Y211455D01*
X725995Y210765D01*
G01X733445Y266470D02*
Y272670D01*
X735361D01*
X735975Y272360D01*
X736358Y271947D01*
X736511Y271120D01*
X736358Y270293D01*
X735898Y269777D01*
X735361Y269467D01*
X733445D01*
G01X735361D02*
X736511Y266470D01*
G01X739721Y269053D02*
X740258Y269777D01*
X740718Y270190D01*
X741331Y270397D01*
X741868Y270190D01*
X742251Y269777D01*
X742558Y269157D01*
X742635Y268433D01*
X742558Y267813D01*
X742251Y267193D01*
X741791Y266677D01*
X741255Y266470D01*
X740641Y266677D01*
X740105Y267296D01*
X739798Y268227D01*
X739721Y269260D01*
X739875Y270603D01*
X740105Y271327D01*
X740488Y272050D01*
X741025Y272567D01*
X741561Y272670D01*
X742098Y272463D01*
X742481Y271947D01*
G01X747378Y266470D02*
Y272670D01*
X746458Y271430D01*
G01Y266470D02*
X748298D01*
G01X730345Y284438D02*
Y290638D01*
X732261D01*
X732875Y290328D01*
X733258Y289915D01*
X733411Y289088D01*
X733258Y288261D01*
X732798Y287745D01*
X732261Y287435D01*
X730345D01*
G01X732261D02*
X733411Y284438D01*
G01X738078D02*
Y290638D01*
X737158Y289398D01*
G01Y284438D02*
X738998D01*
G01X742591Y285368D02*
X743051Y284851D01*
X743588Y284541D01*
X744278Y284438D01*
X744968Y284645D01*
X745505Y285058D01*
X745888Y285781D01*
X745965Y286608D01*
X745811Y287435D01*
X745428Y287951D01*
X744891Y288365D01*
X744355Y288468D01*
X743818Y288365D01*
X743128Y287951D01*
X743358Y290638D01*
X745428D01*
G01X751398Y284438D02*
Y290638D01*
X748561Y286195D01*
X752395D01*
G01X733445Y276470D02*
Y282670D01*
X735361D01*
X735975Y282360D01*
X736358Y281947D01*
X736511Y281120D01*
X736358Y280293D01*
X735898Y279777D01*
X735361Y279467D01*
X733445D01*
G01X735361D02*
X736511Y276470D01*
G01X739721Y279053D02*
X740258Y279777D01*
X740718Y280190D01*
X741331Y280397D01*
X741868Y280190D01*
X742251Y279777D01*
X742558Y279157D01*
X742635Y278433D01*
X742558Y277813D01*
X742251Y277193D01*
X741791Y276677D01*
X741255Y276470D01*
X740641Y276677D01*
X740105Y277296D01*
X739798Y278227D01*
X739721Y279260D01*
X739875Y280603D01*
X740105Y281327D01*
X740488Y282050D01*
X741025Y282567D01*
X741561Y282670D01*
X742098Y282463D01*
X742481Y281947D01*
G01X745921Y281637D02*
X746381Y282257D01*
X746918Y282567D01*
X747531Y282670D01*
X748298Y282463D01*
X748835Y281947D01*
X748988Y281327D01*
X748911Y280707D01*
X748605Y280190D01*
X747071Y279157D01*
X746381Y278433D01*
X745921Y277400D01*
X745768Y276470D01*
X748988D01*
G01X730345Y293438D02*
Y299638D01*
X732261D01*
X732875Y299328D01*
X733258Y298915D01*
X733411Y298088D01*
X733258Y297261D01*
X732798Y296745D01*
X732261Y296435D01*
X730345D01*
G01X732261D02*
X733411Y293438D01*
G01X738078D02*
Y299638D01*
X737158Y298398D01*
G01Y293438D02*
X738998D01*
G01X742591Y294368D02*
X743051Y293851D01*
X743588Y293541D01*
X744278Y293438D01*
X744968Y293645D01*
X745505Y294058D01*
X745888Y294781D01*
X745965Y295608D01*
X745811Y296435D01*
X745428Y296951D01*
X744891Y297365D01*
X744355Y297468D01*
X743818Y297365D01*
X743128Y296951D01*
X743358Y299638D01*
X745428D01*
G01X750478Y293438D02*
Y299638D01*
X749558Y298398D01*
G01Y293438D02*
X751398D01*
G01X753389Y-256975D02*
X753079Y-257435D01*
X752872Y-257972D01*
Y-258585D01*
X753182Y-259275D01*
X753699Y-259812D01*
X754319Y-260195D01*
X755352Y-260502D01*
X756282Y-260579D01*
X757212Y-260425D01*
X757832Y-260195D01*
X758452Y-259735D01*
X758865Y-259199D01*
X759072Y-258662D01*
Y-258125D01*
X758865Y-257589D01*
X758555Y-257129D01*
X758142Y-256745D01*
G01X757832Y-254149D02*
X758555Y-253689D01*
X758969Y-253075D01*
X759072Y-252385D01*
X758969Y-251772D01*
X758452Y-251159D01*
X757832Y-250775D01*
X757212Y-250699D01*
X756489Y-250852D01*
X755972Y-251389D01*
X755765Y-251925D01*
Y-252615D01*
G01Y-251925D02*
X755455Y-251465D01*
X754939Y-251082D01*
X754319Y-250929D01*
X753699Y-251082D01*
X753182Y-251465D01*
X752872Y-252155D01*
X752975Y-252845D01*
X753389Y-253535D01*
G01X758142Y-247949D02*
X758659Y-247489D01*
X758969Y-246952D01*
X759072Y-246262D01*
X758865Y-245572D01*
X758452Y-245035D01*
X757729Y-244652D01*
X756902Y-244575D01*
X756075Y-244729D01*
X755559Y-245112D01*
X755145Y-245649D01*
X755042Y-246185D01*
X755145Y-246722D01*
X755559Y-247412D01*
X752872Y-247182D01*
Y-245112D01*
G01X743389Y-256975D02*
X743079Y-257435D01*
X742872Y-257972D01*
Y-258585D01*
X743182Y-259275D01*
X743699Y-259812D01*
X744319Y-260195D01*
X745352Y-260502D01*
X746282Y-260579D01*
X747212Y-260425D01*
X747832Y-260195D01*
X748452Y-259735D01*
X748865Y-259199D01*
X749072Y-258662D01*
Y-258125D01*
X748865Y-257589D01*
X748555Y-257129D01*
X748142Y-256745D01*
G01X747832Y-254149D02*
X748555Y-253689D01*
X748969Y-253075D01*
X749072Y-252385D01*
X748969Y-251772D01*
X748452Y-251159D01*
X747832Y-250775D01*
X747212Y-250699D01*
X746489Y-250852D01*
X745972Y-251389D01*
X745765Y-251925D01*
Y-252615D01*
G01Y-251925D02*
X745455Y-251465D01*
X744939Y-251082D01*
X744319Y-250929D01*
X743699Y-251082D01*
X743182Y-251465D01*
X742872Y-252155D01*
X742975Y-252845D01*
X743389Y-253535D01*
G01X746489Y-247719D02*
X745765Y-247182D01*
X745352Y-246722D01*
X745145Y-246109D01*
X745352Y-245572D01*
X745765Y-245189D01*
X746385Y-244882D01*
X747109Y-244805D01*
X747729Y-244882D01*
X748349Y-245189D01*
X748865Y-245649D01*
X749072Y-246185D01*
X748865Y-246799D01*
X748246Y-247335D01*
X747315Y-247642D01*
X746282Y-247719D01*
X744939Y-247565D01*
X744215Y-247335D01*
X743492Y-246952D01*
X742975Y-246415D01*
X742872Y-245879D01*
X743079Y-245342D01*
X743595Y-244959D01*
G01X750644Y59438D02*
X750541Y58825D01*
X750127Y58288D01*
X749507Y57828D01*
X748784Y57521D01*
X747957Y57368D01*
X747131D01*
X746304Y57521D01*
X745581Y57828D01*
X744961Y58288D01*
X744547Y58825D01*
X744444Y59438D01*
X744547Y60051D01*
X744961Y60588D01*
X745581Y61048D01*
X746304Y61355D01*
X747131Y61508D01*
X747957D01*
X748784Y61355D01*
X749507Y61048D01*
X750127Y60588D01*
X750541Y60051D01*
X750644Y59438D01*
G01X748991Y60051D02*
X750644Y60971D01*
G01X745477Y64181D02*
X744857Y64641D01*
X744547Y65178D01*
X744444Y65791D01*
X744651Y66558D01*
X745167Y67095D01*
X745787Y67248D01*
X746407Y67171D01*
X746924Y66865D01*
X747957Y65331D01*
X748681Y64641D01*
X749714Y64181D01*
X750644Y64028D01*
Y67248D01*
G01X750678Y86438D02*
X750575Y85825D01*
X750161Y85288D01*
X749541Y84828D01*
X748818Y84521D01*
X747991Y84368D01*
X747165D01*
X746338Y84521D01*
X745615Y84828D01*
X744995Y85288D01*
X744581Y85825D01*
X744478Y86438D01*
X744581Y87051D01*
X744995Y87588D01*
X745615Y88048D01*
X746338Y88355D01*
X747165Y88508D01*
X747991D01*
X748818Y88355D01*
X749541Y88048D01*
X750161Y87588D01*
X750575Y87051D01*
X750678Y86438D01*
G01X749025Y87051D02*
X750678Y87971D01*
G01X749438Y90951D02*
X750161Y91411D01*
X750575Y92025D01*
X750678Y92715D01*
X750575Y93328D01*
X750058Y93941D01*
X749438Y94325D01*
X748818Y94401D01*
X748095Y94248D01*
X747578Y93711D01*
X747371Y93175D01*
Y92485D01*
G01Y93175D02*
X747061Y93635D01*
X746545Y94018D01*
X745925Y94171D01*
X745305Y94018D01*
X744788Y93635D01*
X744478Y92945D01*
X744581Y92255D01*
X744995Y91565D01*
G01X760121Y101605D02*
X760581Y102225D01*
X761118Y102535D01*
X761731Y102638D01*
X762498Y102431D01*
X763035Y101915D01*
X763188Y101295D01*
X763111Y100675D01*
X762805Y100158D01*
X761271Y99125D01*
X760581Y98401D01*
X760121Y97368D01*
X759968Y96438D01*
X763188D01*
G01X755995Y198025D02*
X755685Y197565D01*
X755478Y197028D01*
Y196415D01*
X755788Y195725D01*
X756305Y195188D01*
X756925Y194805D01*
X757958Y194498D01*
X758888Y194421D01*
X759818Y194575D01*
X760438Y194805D01*
X761058Y195265D01*
X761471Y195801D01*
X761678Y196338D01*
Y196875D01*
X761471Y197411D01*
X761161Y197871D01*
X760748Y198255D01*
G01Y200851D02*
X761265Y201311D01*
X761575Y201848D01*
X761678Y202538D01*
X761471Y203228D01*
X761058Y203765D01*
X760335Y204148D01*
X759508Y204225D01*
X758681Y204071D01*
X758165Y203688D01*
X757751Y203151D01*
X757648Y202615D01*
X757751Y202078D01*
X758165Y201388D01*
X755478Y201618D01*
Y203688D01*
G01X761678Y208738D02*
X761575Y209275D01*
X761265Y209888D01*
X760748Y210271D01*
X760025Y210425D01*
X759301Y210271D01*
X758681Y209811D01*
X758371Y209121D01*
Y208355D01*
X758165Y207895D01*
X757648Y207511D01*
X756925Y207358D01*
X756201Y207588D01*
X755685Y208125D01*
X755478Y208738D01*
X755685Y209351D01*
X756201Y209888D01*
X756925Y210118D01*
X757648Y209965D01*
X758165Y209581D01*
X758371Y209121D01*
Y208355D01*
X758681Y207665D01*
X759301Y207205D01*
X760025Y207051D01*
X760748Y207205D01*
X761265Y207588D01*
X761575Y208201D01*
X761678Y208738D01*
G01X771678Y82805D02*
X765478D01*
Y84721D01*
X765788Y85335D01*
X766201Y85718D01*
X767028Y85871D01*
X767855Y85718D01*
X768371Y85258D01*
X768681Y84721D01*
Y82805D01*
G01Y84721D02*
X771678Y85871D01*
G01Y91458D02*
X765478D01*
X769921Y88621D01*
Y92455D01*
G01X771678Y97658D02*
X765478D01*
X769921Y94821D01*
Y98655D01*
G01X767995Y195025D02*
X767685Y194565D01*
X767478Y194028D01*
Y193415D01*
X767788Y192725D01*
X768305Y192188D01*
X768925Y191805D01*
X769958Y191498D01*
X770888Y191421D01*
X771818Y191575D01*
X772438Y191805D01*
X773058Y192265D01*
X773471Y192801D01*
X773678Y193338D01*
Y193875D01*
X773471Y194411D01*
X773161Y194871D01*
X772748Y195255D01*
G01X771095Y198081D02*
X770371Y198618D01*
X769958Y199078D01*
X769751Y199691D01*
X769958Y200228D01*
X770371Y200611D01*
X770991Y200918D01*
X771715Y200995D01*
X772335Y200918D01*
X772955Y200611D01*
X773471Y200151D01*
X773678Y199615D01*
X773471Y199001D01*
X772852Y198465D01*
X771921Y198158D01*
X770888Y198081D01*
X769545Y198235D01*
X768821Y198465D01*
X768098Y198848D01*
X767581Y199385D01*
X767478Y199921D01*
X767685Y200458D01*
X768201Y200841D01*
G01X767478Y205738D02*
X767685Y205125D01*
X768201Y204665D01*
X768821Y204358D01*
X769648Y204128D01*
X770578Y204051D01*
X771508Y204128D01*
X772335Y204358D01*
X772955Y204665D01*
X773471Y205125D01*
X773678Y205738D01*
X773471Y206351D01*
X772955Y206811D01*
X772335Y207118D01*
X771508Y207348D01*
X770578Y207425D01*
X769648Y207348D01*
X768821Y207118D01*
X768201Y206811D01*
X767685Y206351D01*
X767478Y205738D01*
G01X776995Y195025D02*
X776685Y194565D01*
X776478Y194028D01*
Y193415D01*
X776788Y192725D01*
X777305Y192188D01*
X777925Y191805D01*
X778958Y191498D01*
X779888Y191421D01*
X780818Y191575D01*
X781438Y191805D01*
X782058Y192265D01*
X782471Y192801D01*
X782678Y193338D01*
Y193875D01*
X782471Y194411D01*
X782161Y194871D01*
X781748Y195255D01*
G01Y197851D02*
X782265Y198311D01*
X782575Y198848D01*
X782678Y199538D01*
X782471Y200228D01*
X782058Y200765D01*
X781335Y201148D01*
X780508Y201225D01*
X779681Y201071D01*
X779165Y200688D01*
X778751Y200151D01*
X778648Y199615D01*
X778751Y199078D01*
X779165Y198388D01*
X776478Y198618D01*
Y200688D01*
G01X781955Y204435D02*
X782471Y204971D01*
X782678Y205585D01*
X782471Y206198D01*
X781852Y206735D01*
X780921Y207118D01*
X779991Y207271D01*
X778855D01*
X777925Y207118D01*
X777098Y206735D01*
X776685Y206275D01*
X776478Y205738D01*
X776685Y205125D01*
X777098Y204665D01*
X777718Y204358D01*
X778545Y204205D01*
X779268Y204358D01*
X779991Y204741D01*
X780405Y205201D01*
X780508Y205738D01*
X780301Y206351D01*
X779785Y206811D01*
X778855Y207271D01*
G01X787885Y-256975D02*
X787575Y-257435D01*
X787368Y-257972D01*
Y-258585D01*
X787678Y-259275D01*
X788195Y-259812D01*
X788815Y-260195D01*
X789848Y-260502D01*
X790778Y-260579D01*
X791708Y-260425D01*
X792328Y-260195D01*
X792948Y-259735D01*
X793361Y-259199D01*
X793568Y-258662D01*
Y-258125D01*
X793361Y-257589D01*
X793051Y-257129D01*
X792638Y-256745D01*
G01X788401Y-253919D02*
X787781Y-253459D01*
X787471Y-252922D01*
X787368Y-252309D01*
X787575Y-251542D01*
X788091Y-251005D01*
X788711Y-250852D01*
X789331Y-250929D01*
X789848Y-251235D01*
X790881Y-252769D01*
X791605Y-253459D01*
X792638Y-253919D01*
X793568Y-254072D01*
Y-250852D01*
G01Y-246262D02*
X793465Y-245725D01*
X793155Y-245112D01*
X792638Y-244729D01*
X791915Y-244575D01*
X791191Y-244729D01*
X790571Y-245189D01*
X790261Y-245879D01*
Y-246645D01*
X790055Y-247105D01*
X789538Y-247489D01*
X788815Y-247642D01*
X788091Y-247412D01*
X787575Y-246875D01*
X787368Y-246262D01*
X787575Y-245649D01*
X788091Y-245112D01*
X788815Y-244882D01*
X789538Y-245035D01*
X790055Y-245419D01*
X790261Y-245879D01*
Y-246645D01*
X790571Y-247335D01*
X791191Y-247795D01*
X791915Y-247949D01*
X792638Y-247795D01*
X793155Y-247412D01*
X793465Y-246799D01*
X793568Y-246262D01*
G01X777885Y-256975D02*
X777575Y-257435D01*
X777368Y-257972D01*
Y-258585D01*
X777678Y-259275D01*
X778195Y-259812D01*
X778815Y-260195D01*
X779848Y-260502D01*
X780778Y-260579D01*
X781708Y-260425D01*
X782328Y-260195D01*
X782948Y-259735D01*
X783361Y-259199D01*
X783568Y-258662D01*
Y-258125D01*
X783361Y-257589D01*
X783051Y-257129D01*
X782638Y-256745D01*
G01X782328Y-254149D02*
X783051Y-253689D01*
X783465Y-253075D01*
X783568Y-252385D01*
X783465Y-251772D01*
X782948Y-251159D01*
X782328Y-250775D01*
X781708Y-250699D01*
X780985Y-250852D01*
X780468Y-251389D01*
X780261Y-251925D01*
Y-252615D01*
G01Y-251925D02*
X779951Y-251465D01*
X779435Y-251082D01*
X778815Y-250929D01*
X778195Y-251082D01*
X777678Y-251465D01*
X777368Y-252155D01*
X777471Y-252845D01*
X777885Y-253535D01*
G01X783568Y-245342D02*
X777368D01*
X781811Y-248179D01*
Y-244345D01*
G01X794678Y-9395D02*
X788478D01*
Y-7479D01*
X788788Y-6865D01*
X789201Y-6482D01*
X790028Y-6329D01*
X790855Y-6482D01*
X791371Y-6942D01*
X791681Y-7479D01*
Y-9395D01*
G01Y-7479D02*
X794678Y-6329D01*
G01X793955Y-2965D02*
X794471Y-2429D01*
X794678Y-1815D01*
X794471Y-1202D01*
X793852Y-665D01*
X792921Y-282D01*
X791991Y-129D01*
X790855D01*
X789925Y-282D01*
X789098Y-665D01*
X788685Y-1125D01*
X788478Y-1662D01*
X788685Y-2275D01*
X789098Y-2735D01*
X789718Y-3042D01*
X790545Y-3195D01*
X791268Y-3042D01*
X791991Y-2659D01*
X792405Y-2199D01*
X792508Y-1662D01*
X792301Y-1049D01*
X791785Y-589D01*
X790855Y-129D01*
G01X788478Y4538D02*
X788685Y3925D01*
X789201Y3465D01*
X789821Y3158D01*
X790648Y2928D01*
X791578Y2851D01*
X792508Y2928D01*
X793335Y3158D01*
X793955Y3465D01*
X794471Y3925D01*
X794678Y4538D01*
X794471Y5151D01*
X793955Y5611D01*
X793335Y5918D01*
X792508Y6148D01*
X791578Y6225D01*
X790648Y6148D01*
X789821Y5918D01*
X789201Y5611D01*
X788685Y5151D01*
X788478Y4538D01*
G01X779345Y12438D02*
Y18638D01*
X781261D01*
X781875Y18328D01*
X782258Y17915D01*
X782411Y17088D01*
X782258Y16261D01*
X781798Y15745D01*
X781261Y15435D01*
X779345D01*
G01X781261D02*
X782411Y12438D01*
G01X787078D02*
X787615Y12541D01*
X788228Y12851D01*
X788611Y13368D01*
X788765Y14091D01*
X788611Y14815D01*
X788151Y15435D01*
X787461Y15745D01*
X786695D01*
X786235Y15951D01*
X785851Y16468D01*
X785698Y17191D01*
X785928Y17915D01*
X786465Y18431D01*
X787078Y18638D01*
X787691Y18431D01*
X788228Y17915D01*
X788458Y17191D01*
X788305Y16468D01*
X787921Y15951D01*
X787461Y15745D01*
X786695D01*
X786005Y15435D01*
X785545Y14815D01*
X785391Y14091D01*
X785545Y13368D01*
X785928Y12851D01*
X786541Y12541D01*
X787078Y12438D01*
G01X791975Y13161D02*
X792511Y12645D01*
X793125Y12438D01*
X793738Y12645D01*
X794275Y13264D01*
X794658Y14195D01*
X794811Y15125D01*
Y16261D01*
X794658Y17191D01*
X794275Y18018D01*
X793815Y18431D01*
X793278Y18638D01*
X792665Y18431D01*
X792205Y18018D01*
X791898Y17398D01*
X791745Y16571D01*
X791898Y15848D01*
X792281Y15125D01*
X792741Y14711D01*
X793278Y14608D01*
X793891Y14815D01*
X794351Y15331D01*
X794811Y16261D01*
G01X789995Y59025D02*
X789685Y58565D01*
X789478Y58028D01*
Y57415D01*
X789788Y56725D01*
X790305Y56188D01*
X790925Y55805D01*
X791958Y55498D01*
X792888Y55421D01*
X793818Y55575D01*
X794438Y55805D01*
X795058Y56265D01*
X795471Y56801D01*
X795678Y57338D01*
Y57875D01*
X795471Y58411D01*
X795161Y58871D01*
X794748Y59255D01*
G01X795678Y63385D02*
X794335Y63538D01*
X793198Y63768D01*
X792165Y64075D01*
X791028Y64458D01*
X789478Y65071D01*
Y62005D01*
G01X795678Y69738D02*
X789478D01*
X790718Y68818D01*
G01X795678D02*
Y70658D01*
G01X784678Y57881D02*
X778478D01*
Y60795D01*
G01X781475Y59721D02*
Y57881D01*
G01X778478Y63851D02*
X782921D01*
X783852Y64158D01*
X784471Y64771D01*
X784678Y65538D01*
X784471Y66305D01*
X783852Y66918D01*
X782921Y67225D01*
X778478D01*
G01X783438Y70051D02*
X784161Y70511D01*
X784575Y71125D01*
X784678Y71815D01*
X784575Y72428D01*
X784058Y73041D01*
X783438Y73425D01*
X782818Y73501D01*
X782095Y73348D01*
X781578Y72811D01*
X781371Y72275D01*
Y71585D01*
G01Y72275D02*
X781061Y72735D01*
X780545Y73118D01*
X779925Y73271D01*
X779305Y73118D01*
X778788Y72735D01*
X778478Y72045D01*
X778581Y71355D01*
X778995Y70665D01*
G01X789995Y85425D02*
X789685Y84965D01*
X789478Y84428D01*
Y83815D01*
X789788Y83125D01*
X790305Y82588D01*
X790925Y82205D01*
X791958Y81898D01*
X792888Y81821D01*
X793818Y81975D01*
X794438Y82205D01*
X795058Y82665D01*
X795471Y83201D01*
X795678Y83738D01*
Y84275D01*
X795471Y84811D01*
X795161Y85271D01*
X794748Y85655D01*
G01X795678Y89785D02*
X794335Y89938D01*
X793198Y90168D01*
X792165Y90475D01*
X791028Y90858D01*
X789478Y91471D01*
Y88405D01*
G01Y96138D02*
X789685Y95525D01*
X790201Y95065D01*
X790821Y94758D01*
X791648Y94528D01*
X792578Y94451D01*
X793508Y94528D01*
X794335Y94758D01*
X794955Y95065D01*
X795471Y95525D01*
X795678Y96138D01*
X795471Y96751D01*
X794955Y97211D01*
X794335Y97518D01*
X793508Y97748D01*
X792578Y97825D01*
X791648Y97748D01*
X790821Y97518D01*
X790201Y97211D01*
X789685Y96751D01*
X789478Y96138D01*
G01X783678Y77705D02*
X777478D01*
Y79621D01*
X777788Y80235D01*
X778201Y80618D01*
X779028Y80771D01*
X779855Y80618D01*
X780371Y80158D01*
X780681Y79621D01*
Y77705D01*
G01Y79621D02*
X783678Y80771D01*
G01X782438Y83751D02*
X783161Y84211D01*
X783575Y84825D01*
X783678Y85515D01*
X783575Y86128D01*
X783058Y86741D01*
X782438Y87125D01*
X781818Y87201D01*
X781095Y87048D01*
X780578Y86511D01*
X780371Y85975D01*
Y85285D01*
G01Y85975D02*
X780061Y86435D01*
X779545Y86818D01*
X778925Y86971D01*
X778305Y86818D01*
X777788Y86435D01*
X777478Y85745D01*
X777581Y85055D01*
X777995Y84365D01*
G01X782748Y89951D02*
X783265Y90411D01*
X783575Y90948D01*
X783678Y91638D01*
X783471Y92328D01*
X783058Y92865D01*
X782335Y93248D01*
X781508Y93325D01*
X780681Y93171D01*
X780165Y92788D01*
X779751Y92251D01*
X779648Y91715D01*
X779751Y91178D01*
X780165Y90488D01*
X777478Y90718D01*
Y92788D01*
G01X783678Y97685D02*
X782335Y97838D01*
X781198Y98068D01*
X780165Y98375D01*
X779028Y98758D01*
X777478Y99371D01*
Y96305D01*
G01X806381Y-256975D02*
X806071Y-257435D01*
X805864Y-257972D01*
Y-258585D01*
X806174Y-259275D01*
X806691Y-259812D01*
X807311Y-260195D01*
X808344Y-260502D01*
X809274Y-260579D01*
X810204Y-260425D01*
X810824Y-260195D01*
X811444Y-259735D01*
X811857Y-259199D01*
X812064Y-258662D01*
Y-258125D01*
X811857Y-257589D01*
X811547Y-257129D01*
X811134Y-256745D01*
G01X806897Y-253919D02*
X806277Y-253459D01*
X805967Y-252922D01*
X805864Y-252309D01*
X806071Y-251542D01*
X806587Y-251005D01*
X807207Y-250852D01*
X807827Y-250929D01*
X808344Y-251235D01*
X809377Y-252769D01*
X810101Y-253459D01*
X811134Y-253919D01*
X812064Y-254072D01*
Y-250852D01*
G01Y-246415D02*
X810721Y-246262D01*
X809584Y-246032D01*
X808551Y-245725D01*
X807414Y-245342D01*
X805864Y-244729D01*
Y-247795D01*
G01X809478Y68651D02*
X813921D01*
X814852Y68958D01*
X815471Y69571D01*
X815678Y70338D01*
X815471Y71105D01*
X814852Y71718D01*
X813921Y72025D01*
X809478D01*
G01X815678Y76538D02*
X809478D01*
X810718Y75618D01*
G01X815678D02*
Y77458D01*
G01X810511Y81281D02*
X809891Y81741D01*
X809581Y82278D01*
X809478Y82891D01*
X809685Y83658D01*
X810201Y84195D01*
X810821Y84348D01*
X811441Y84271D01*
X811958Y83965D01*
X812991Y82431D01*
X813715Y81741D01*
X814748Y81281D01*
X815678Y81128D01*
Y84348D01*
G01X801891Y91468D02*
X802351Y90951D01*
X802888Y90641D01*
X803578Y90538D01*
X804268Y90745D01*
X804805Y91158D01*
X805188Y91881D01*
X805265Y92708D01*
X805111Y93535D01*
X804728Y94051D01*
X804191Y94465D01*
X803655Y94568D01*
X803118Y94465D01*
X802428Y94051D01*
X802658Y96738D01*
X804728D01*
G01X808745Y98538D02*
Y104738D01*
X810661D01*
X811275Y104428D01*
X811658Y104015D01*
X811811Y103188D01*
X811658Y102361D01*
X811198Y101845D01*
X810661Y101535D01*
X808745D01*
G01X810661D02*
X811811Y98538D01*
G01X815021Y103705D02*
X815481Y104325D01*
X816018Y104635D01*
X816631Y104738D01*
X817398Y104531D01*
X817935Y104015D01*
X818088Y103395D01*
X818011Y102775D01*
X817705Y102258D01*
X816171Y101225D01*
X815481Y100501D01*
X815021Y99468D01*
X814868Y98538D01*
X818088D01*
G01X821221Y101121D02*
X821758Y101845D01*
X822218Y102258D01*
X822831Y102465D01*
X823368Y102258D01*
X823751Y101845D01*
X824058Y101225D01*
X824135Y100501D01*
X824058Y99881D01*
X823751Y99261D01*
X823291Y98745D01*
X822755Y98538D01*
X822141Y98745D01*
X821605Y99364D01*
X821298Y100295D01*
X821221Y101328D01*
X821375Y102671D01*
X821605Y103395D01*
X821988Y104118D01*
X822525Y104635D01*
X823061Y104738D01*
X823598Y104531D01*
X823981Y104015D01*
G01X828725Y98538D02*
X828878Y99881D01*
X829108Y101018D01*
X829415Y102051D01*
X829798Y103188D01*
X830411Y104738D01*
X827345D01*
G01X816381Y-256975D02*
X816071Y-257435D01*
X815864Y-257972D01*
Y-258585D01*
X816174Y-259275D01*
X816691Y-259812D01*
X817311Y-260195D01*
X818344Y-260502D01*
X819274Y-260579D01*
X820204Y-260425D01*
X820824Y-260195D01*
X821444Y-259735D01*
X821857Y-259199D01*
X822064Y-258662D01*
Y-258125D01*
X821857Y-257589D01*
X821547Y-257129D01*
X821134Y-256745D01*
G01X816897Y-253919D02*
X816277Y-253459D01*
X815967Y-252922D01*
X815864Y-252309D01*
X816071Y-251542D01*
X816587Y-251005D01*
X817207Y-250852D01*
X817827Y-250929D01*
X818344Y-251235D01*
X819377Y-252769D01*
X820101Y-253459D01*
X821134Y-253919D01*
X822064Y-254072D01*
Y-250852D01*
G01X819481Y-247719D02*
X818757Y-247182D01*
X818344Y-246722D01*
X818137Y-246109D01*
X818344Y-245572D01*
X818757Y-245189D01*
X819377Y-244882D01*
X820101Y-244805D01*
X820721Y-244882D01*
X821341Y-245189D01*
X821857Y-245649D01*
X822064Y-246185D01*
X821857Y-246799D01*
X821238Y-247335D01*
X820307Y-247642D01*
X819274Y-247719D01*
X817931Y-247565D01*
X817207Y-247335D01*
X816484Y-246952D01*
X815967Y-246415D01*
X815864Y-245879D01*
X816071Y-245342D01*
X816587Y-244959D01*
G01X821338Y52851D02*
X822061Y53311D01*
X822475Y53925D01*
X822578Y54615D01*
X822475Y55228D01*
X821958Y55841D01*
X821338Y56225D01*
X820718Y56301D01*
X819995Y56148D01*
X819478Y55611D01*
X819271Y55075D01*
Y54385D01*
G01Y55075D02*
X818961Y55535D01*
X818445Y55918D01*
X817825Y56071D01*
X817205Y55918D01*
X816688Y55535D01*
X816378Y54845D01*
X816481Y54155D01*
X816895Y53465D01*
G01X819498Y90538D02*
Y96738D01*
X816661Y92295D01*
X820495D01*
G01X845755Y-256975D02*
X845445Y-257435D01*
X845238Y-257972D01*
Y-258585D01*
X845548Y-259275D01*
X846065Y-259812D01*
X846685Y-260195D01*
X847718Y-260502D01*
X848648Y-260579D01*
X849578Y-260425D01*
X850198Y-260195D01*
X850818Y-259735D01*
X851231Y-259199D01*
X851438Y-258662D01*
Y-258125D01*
X851231Y-257589D01*
X850921Y-257129D01*
X850508Y-256745D01*
G01X846271Y-253919D02*
X845651Y-253459D01*
X845341Y-252922D01*
X845238Y-252309D01*
X845445Y-251542D01*
X845961Y-251005D01*
X846581Y-250852D01*
X847201Y-250929D01*
X847718Y-251235D01*
X848751Y-252769D01*
X849475Y-253459D01*
X850508Y-253919D01*
X851438Y-254072D01*
Y-250852D01*
G01X850508Y-247949D02*
X851025Y-247489D01*
X851335Y-246952D01*
X851438Y-246262D01*
X851231Y-245572D01*
X850818Y-245035D01*
X850095Y-244652D01*
X849268Y-244575D01*
X848441Y-244729D01*
X847925Y-245112D01*
X847511Y-245649D01*
X847408Y-246185D01*
X847511Y-246722D01*
X847925Y-247412D01*
X845238Y-247182D01*
Y-245112D01*
G01X845574Y53805D02*
X839374D01*
Y55721D01*
X839684Y56335D01*
X840097Y56718D01*
X840924Y56871D01*
X841751Y56718D01*
X842267Y56258D01*
X842577Y55721D01*
Y53805D01*
G01Y55721D02*
X845574Y56871D01*
G01X844851Y60235D02*
X845367Y60771D01*
X845574Y61385D01*
X845367Y61998D01*
X844748Y62535D01*
X843817Y62918D01*
X842887Y63071D01*
X841751D01*
X840821Y62918D01*
X839994Y62535D01*
X839581Y62075D01*
X839374Y61538D01*
X839581Y60925D01*
X839994Y60465D01*
X840614Y60158D01*
X841441Y60005D01*
X842164Y60158D01*
X842887Y60541D01*
X843301Y61001D01*
X843404Y61538D01*
X843197Y62151D01*
X842681Y62611D01*
X841751Y63071D01*
G01X844851Y66435D02*
X845367Y66971D01*
X845574Y67585D01*
X845367Y68198D01*
X844748Y68735D01*
X843817Y69118D01*
X842887Y69271D01*
X841751D01*
X840821Y69118D01*
X839994Y68735D01*
X839581Y68275D01*
X839374Y67738D01*
X839581Y67125D01*
X839994Y66665D01*
X840614Y66358D01*
X841441Y66205D01*
X842164Y66358D01*
X842887Y66741D01*
X843301Y67201D01*
X843404Y67738D01*
X843197Y68351D01*
X842681Y68811D01*
X841751Y69271D01*
G01X845674Y72705D02*
X839474D01*
Y74621D01*
X839784Y75235D01*
X840197Y75618D01*
X841024Y75771D01*
X841851Y75618D01*
X842367Y75158D01*
X842677Y74621D01*
Y72705D01*
G01Y74621D02*
X845674Y75771D01*
G01Y80438D02*
X839474D01*
X840714Y79518D01*
G01X845674D02*
Y81358D01*
G01X839474Y86638D02*
X839681Y86025D01*
X840197Y85565D01*
X840817Y85258D01*
X841644Y85028D01*
X842574Y84951D01*
X843504Y85028D01*
X844331Y85258D01*
X844951Y85565D01*
X845467Y86025D01*
X845674Y86638D01*
X845467Y87251D01*
X844951Y87711D01*
X844331Y88018D01*
X843504Y88248D01*
X842574Y88325D01*
X841644Y88248D01*
X840817Y88018D01*
X840197Y87711D01*
X839681Y87251D01*
X839474Y86638D01*
G01Y92838D02*
X839681Y92225D01*
X840197Y91765D01*
X840817Y91458D01*
X841644Y91228D01*
X842574Y91151D01*
X843504Y91228D01*
X844331Y91458D01*
X844951Y91765D01*
X845467Y92225D01*
X845674Y92838D01*
X845467Y93451D01*
X844951Y93911D01*
X844331Y94218D01*
X843504Y94448D01*
X842574Y94525D01*
X841644Y94448D01*
X840817Y94218D01*
X840197Y93911D01*
X839681Y93451D01*
X839474Y92838D01*
G01X829991Y79025D02*
X829681Y78565D01*
X829474Y78028D01*
Y77415D01*
X829784Y76725D01*
X830301Y76188D01*
X830921Y75805D01*
X831954Y75498D01*
X832884Y75421D01*
X833814Y75575D01*
X834434Y75805D01*
X835054Y76265D01*
X835467Y76801D01*
X835674Y77338D01*
Y77875D01*
X835467Y78411D01*
X835157Y78871D01*
X834744Y79255D01*
G01X833091Y82081D02*
X832367Y82618D01*
X831954Y83078D01*
X831747Y83691D01*
X831954Y84228D01*
X832367Y84611D01*
X832987Y84918D01*
X833711Y84995D01*
X834331Y84918D01*
X834951Y84611D01*
X835467Y84151D01*
X835674Y83615D01*
X835467Y83001D01*
X834848Y82465D01*
X833917Y82158D01*
X832884Y82081D01*
X831541Y82235D01*
X830817Y82465D01*
X830094Y82848D01*
X829577Y83385D01*
X829474Y83921D01*
X829681Y84458D01*
X830197Y84841D01*
G01X834951Y88435D02*
X835467Y88971D01*
X835674Y89585D01*
X835467Y90198D01*
X834848Y90735D01*
X833917Y91118D01*
X832987Y91271D01*
X831851D01*
X830921Y91118D01*
X830094Y90735D01*
X829681Y90275D01*
X829474Y89738D01*
X829681Y89125D01*
X830094Y88665D01*
X830714Y88358D01*
X831541Y88205D01*
X832264Y88358D01*
X832987Y88741D01*
X833401Y89201D01*
X833504Y89738D01*
X833297Y90351D01*
X832781Y90811D01*
X831851Y91271D01*
G01X836745Y97538D02*
Y103738D01*
X838661D01*
X839275Y103428D01*
X839658Y103015D01*
X839811Y102188D01*
X839658Y101361D01*
X839198Y100845D01*
X838661Y100535D01*
X836745D01*
G01X838661D02*
X839811Y97538D01*
G01X844478D02*
Y103738D01*
X843558Y102498D01*
G01Y97538D02*
X845398D01*
G01X850678Y103738D02*
X850065Y103531D01*
X849605Y103015D01*
X849298Y102395D01*
X849068Y101568D01*
X848991Y100638D01*
X849068Y99708D01*
X849298Y98881D01*
X849605Y98261D01*
X850065Y97745D01*
X850678Y97538D01*
X851291Y97745D01*
X851751Y98261D01*
X852058Y98881D01*
X852288Y99708D01*
X852365Y100638D01*
X852288Y101568D01*
X852058Y102395D01*
X851751Y103015D01*
X851291Y103531D01*
X850678Y103738D01*
G01X856725Y97538D02*
X856878Y98881D01*
X857108Y100018D01*
X857415Y101051D01*
X857798Y102188D01*
X858411Y103738D01*
X855345D01*
G01X855755Y-256975D02*
X855445Y-257435D01*
X855238Y-257972D01*
Y-258585D01*
X855548Y-259275D01*
X856065Y-259812D01*
X856685Y-260195D01*
X857718Y-260502D01*
X858648Y-260579D01*
X859578Y-260425D01*
X860198Y-260195D01*
X860818Y-259735D01*
X861231Y-259199D01*
X861438Y-258662D01*
Y-258125D01*
X861231Y-257589D01*
X860921Y-257129D01*
X860508Y-256745D01*
G01X856271Y-253919D02*
X855651Y-253459D01*
X855341Y-252922D01*
X855238Y-252309D01*
X855445Y-251542D01*
X855961Y-251005D01*
X856581Y-250852D01*
X857201Y-250929D01*
X857718Y-251235D01*
X858751Y-252769D01*
X859475Y-253459D01*
X860508Y-253919D01*
X861438Y-254072D01*
Y-250852D01*
G01Y-245342D02*
X855238D01*
X859681Y-248179D01*
Y-244345D01*
G01X859474Y66651D02*
X863917D01*
X864848Y66958D01*
X865467Y67571D01*
X865674Y68338D01*
X865467Y69105D01*
X864848Y69718D01*
X863917Y70025D01*
X859474D01*
G01X865674Y74538D02*
X859474D01*
X860714Y73618D01*
G01X865674D02*
Y75458D01*
G01X859474Y80738D02*
X859681Y80125D01*
X860197Y79665D01*
X860817Y79358D01*
X861644Y79128D01*
X862574Y79051D01*
X863504Y79128D01*
X864331Y79358D01*
X864951Y79665D01*
X865467Y80125D01*
X865674Y80738D01*
X865467Y81351D01*
X864951Y81811D01*
X864331Y82118D01*
X863504Y82348D01*
X862574Y82425D01*
X861644Y82348D01*
X860817Y82118D01*
X860197Y81811D01*
X859681Y81351D01*
X859474Y80738D01*
G01X862065Y100221D02*
X861605Y100531D01*
X861068Y100738D01*
X860455D01*
X859765Y100428D01*
X859228Y99911D01*
X858845Y99291D01*
X858538Y98258D01*
X858461Y97328D01*
X858615Y96398D01*
X858845Y95778D01*
X859305Y95158D01*
X859841Y94745D01*
X860378Y94538D01*
X860915D01*
X861451Y94745D01*
X861911Y95055D01*
X862295Y95468D01*
G01X865121Y97121D02*
X865658Y97845D01*
X866118Y98258D01*
X866731Y98465D01*
X867268Y98258D01*
X867651Y97845D01*
X867958Y97225D01*
X868035Y96501D01*
X867958Y95881D01*
X867651Y95261D01*
X867191Y94745D01*
X866655Y94538D01*
X866041Y94745D01*
X865505Y95364D01*
X865198Y96295D01*
X865121Y97328D01*
X865275Y98671D01*
X865505Y99395D01*
X865888Y100118D01*
X866425Y100635D01*
X866961Y100738D01*
X867498Y100531D01*
X867881Y100015D01*
G01X872778Y94538D02*
X873315Y94641D01*
X873928Y94951D01*
X874311Y95468D01*
X874465Y96191D01*
X874311Y96915D01*
X873851Y97535D01*
X873161Y97845D01*
X872395D01*
X871935Y98051D01*
X871551Y98568D01*
X871398Y99291D01*
X871628Y100015D01*
X872165Y100531D01*
X872778Y100738D01*
X873391Y100531D01*
X873928Y100015D01*
X874158Y99291D01*
X874005Y98568D01*
X873621Y98051D01*
X873161Y97845D01*
X872395D01*
X871705Y97535D01*
X871245Y96915D01*
X871091Y96191D01*
X871245Y95468D01*
X871628Y94951D01*
X872241Y94641D01*
X872778Y94538D01*
G01X852957Y86468D02*
X853417Y85951D01*
X853954Y85641D01*
X854644Y85538D01*
X855334Y85745D01*
X855871Y86158D01*
X856254Y86881D01*
X856331Y87708D01*
X856177Y88535D01*
X855794Y89051D01*
X855257Y89465D01*
X854721Y89568D01*
X854184Y89465D01*
X853494Y89051D01*
X853724Y91738D01*
X855794D01*
G01X866388Y85774D02*
Y91974D01*
X863551Y87531D01*
X867385D01*
G01X869369Y-256975D02*
X869059Y-257435D01*
X868852Y-257972D01*
Y-258585D01*
X869162Y-259275D01*
X869679Y-259812D01*
X870299Y-260195D01*
X871332Y-260502D01*
X872262Y-260579D01*
X873192Y-260425D01*
X873812Y-260195D01*
X874432Y-259735D01*
X874845Y-259199D01*
X875052Y-258662D01*
Y-258125D01*
X874845Y-257589D01*
X874535Y-257129D01*
X874122Y-256745D01*
G01X869885Y-253919D02*
X869265Y-253459D01*
X868955Y-252922D01*
X868852Y-252309D01*
X869059Y-251542D01*
X869575Y-251005D01*
X870195Y-250852D01*
X870815Y-250929D01*
X871332Y-251235D01*
X872365Y-252769D01*
X873089Y-253459D01*
X874122Y-253919D01*
X875052Y-254072D01*
Y-250852D01*
G01X873812Y-247949D02*
X874535Y-247489D01*
X874949Y-246875D01*
X875052Y-246185D01*
X874949Y-245572D01*
X874432Y-244959D01*
X873812Y-244575D01*
X873192Y-244499D01*
X872469Y-244652D01*
X871952Y-245189D01*
X871745Y-245725D01*
Y-246415D01*
G01Y-245725D02*
X871435Y-245265D01*
X870919Y-244882D01*
X870299Y-244729D01*
X869679Y-244882D01*
X869162Y-245265D01*
X868852Y-245955D01*
X868955Y-246645D01*
X869369Y-247335D01*
G01X879371Y-256995D02*
X879061Y-257455D01*
X878854Y-257992D01*
Y-258605D01*
X879164Y-259295D01*
X879681Y-259832D01*
X880301Y-260215D01*
X881334Y-260522D01*
X882264Y-260599D01*
X883194Y-260445D01*
X883814Y-260215D01*
X884434Y-259755D01*
X884847Y-259219D01*
X885054Y-258682D01*
Y-258145D01*
X884847Y-257609D01*
X884537Y-257149D01*
X884124Y-256765D01*
G01X885054Y-252482D02*
X878854D01*
X880094Y-253402D01*
G01X885054D02*
Y-251562D01*
G01X884331Y-247585D02*
X884847Y-247049D01*
X885054Y-246435D01*
X884847Y-245822D01*
X884228Y-245285D01*
X883297Y-244902D01*
X882367Y-244749D01*
X881231D01*
X880301Y-244902D01*
X879474Y-245285D01*
X879061Y-245745D01*
X878854Y-246282D01*
X879061Y-246895D01*
X879474Y-247355D01*
X880094Y-247662D01*
X880921Y-247815D01*
X881644Y-247662D01*
X882367Y-247279D01*
X882781Y-246819D01*
X882884Y-246282D01*
X882677Y-245669D01*
X882161Y-245209D01*
X881231Y-244749D01*
G01X867891Y56778D02*
X868351Y56055D01*
X868965Y55641D01*
X869655Y55538D01*
X870268Y55641D01*
X870881Y56158D01*
X871265Y56778D01*
X871341Y57398D01*
X871188Y58121D01*
X870651Y58638D01*
X870115Y58845D01*
X869425D01*
G01X870115D02*
X870575Y59155D01*
X870958Y59671D01*
X871111Y60291D01*
X870958Y60911D01*
X870575Y61428D01*
X869885Y61738D01*
X869195Y61635D01*
X868505Y61221D01*
G01X895316Y-250757D02*
X901516D01*
Y-247691D01*
G01X896349Y-244481D02*
X895729Y-244021D01*
X895419Y-243484D01*
X895316Y-242871D01*
X895523Y-242104D01*
X896039Y-241567D01*
X896659Y-241414D01*
X897279Y-241491D01*
X897796Y-241797D01*
X898829Y-243331D01*
X899553Y-244021D01*
X900586Y-244481D01*
X901516Y-244634D01*
Y-241414D01*
G01Y-236824D02*
X895316D01*
X896556Y-237744D01*
G01X901516D02*
Y-235904D01*
G01X907991Y-254075D02*
X907681Y-254535D01*
X907474Y-255072D01*
Y-255685D01*
X907784Y-256375D01*
X908301Y-256912D01*
X908921Y-257295D01*
X909954Y-257602D01*
X910884Y-257679D01*
X911814Y-257525D01*
X912434Y-257295D01*
X913054Y-256835D01*
X913467Y-256299D01*
X913674Y-255762D01*
Y-255225D01*
X913467Y-254689D01*
X913157Y-254229D01*
X912744Y-253845D01*
G01X908507Y-251019D02*
X907887Y-250559D01*
X907577Y-250022D01*
X907474Y-249409D01*
X907681Y-248642D01*
X908197Y-248105D01*
X908817Y-247952D01*
X909437Y-248029D01*
X909954Y-248335D01*
X910987Y-249869D01*
X911711Y-250559D01*
X912744Y-251019D01*
X913674Y-251172D01*
Y-247952D01*
G01X912951Y-244665D02*
X913467Y-244129D01*
X913674Y-243515D01*
X913467Y-242902D01*
X912848Y-242365D01*
X911917Y-241982D01*
X910987Y-241829D01*
X909851D01*
X908921Y-241982D01*
X908094Y-242365D01*
X907681Y-242825D01*
X907474Y-243362D01*
X907681Y-243975D01*
X908094Y-244435D01*
X908714Y-244742D01*
X909541Y-244895D01*
X910264Y-244742D01*
X910987Y-244359D01*
X911401Y-243899D01*
X911504Y-243362D01*
X911297Y-242749D01*
X910781Y-242289D01*
X909851Y-241829D01*
G01X907474Y-237162D02*
X907681Y-237775D01*
X908197Y-238235D01*
X908817Y-238542D01*
X909644Y-238772D01*
X910574Y-238849D01*
X911504Y-238772D01*
X912331Y-238542D01*
X912951Y-238235D01*
X913467Y-237775D01*
X913674Y-237162D01*
X913467Y-236549D01*
X912951Y-236089D01*
X912331Y-235782D01*
X911504Y-235552D01*
X910574Y-235475D01*
X909644Y-235552D01*
X908817Y-235782D01*
X908197Y-236089D01*
X907681Y-236549D01*
X907474Y-237162D01*
G01X919074Y206105D02*
X912874D01*
Y208021D01*
X913184Y208635D01*
X913597Y209018D01*
X914424Y209171D01*
X915251Y209018D01*
X915767Y208558D01*
X916077Y208021D01*
Y206105D01*
G01Y208021D02*
X919074Y209171D01*
G01Y214758D02*
X912874D01*
X917317Y211921D01*
Y215755D01*
G01X919074Y220038D02*
X912874D01*
X914114Y219118D01*
G01X919074D02*
Y220958D01*
G01X916491Y224781D02*
X915767Y225318D01*
X915354Y225778D01*
X915147Y226391D01*
X915354Y226928D01*
X915767Y227311D01*
X916387Y227618D01*
X917111Y227695D01*
X917731Y227618D01*
X918351Y227311D01*
X918867Y226851D01*
X919074Y226315D01*
X918867Y225701D01*
X918248Y225165D01*
X917317Y224858D01*
X916284Y224781D01*
X914941Y224935D01*
X914217Y225165D01*
X913494Y225548D01*
X912977Y226085D01*
X912874Y226621D01*
X913081Y227158D01*
X913597Y227541D01*
G01X912745Y294438D02*
Y300638D01*
X914661D01*
X915275Y300328D01*
X915658Y299915D01*
X915811Y299088D01*
X915658Y298261D01*
X915198Y297745D01*
X914661Y297435D01*
X912745D01*
G01X914661D02*
X915811Y294438D01*
G01X921398D02*
Y300638D01*
X918561Y296195D01*
X922395D01*
G01X927598Y294438D02*
Y300638D01*
X924761Y296195D01*
X928595D01*
G01X933798Y294438D02*
Y300638D01*
X930961Y296195D01*
X934795D01*
G01X914745Y309438D02*
Y315638D01*
X916661D01*
X917275Y315328D01*
X917658Y314915D01*
X917811Y314088D01*
X917658Y313261D01*
X917198Y312745D01*
X916661Y312435D01*
X914745D01*
G01X916661D02*
X917811Y309438D01*
G01X923398D02*
Y315638D01*
X920561Y311195D01*
X924395D01*
G01X926991Y310368D02*
X927451Y309851D01*
X927988Y309541D01*
X928678Y309438D01*
X929368Y309645D01*
X929905Y310058D01*
X930288Y310781D01*
X930365Y311608D01*
X930211Y312435D01*
X929828Y312951D01*
X929291Y313365D01*
X928755Y313468D01*
X928218Y313365D01*
X927528Y312951D01*
X927758Y315638D01*
X929828D01*
G01X935798Y309438D02*
Y315638D01*
X932961Y311195D01*
X936795D01*
G01X914745Y324470D02*
Y330670D01*
X916661D01*
X917275Y330360D01*
X917658Y329947D01*
X917811Y329120D01*
X917658Y328293D01*
X917198Y327777D01*
X916661Y327467D01*
X914745D01*
G01X916661D02*
X917811Y324470D01*
G01X923398D02*
Y330670D01*
X920561Y326227D01*
X924395D01*
G01X929598Y324470D02*
Y330670D01*
X926761Y326227D01*
X930595D01*
G01X934725Y324470D02*
X934878Y325813D01*
X935108Y326950D01*
X935415Y327983D01*
X935798Y329120D01*
X936411Y330670D01*
X933345D01*
G01X914745Y334470D02*
Y340670D01*
X916661D01*
X917275Y340360D01*
X917658Y339947D01*
X917811Y339120D01*
X917658Y338293D01*
X917198Y337777D01*
X916661Y337467D01*
X914745D01*
G01X916661D02*
X917811Y334470D01*
G01X923398D02*
Y340670D01*
X920561Y336227D01*
X924395D01*
G01X929598Y334470D02*
Y340670D01*
X926761Y336227D01*
X930595D01*
G01X933421Y337053D02*
X933958Y337777D01*
X934418Y338190D01*
X935031Y338397D01*
X935568Y338190D01*
X935951Y337777D01*
X936258Y337157D01*
X936335Y336433D01*
X936258Y335813D01*
X935951Y335193D01*
X935491Y334677D01*
X934955Y334470D01*
X934341Y334677D01*
X933805Y335296D01*
X933498Y336227D01*
X933421Y337260D01*
X933575Y338603D01*
X933805Y339327D01*
X934188Y340050D01*
X934725Y340567D01*
X935261Y340670D01*
X935798Y340463D01*
X936181Y339947D01*
G01X916991Y-254075D02*
X916681Y-254535D01*
X916474Y-255072D01*
Y-255685D01*
X916784Y-256375D01*
X917301Y-256912D01*
X917921Y-257295D01*
X918954Y-257602D01*
X919884Y-257679D01*
X920814Y-257525D01*
X921434Y-257295D01*
X922054Y-256835D01*
X922467Y-256299D01*
X922674Y-255762D01*
Y-255225D01*
X922467Y-254689D01*
X922157Y-254229D01*
X921744Y-253845D01*
G01X917507Y-251019D02*
X916887Y-250559D01*
X916577Y-250022D01*
X916474Y-249409D01*
X916681Y-248642D01*
X917197Y-248105D01*
X917817Y-247952D01*
X918437Y-248029D01*
X918954Y-248335D01*
X919987Y-249869D01*
X920711Y-250559D01*
X921744Y-251019D01*
X922674Y-251172D01*
Y-247952D01*
G01Y-243362D02*
X922571Y-242825D01*
X922261Y-242212D01*
X921744Y-241829D01*
X921021Y-241675D01*
X920297Y-241829D01*
X919677Y-242289D01*
X919367Y-242979D01*
Y-243745D01*
X919161Y-244205D01*
X918644Y-244589D01*
X917921Y-244742D01*
X917197Y-244512D01*
X916681Y-243975D01*
X916474Y-243362D01*
X916681Y-242749D01*
X917197Y-242212D01*
X917921Y-241982D01*
X918644Y-242135D01*
X919161Y-242519D01*
X919367Y-242979D01*
Y-243745D01*
X919677Y-244435D01*
X920297Y-244895D01*
X921021Y-245049D01*
X921744Y-244895D01*
X922261Y-244512D01*
X922571Y-243899D01*
X922674Y-243362D01*
G01X921951Y-238465D02*
X922467Y-237929D01*
X922674Y-237315D01*
X922467Y-236702D01*
X921848Y-236165D01*
X920917Y-235782D01*
X919987Y-235629D01*
X918851D01*
X917921Y-235782D01*
X917094Y-236165D01*
X916681Y-236625D01*
X916474Y-237162D01*
X916681Y-237775D01*
X917094Y-238235D01*
X917714Y-238542D01*
X918541Y-238695D01*
X919264Y-238542D01*
X919987Y-238159D01*
X920401Y-237699D01*
X920504Y-237162D01*
X920297Y-236549D01*
X919781Y-236089D01*
X918851Y-235629D01*
G01X920648Y68044D02*
X922488Y66478D01*
X924558Y65538D01*
X926398D01*
X928238Y66478D01*
X929618Y68044D01*
X930308Y70238D01*
X929848Y72431D01*
X928698Y74311D01*
X926628Y75565D01*
X923868Y76191D01*
X922258Y77444D01*
X921568Y79638D01*
X922028Y81831D01*
X923178Y83398D01*
X924788Y84338D01*
X926398D01*
X928008Y83711D01*
X929388Y82145D01*
G01X948478Y65538D02*
X939278D01*
Y84338D01*
X948478D01*
G01X944798Y75252D02*
X939278D01*
G01X957678Y65538D02*
Y84338D01*
X963428D01*
X965268Y83398D01*
X966418Y82145D01*
X966878Y79638D01*
X966418Y77131D01*
X965038Y75565D01*
X963428Y74624D01*
X957678D01*
G01X963428D02*
X966878Y65538D01*
G01X977918Y84338D02*
X983438D01*
G01X980678D02*
Y65538D01*
G01X977918D02*
X983438D01*
G01X993328D02*
X999078Y84338D01*
X1004828Y65538D01*
G01X1002758Y72118D02*
X995398D01*
G01X1012878Y84338D02*
Y65538D01*
X1022078D01*
G01X1048988D02*
Y84338D01*
X1059568Y65538D01*
Y84338D01*
G01X1072678Y65538D02*
X1070838Y65851D01*
X1069228Y67104D01*
X1067848Y68985D01*
X1066928Y71178D01*
X1066468Y73685D01*
Y76191D01*
X1066928Y78698D01*
X1067848Y80891D01*
X1069228Y82771D01*
X1070838Y84025D01*
X1072678Y84338D01*
X1074518Y84025D01*
X1076128Y82771D01*
X1077508Y80891D01*
X1078428Y78698D01*
X1078888Y76191D01*
Y73685D01*
X1078428Y71178D01*
X1077508Y68985D01*
X1076128Y67104D01*
X1074518Y65851D01*
X1072678Y65538D01*
G01X1091078Y64911D02*
X1090618Y65225D01*
Y65851D01*
X1091078Y66165D01*
X1091538Y65851D01*
Y65225D01*
X1091078Y64911D01*
G01X928074Y206105D02*
X921874D01*
Y208021D01*
X922184Y208635D01*
X922597Y209018D01*
X923424Y209171D01*
X924251Y209018D01*
X924767Y208558D01*
X925077Y208021D01*
Y206105D01*
G01Y208021D02*
X928074Y209171D01*
G01Y214758D02*
X921874D01*
X926317Y211921D01*
Y215755D01*
G01X928074Y220038D02*
X921874D01*
X923114Y219118D01*
G01X928074D02*
Y220958D01*
G01X926834Y224551D02*
X927557Y225011D01*
X927971Y225625D01*
X928074Y226315D01*
X927971Y226928D01*
X927454Y227541D01*
X926834Y227925D01*
X926214Y228001D01*
X925491Y227848D01*
X924974Y227311D01*
X924767Y226775D01*
Y226085D01*
G01Y226775D02*
X924457Y227235D01*
X923941Y227618D01*
X923321Y227771D01*
X922701Y227618D01*
X922184Y227235D01*
X921874Y226545D01*
X921977Y225855D01*
X922391Y225165D01*
G01X937074Y206105D02*
X930874D01*
Y208021D01*
X931184Y208635D01*
X931597Y209018D01*
X932424Y209171D01*
X933251Y209018D01*
X933767Y208558D01*
X934077Y208021D01*
Y206105D01*
G01Y208021D02*
X937074Y209171D01*
G01Y214758D02*
X930874D01*
X935317Y211921D01*
Y215755D01*
G01X930874Y220038D02*
X931081Y219425D01*
X931597Y218965D01*
X932217Y218658D01*
X933044Y218428D01*
X933974Y218351D01*
X934904Y218428D01*
X935731Y218658D01*
X936351Y218965D01*
X936867Y219425D01*
X937074Y220038D01*
X936867Y220651D01*
X936351Y221111D01*
X935731Y221418D01*
X934904Y221648D01*
X933974Y221725D01*
X933044Y221648D01*
X932217Y221418D01*
X931597Y221111D01*
X931081Y220651D01*
X930874Y220038D01*
G01X936351Y224935D02*
X936867Y225471D01*
X937074Y226085D01*
X936867Y226698D01*
X936248Y227235D01*
X935317Y227618D01*
X934387Y227771D01*
X933251D01*
X932321Y227618D01*
X931494Y227235D01*
X931081Y226775D01*
X930874Y226238D01*
X931081Y225625D01*
X931494Y225165D01*
X932114Y224858D01*
X932941Y224705D01*
X933664Y224858D01*
X934387Y225241D01*
X934801Y225701D01*
X934904Y226238D01*
X934697Y226851D01*
X934181Y227311D01*
X933251Y227771D01*
G01X945098Y300338D02*
Y306538D01*
X942261Y302095D01*
X946095D01*
G01X985313Y-318966D02*
X987230Y-312766D01*
X989147Y-318966D01*
G01X988457Y-316796D02*
X986003D01*
G01X993430Y-318966D02*
Y-312766D01*
X992510Y-314006D01*
G01Y-318966D02*
X994350D01*
G01X980758Y-256555D02*
X974558D01*
Y-254639D01*
X974868Y-254025D01*
X975281Y-253642D01*
X976108Y-253489D01*
X976935Y-253642D01*
X977451Y-254102D01*
X977761Y-254639D01*
Y-256555D01*
G01Y-254639D02*
X980758Y-253489D01*
G01X975591Y-250279D02*
X974971Y-249819D01*
X974661Y-249282D01*
X974558Y-248669D01*
X974765Y-247902D01*
X975281Y-247365D01*
X975901Y-247212D01*
X976521Y-247289D01*
X977038Y-247595D01*
X978071Y-249129D01*
X978795Y-249819D01*
X979828Y-250279D01*
X980758Y-250432D01*
Y-247212D01*
G01X979518Y-244309D02*
X980241Y-243849D01*
X980655Y-243235D01*
X980758Y-242545D01*
X980655Y-241932D01*
X980138Y-241319D01*
X979518Y-240935D01*
X978898Y-240859D01*
X978175Y-241012D01*
X977658Y-241549D01*
X977451Y-242085D01*
Y-242775D01*
G01Y-242085D02*
X977141Y-241625D01*
X976625Y-241242D01*
X976005Y-241089D01*
X975385Y-241242D01*
X974868Y-241625D01*
X974558Y-242315D01*
X974661Y-243005D01*
X975075Y-243695D01*
G01X975646Y207705D02*
X969446D01*
Y209621D01*
X969756Y210235D01*
X970169Y210618D01*
X970996Y210771D01*
X971823Y210618D01*
X972339Y210158D01*
X972649Y209621D01*
Y207705D01*
G01Y209621D02*
X975646Y210771D01*
G01Y216358D02*
X969446D01*
X973889Y213521D01*
Y217355D01*
G01X975646Y221638D02*
X975543Y222175D01*
X975233Y222788D01*
X974716Y223171D01*
X973993Y223325D01*
X973269Y223171D01*
X972649Y222711D01*
X972339Y222021D01*
Y221255D01*
X972133Y220795D01*
X971616Y220411D01*
X970893Y220258D01*
X970169Y220488D01*
X969653Y221025D01*
X969446Y221638D01*
X969653Y222251D01*
X970169Y222788D01*
X970893Y223018D01*
X971616Y222865D01*
X972133Y222481D01*
X972339Y222021D01*
Y221255D01*
X972649Y220565D01*
X973269Y220105D01*
X973993Y219951D01*
X974716Y220105D01*
X975233Y220488D01*
X975543Y221101D01*
X975646Y221638D01*
G01Y227838D02*
X975543Y228375D01*
X975233Y228988D01*
X974716Y229371D01*
X973993Y229525D01*
X973269Y229371D01*
X972649Y228911D01*
X972339Y228221D01*
Y227455D01*
X972133Y226995D01*
X971616Y226611D01*
X970893Y226458D01*
X970169Y226688D01*
X969653Y227225D01*
X969446Y227838D01*
X969653Y228451D01*
X970169Y228988D01*
X970893Y229218D01*
X971616Y229065D01*
X972133Y228681D01*
X972339Y228221D01*
Y227455D01*
X972649Y226765D01*
X973269Y226305D01*
X973993Y226151D01*
X974716Y226305D01*
X975233Y226688D01*
X975543Y227301D01*
X975646Y227838D01*
G01X970891Y325338D02*
Y320895D01*
X971198Y319964D01*
X971811Y319345D01*
X972578Y319138D01*
X973345Y319345D01*
X973958Y319964D01*
X974265Y320895D01*
Y325338D01*
G01X977091Y320378D02*
X977551Y319655D01*
X978165Y319241D01*
X978855Y319138D01*
X979468Y319241D01*
X980081Y319758D01*
X980465Y320378D01*
X980541Y320998D01*
X980388Y321721D01*
X979851Y322238D01*
X979315Y322445D01*
X978625D01*
G01X979315D02*
X979775Y322755D01*
X980158Y323271D01*
X980311Y323891D01*
X980158Y324511D01*
X979775Y325028D01*
X979085Y325338D01*
X978395Y325235D01*
X977705Y324821D01*
G01X984978Y319138D02*
Y325338D01*
X984058Y324098D01*
G01Y319138D02*
X985898D01*
G01X974845Y449438D02*
Y455638D01*
X976761D01*
X977375Y455328D01*
X977758Y454915D01*
X977911Y454088D01*
X977758Y453261D01*
X977298Y452745D01*
X976761Y452435D01*
X974845D01*
G01X976761D02*
X977911Y449438D01*
G01X980891Y450678D02*
X981351Y449955D01*
X981965Y449541D01*
X982655Y449438D01*
X983268Y449541D01*
X983881Y450058D01*
X984265Y450678D01*
X984341Y451298D01*
X984188Y452021D01*
X983651Y452538D01*
X983115Y452745D01*
X982425D01*
G01X983115D02*
X983575Y453055D01*
X983958Y453571D01*
X984111Y454191D01*
X983958Y454811D01*
X983575Y455328D01*
X982885Y455638D01*
X982195Y455535D01*
X981505Y455121D01*
G01X987091Y450678D02*
X987551Y449955D01*
X988165Y449541D01*
X988855Y449438D01*
X989468Y449541D01*
X990081Y450058D01*
X990465Y450678D01*
X990541Y451298D01*
X990388Y452021D01*
X989851Y452538D01*
X989315Y452745D01*
X988625D01*
G01X989315D02*
X989775Y453055D01*
X990158Y453571D01*
X990311Y454191D01*
X990158Y454811D01*
X989775Y455328D01*
X989085Y455638D01*
X988395Y455535D01*
X987705Y455121D01*
G01X997065Y411121D02*
X996605Y411431D01*
X996068Y411638D01*
X995455D01*
X994765Y411328D01*
X994228Y410811D01*
X993845Y410191D01*
X993538Y409158D01*
X993461Y408228D01*
X993615Y407298D01*
X993845Y406678D01*
X994305Y406058D01*
X994841Y405645D01*
X995378Y405438D01*
X995915D01*
X996451Y405645D01*
X996911Y405955D01*
X997295Y406368D01*
G01X1002498Y405438D02*
Y411638D01*
X999661Y407195D01*
X1003495D01*
G01X1008698Y405438D02*
Y411638D01*
X1005861Y407195D01*
X1009695D01*
G01X987995Y431025D02*
X987685Y430565D01*
X987478Y430028D01*
Y429415D01*
X987788Y428725D01*
X988305Y428188D01*
X988925Y427805D01*
X989958Y427498D01*
X990888Y427421D01*
X991818Y427575D01*
X992438Y427805D01*
X993058Y428265D01*
X993471Y428801D01*
X993678Y429338D01*
Y429875D01*
X993471Y430411D01*
X993161Y430871D01*
X992748Y431255D01*
G01X993678Y436458D02*
X987478D01*
X991921Y433621D01*
Y437455D01*
G01X992748Y440051D02*
X993265Y440511D01*
X993575Y441048D01*
X993678Y441738D01*
X993471Y442428D01*
X993058Y442965D01*
X992335Y443348D01*
X991508Y443425D01*
X990681Y443271D01*
X990165Y442888D01*
X989751Y442351D01*
X989648Y441815D01*
X989751Y441278D01*
X990165Y440588D01*
X987478Y440818D01*
Y442888D01*
G01X1011691Y302068D02*
X1012151Y301551D01*
X1012688Y301241D01*
X1013378Y301138D01*
X1014068Y301345D01*
X1014605Y301758D01*
X1014988Y302481D01*
X1015065Y303308D01*
X1014911Y304135D01*
X1014528Y304651D01*
X1013991Y305065D01*
X1013455Y305168D01*
X1012918Y305065D01*
X1012228Y304651D01*
X1012458Y307338D01*
X1014528D01*
G01X1013178Y331138D02*
X1013715Y331241D01*
X1014328Y331551D01*
X1014711Y332068D01*
X1014865Y332791D01*
X1014711Y333515D01*
X1014251Y334135D01*
X1013561Y334445D01*
X1012795D01*
X1012335Y334651D01*
X1011951Y335168D01*
X1011798Y335891D01*
X1012028Y336615D01*
X1012565Y337131D01*
X1013178Y337338D01*
X1013791Y337131D01*
X1014328Y336615D01*
X1014558Y335891D01*
X1014405Y335168D01*
X1014021Y334651D01*
X1013561Y334445D01*
X1012795D01*
X1012105Y334135D01*
X1011645Y333515D01*
X1011491Y332791D01*
X1011645Y332068D01*
X1012028Y331551D01*
X1012641Y331241D01*
X1013178Y331138D01*
G01X1013845Y401470D02*
Y407670D01*
X1015761D01*
X1016375Y407360D01*
X1016758Y406947D01*
X1016911Y406120D01*
X1016758Y405293D01*
X1016298Y404777D01*
X1015761Y404467D01*
X1013845D01*
G01X1015761D02*
X1016911Y401470D01*
G01X1019891Y402710D02*
X1020351Y401987D01*
X1020965Y401573D01*
X1021655Y401470D01*
X1022268Y401573D01*
X1022881Y402090D01*
X1023265Y402710D01*
X1023341Y403330D01*
X1023188Y404053D01*
X1022651Y404570D01*
X1022115Y404777D01*
X1021425D01*
G01X1022115D02*
X1022575Y405087D01*
X1022958Y405603D01*
X1023111Y406223D01*
X1022958Y406843D01*
X1022575Y407360D01*
X1021885Y407670D01*
X1021195Y407567D01*
X1020505Y407153D01*
G01X1027778Y401470D02*
Y407670D01*
X1026858Y406430D01*
G01Y401470D02*
X1028698D01*
G01X1016568Y430464D02*
X1017181Y429948D01*
X1017871Y429638D01*
X1018485D01*
X1019098Y429948D01*
X1019558Y430464D01*
X1019788Y431188D01*
X1019635Y431911D01*
X1019251Y432531D01*
X1018561Y432945D01*
X1017641Y433151D01*
X1017105Y433565D01*
X1016875Y434288D01*
X1017028Y435011D01*
X1017411Y435528D01*
X1017948Y435838D01*
X1018485D01*
X1019021Y435631D01*
X1019481Y435115D01*
G01X1022845Y429638D02*
Y435838D01*
X1024685D01*
X1025298Y435528D01*
X1025758Y434805D01*
X1025911Y433978D01*
X1025758Y433151D01*
X1025375Y432531D01*
X1024685Y432221D01*
X1022845D01*
G01X1030578Y429638D02*
Y435838D01*
X1029658Y434598D01*
G01Y429638D02*
X1031498D01*
G01X1021995Y327025D02*
X1021685Y326565D01*
X1021478Y326028D01*
Y325415D01*
X1021788Y324725D01*
X1022305Y324188D01*
X1022925Y323805D01*
X1023958Y323498D01*
X1024888Y323421D01*
X1025818Y323575D01*
X1026438Y323805D01*
X1027058Y324265D01*
X1027471Y324801D01*
X1027678Y325338D01*
Y325875D01*
X1027471Y326411D01*
X1027161Y326871D01*
X1026748Y327255D01*
G01X1027678Y331538D02*
X1027575Y332075D01*
X1027265Y332688D01*
X1026748Y333071D01*
X1026025Y333225D01*
X1025301Y333071D01*
X1024681Y332611D01*
X1024371Y331921D01*
Y331155D01*
X1024165Y330695D01*
X1023648Y330311D01*
X1022925Y330158D01*
X1022201Y330388D01*
X1021685Y330925D01*
X1021478Y331538D01*
X1021685Y332151D01*
X1022201Y332688D01*
X1022925Y332918D01*
X1023648Y332765D01*
X1024165Y332381D01*
X1024371Y331921D01*
Y331155D01*
X1024681Y330465D01*
X1025301Y330005D01*
X1026025Y329851D01*
X1026748Y330005D01*
X1027265Y330388D01*
X1027575Y331001D01*
X1027678Y331538D01*
G01Y337738D02*
X1027575Y338275D01*
X1027265Y338888D01*
X1026748Y339271D01*
X1026025Y339425D01*
X1025301Y339271D01*
X1024681Y338811D01*
X1024371Y338121D01*
Y337355D01*
X1024165Y336895D01*
X1023648Y336511D01*
X1022925Y336358D01*
X1022201Y336588D01*
X1021685Y337125D01*
X1021478Y337738D01*
X1021685Y338351D01*
X1022201Y338888D01*
X1022925Y339118D01*
X1023648Y338965D01*
X1024165Y338581D01*
X1024371Y338121D01*
Y337355D01*
X1024681Y336665D01*
X1025301Y336205D01*
X1026025Y336051D01*
X1026748Y336205D01*
X1027265Y336588D01*
X1027575Y337201D01*
X1027678Y337738D01*
G01X1030645Y379670D02*
Y385870D01*
X1032561D01*
X1033175Y385560D01*
X1033558Y385147D01*
X1033711Y384320D01*
X1033558Y383493D01*
X1033098Y382977D01*
X1032561Y382667D01*
X1030645D01*
G01X1032561D02*
X1033711Y379670D01*
G01X1039298D02*
Y385870D01*
X1036461Y381427D01*
X1040295D01*
G01X1043275Y380393D02*
X1043811Y379877D01*
X1044425Y379670D01*
X1045038Y379877D01*
X1045575Y380496D01*
X1045958Y381427D01*
X1046111Y382357D01*
Y383493D01*
X1045958Y384423D01*
X1045575Y385250D01*
X1045115Y385663D01*
X1044578Y385870D01*
X1043965Y385663D01*
X1043505Y385250D01*
X1043198Y384630D01*
X1043045Y383803D01*
X1043198Y383080D01*
X1043581Y382357D01*
X1044041Y381943D01*
X1044578Y381840D01*
X1045191Y382047D01*
X1045651Y382563D01*
X1046111Y383493D01*
G01X1039745Y224470D02*
Y230670D01*
X1041661D01*
X1042275Y230360D01*
X1042658Y229947D01*
X1042811Y229120D01*
X1042658Y228293D01*
X1042198Y227777D01*
X1041661Y227467D01*
X1039745D01*
G01X1041661D02*
X1042811Y224470D01*
G01X1048398D02*
Y230670D01*
X1045561Y226227D01*
X1049395D01*
G01X1052375Y225193D02*
X1052911Y224677D01*
X1053525Y224470D01*
X1054138Y224677D01*
X1054675Y225296D01*
X1055058Y226227D01*
X1055211Y227157D01*
Y228293D01*
X1055058Y229223D01*
X1054675Y230050D01*
X1054215Y230463D01*
X1053678Y230670D01*
X1053065Y230463D01*
X1052605Y230050D01*
X1052298Y229430D01*
X1052145Y228603D01*
X1052298Y227880D01*
X1052681Y227157D01*
X1053141Y226743D01*
X1053678Y226640D01*
X1054291Y226847D01*
X1054751Y227363D01*
X1055211Y228293D01*
G01X1059878Y224470D02*
Y230670D01*
X1058958Y229430D01*
G01Y224470D02*
X1060798D01*
G01X1048545Y403638D02*
Y409838D01*
X1050461D01*
X1051075Y409528D01*
X1051458Y409115D01*
X1051611Y408288D01*
X1051458Y407461D01*
X1050998Y406945D01*
X1050461Y406635D01*
X1048545D01*
G01X1050461D02*
X1051611Y403638D01*
G01X1056278D02*
Y409838D01*
X1055358Y408598D01*
G01Y403638D02*
X1057198D01*
G01X1063398D02*
Y409838D01*
X1060561Y405395D01*
X1064395D01*
G01X1067221Y408805D02*
X1067681Y409425D01*
X1068218Y409735D01*
X1068831Y409838D01*
X1069598Y409631D01*
X1070135Y409115D01*
X1070288Y408495D01*
X1070211Y407875D01*
X1069905Y407358D01*
X1068371Y406325D01*
X1067681Y405601D01*
X1067221Y404568D01*
X1067068Y403638D01*
X1070288D01*
G01X1053645Y394670D02*
Y400870D01*
X1055561D01*
X1056175Y400560D01*
X1056558Y400147D01*
X1056711Y399320D01*
X1056558Y398493D01*
X1056098Y397977D01*
X1055561Y397667D01*
X1053645D01*
G01X1055561D02*
X1056711Y394670D01*
G01X1062298D02*
Y400870D01*
X1059461Y396427D01*
X1063295D01*
G01X1067425Y394670D02*
X1067578Y396013D01*
X1067808Y397150D01*
X1068115Y398183D01*
X1068498Y399320D01*
X1069111Y400870D01*
X1066045D01*
G01X1051645Y421638D02*
Y427838D01*
X1053561D01*
X1054175Y427528D01*
X1054558Y427115D01*
X1054711Y426288D01*
X1054558Y425461D01*
X1054098Y424945D01*
X1053561Y424635D01*
X1051645D01*
G01X1053561D02*
X1054711Y421638D01*
G01X1057691Y422878D02*
X1058151Y422155D01*
X1058765Y421741D01*
X1059455Y421638D01*
X1060068Y421741D01*
X1060681Y422258D01*
X1061065Y422878D01*
X1061141Y423498D01*
X1060988Y424221D01*
X1060451Y424738D01*
X1059915Y424945D01*
X1059225D01*
G01X1059915D02*
X1060375Y425255D01*
X1060758Y425771D01*
X1060911Y426391D01*
X1060758Y427011D01*
X1060375Y427528D01*
X1059685Y427838D01*
X1058995Y427735D01*
X1058305Y427321D01*
G01X1065578Y427838D02*
X1064965Y427631D01*
X1064505Y427115D01*
X1064198Y426495D01*
X1063968Y425668D01*
X1063891Y424738D01*
X1063968Y423808D01*
X1064198Y422981D01*
X1064505Y422361D01*
X1064965Y421845D01*
X1065578Y421638D01*
X1066191Y421845D01*
X1066651Y422361D01*
X1066958Y422981D01*
X1067188Y423808D01*
X1067265Y424738D01*
X1067188Y425668D01*
X1066958Y426495D01*
X1066651Y427115D01*
X1066191Y427631D01*
X1065578Y427838D01*
G01X1051645Y412638D02*
Y418838D01*
X1053561D01*
X1054175Y418528D01*
X1054558Y418115D01*
X1054711Y417288D01*
X1054558Y416461D01*
X1054098Y415945D01*
X1053561Y415635D01*
X1051645D01*
G01X1053561D02*
X1054711Y412638D01*
G01X1060298D02*
Y418838D01*
X1057461Y414395D01*
X1061295D01*
G01X1065578Y412638D02*
X1066115Y412741D01*
X1066728Y413051D01*
X1067111Y413568D01*
X1067265Y414291D01*
X1067111Y415015D01*
X1066651Y415635D01*
X1065961Y415945D01*
X1065195D01*
X1064735Y416151D01*
X1064351Y416668D01*
X1064198Y417391D01*
X1064428Y418115D01*
X1064965Y418631D01*
X1065578Y418838D01*
X1066191Y418631D01*
X1066728Y418115D01*
X1066958Y417391D01*
X1066805Y416668D01*
X1066421Y416151D01*
X1065961Y415945D01*
X1065195D01*
X1064505Y415635D01*
X1064045Y415015D01*
X1063891Y414291D01*
X1064045Y413568D01*
X1064428Y413051D01*
X1065041Y412741D01*
X1065578Y412638D01*
G01X1053845Y441438D02*
Y447638D01*
X1055761D01*
X1056375Y447328D01*
X1056758Y446915D01*
X1056911Y446088D01*
X1056758Y445261D01*
X1056298Y444745D01*
X1055761Y444435D01*
X1053845D01*
G01X1055761D02*
X1056911Y441438D01*
G01X1059891Y442368D02*
X1060351Y441851D01*
X1060888Y441541D01*
X1061578Y441438D01*
X1062268Y441645D01*
X1062805Y442058D01*
X1063188Y442781D01*
X1063265Y443608D01*
X1063111Y444435D01*
X1062728Y444951D01*
X1062191Y445365D01*
X1061655Y445468D01*
X1061118Y445365D01*
X1060428Y444951D01*
X1060658Y447638D01*
X1062728D01*
G01X1067778D02*
X1067165Y447431D01*
X1066705Y446915D01*
X1066398Y446295D01*
X1066168Y445468D01*
X1066091Y444538D01*
X1066168Y443608D01*
X1066398Y442781D01*
X1066705Y442161D01*
X1067165Y441645D01*
X1067778Y441438D01*
X1068391Y441645D01*
X1068851Y442161D01*
X1069158Y442781D01*
X1069388Y443608D01*
X1069465Y444538D01*
X1069388Y445468D01*
X1069158Y446295D01*
X1068851Y446915D01*
X1068391Y447431D01*
X1067778Y447638D01*
G01X1054865Y436321D02*
X1054405Y436631D01*
X1053868Y436838D01*
X1053255D01*
X1052565Y436528D01*
X1052028Y436011D01*
X1051645Y435391D01*
X1051338Y434358D01*
X1051261Y433428D01*
X1051415Y432498D01*
X1051645Y431878D01*
X1052105Y431258D01*
X1052641Y430845D01*
X1053178Y430638D01*
X1053715D01*
X1054251Y430845D01*
X1054711Y431155D01*
X1055095Y431568D01*
G01X1060298Y430638D02*
Y436838D01*
X1057461Y432395D01*
X1061295D01*
G01X1064121Y435805D02*
X1064581Y436425D01*
X1065118Y436735D01*
X1065731Y436838D01*
X1066498Y436631D01*
X1067035Y436115D01*
X1067188Y435495D01*
X1067111Y434875D01*
X1066805Y434358D01*
X1065271Y433325D01*
X1064581Y432601D01*
X1064121Y431568D01*
X1063968Y430638D01*
X1067188D01*
G01X1051645Y451838D02*
Y458038D01*
X1053561D01*
X1054175Y457728D01*
X1054558Y457315D01*
X1054711Y456488D01*
X1054558Y455661D01*
X1054098Y455145D01*
X1053561Y454835D01*
X1051645D01*
G01X1053561D02*
X1054711Y451838D01*
G01X1057691Y453078D02*
X1058151Y452355D01*
X1058765Y451941D01*
X1059455Y451838D01*
X1060068Y451941D01*
X1060681Y452458D01*
X1061065Y453078D01*
X1061141Y453698D01*
X1060988Y454421D01*
X1060451Y454938D01*
X1059915Y455145D01*
X1059225D01*
G01X1059915D02*
X1060375Y455455D01*
X1060758Y455971D01*
X1060911Y456591D01*
X1060758Y457211D01*
X1060375Y457728D01*
X1059685Y458038D01*
X1058995Y457935D01*
X1058305Y457521D01*
G01X1064121Y457005D02*
X1064581Y457625D01*
X1065118Y457935D01*
X1065731Y458038D01*
X1066498Y457831D01*
X1067035Y457315D01*
X1067188Y456695D01*
X1067111Y456075D01*
X1066805Y455558D01*
X1065271Y454525D01*
X1064581Y453801D01*
X1064121Y452768D01*
X1063968Y451838D01*
X1067188D01*
G01X1073845Y-244962D02*
Y-238762D01*
X1075761D01*
X1076375Y-239072D01*
X1076758Y-239485D01*
X1076911Y-240312D01*
X1076758Y-241139D01*
X1076298Y-241655D01*
X1075761Y-241965D01*
X1073845D01*
G01X1075761D02*
X1076911Y-244962D01*
G01X1081578D02*
Y-238762D01*
X1080658Y-240002D01*
G01Y-244962D02*
X1082498D01*
G01X1087625D02*
X1087778Y-243619D01*
X1088008Y-242482D01*
X1088315Y-241449D01*
X1088698Y-240312D01*
X1089311Y-238762D01*
X1086245D01*
G01X1092291Y-244032D02*
X1092751Y-244549D01*
X1093288Y-244859D01*
X1093978Y-244962D01*
X1094668Y-244755D01*
X1095205Y-244342D01*
X1095588Y-243619D01*
X1095665Y-242792D01*
X1095511Y-241965D01*
X1095128Y-241449D01*
X1094591Y-241035D01*
X1094055Y-240932D01*
X1093518Y-241035D01*
X1092828Y-241449D01*
X1093058Y-238762D01*
X1095128D01*
G01X1073805Y-234962D02*
Y-228762D01*
X1075721D01*
X1076335Y-229072D01*
X1076718Y-229485D01*
X1076871Y-230312D01*
X1076718Y-231139D01*
X1076258Y-231655D01*
X1075721Y-231965D01*
X1073805D01*
G01X1075721D02*
X1076871Y-234962D01*
G01X1081538D02*
Y-228762D01*
X1080618Y-230002D01*
G01Y-234962D02*
X1082458D01*
G01X1087585D02*
X1087738Y-233619D01*
X1087968Y-232482D01*
X1088275Y-231449D01*
X1088658Y-230312D01*
X1089271Y-228762D01*
X1086205D01*
G01X1092481Y-232379D02*
X1093018Y-231655D01*
X1093478Y-231242D01*
X1094091Y-231035D01*
X1094628Y-231242D01*
X1095011Y-231655D01*
X1095318Y-232275D01*
X1095395Y-232999D01*
X1095318Y-233619D01*
X1095011Y-234239D01*
X1094551Y-234755D01*
X1094015Y-234962D01*
X1093401Y-234755D01*
X1092865Y-234136D01*
X1092558Y-233205D01*
X1092481Y-232172D01*
X1092635Y-230829D01*
X1092865Y-230105D01*
X1093248Y-229382D01*
X1093785Y-228865D01*
X1094321Y-228762D01*
X1094858Y-228969D01*
X1095241Y-229485D01*
G01X1073745Y-223898D02*
Y-217698D01*
X1075661D01*
X1076275Y-218008D01*
X1076658Y-218421D01*
X1076811Y-219248D01*
X1076658Y-220075D01*
X1076198Y-220591D01*
X1075661Y-220901D01*
X1073745D01*
G01X1075661D02*
X1076811Y-223898D01*
G01X1081478D02*
Y-217698D01*
X1080558Y-218938D01*
G01Y-223898D02*
X1082398D01*
G01X1085991Y-222968D02*
X1086451Y-223485D01*
X1086988Y-223795D01*
X1087678Y-223898D01*
X1088368Y-223691D01*
X1088905Y-223278D01*
X1089288Y-222555D01*
X1089365Y-221728D01*
X1089211Y-220901D01*
X1088828Y-220385D01*
X1088291Y-219971D01*
X1087755Y-219868D01*
X1087218Y-219971D01*
X1086528Y-220385D01*
X1086758Y-217698D01*
X1088828D01*
G01X1093878Y-223898D02*
X1094415Y-223795D01*
X1095028Y-223485D01*
X1095411Y-222968D01*
X1095565Y-222245D01*
X1095411Y-221521D01*
X1094951Y-220901D01*
X1094261Y-220591D01*
X1093495D01*
X1093035Y-220385D01*
X1092651Y-219868D01*
X1092498Y-219145D01*
X1092728Y-218421D01*
X1093265Y-217905D01*
X1093878Y-217698D01*
X1094491Y-217905D01*
X1095028Y-218421D01*
X1095258Y-219145D01*
X1095105Y-219868D01*
X1094721Y-220385D01*
X1094261Y-220591D01*
X1093495D01*
X1092805Y-220901D01*
X1092345Y-221521D01*
X1092191Y-222245D01*
X1092345Y-222968D01*
X1092728Y-223485D01*
X1093341Y-223795D01*
X1093878Y-223898D01*
G01X1067745Y281502D02*
Y287702D01*
X1069661D01*
X1070275Y287392D01*
X1070658Y286979D01*
X1070811Y286152D01*
X1070658Y285325D01*
X1070198Y284809D01*
X1069661Y284499D01*
X1067745D01*
G01X1069661D02*
X1070811Y281502D01*
G01X1075478D02*
Y287702D01*
X1074558Y286462D01*
G01Y281502D02*
X1076398D01*
G01X1079991Y282742D02*
X1080451Y282019D01*
X1081065Y281605D01*
X1081755Y281502D01*
X1082368Y281605D01*
X1082981Y282122D01*
X1083365Y282742D01*
X1083441Y283362D01*
X1083288Y284085D01*
X1082751Y284602D01*
X1082215Y284809D01*
X1081525D01*
G01X1082215D02*
X1082675Y285119D01*
X1083058Y285635D01*
X1083211Y286255D01*
X1083058Y286875D01*
X1082675Y287392D01*
X1081985Y287702D01*
X1081295Y287599D01*
X1080605Y287185D01*
G01X1086421Y286669D02*
X1086881Y287289D01*
X1087418Y287599D01*
X1088031Y287702D01*
X1088798Y287495D01*
X1089335Y286979D01*
X1089488Y286359D01*
X1089411Y285739D01*
X1089105Y285222D01*
X1087571Y284189D01*
X1086881Y283465D01*
X1086421Y282432D01*
X1086268Y281502D01*
X1089488D01*
G01X1067745Y272502D02*
Y278702D01*
X1069661D01*
X1070275Y278392D01*
X1070658Y277979D01*
X1070811Y277152D01*
X1070658Y276325D01*
X1070198Y275809D01*
X1069661Y275499D01*
X1067745D01*
G01X1069661D02*
X1070811Y272502D01*
G01X1073791Y273742D02*
X1074251Y273019D01*
X1074865Y272605D01*
X1075555Y272502D01*
X1076168Y272605D01*
X1076781Y273122D01*
X1077165Y273742D01*
X1077241Y274362D01*
X1077088Y275085D01*
X1076551Y275602D01*
X1076015Y275809D01*
X1075325D01*
G01X1076015D02*
X1076475Y276119D01*
X1076858Y276635D01*
X1077011Y277255D01*
X1076858Y277875D01*
X1076475Y278392D01*
X1075785Y278702D01*
X1075095Y278599D01*
X1074405Y278185D01*
G01X1082598Y272502D02*
Y278702D01*
X1079761Y274259D01*
X1083595D01*
G01X1086575Y273225D02*
X1087111Y272709D01*
X1087725Y272502D01*
X1088338Y272709D01*
X1088875Y273328D01*
X1089258Y274259D01*
X1089411Y275189D01*
Y276325D01*
X1089258Y277255D01*
X1088875Y278082D01*
X1088415Y278495D01*
X1087878Y278702D01*
X1087265Y278495D01*
X1086805Y278082D01*
X1086498Y277462D01*
X1086345Y276635D01*
X1086498Y275912D01*
X1086881Y275189D01*
X1087341Y274775D01*
X1087878Y274672D01*
X1088491Y274879D01*
X1088951Y275395D01*
X1089411Y276325D01*
G01X1075065Y331185D02*
X1074605Y331495D01*
X1074068Y331702D01*
X1073455D01*
X1072765Y331392D01*
X1072228Y330875D01*
X1071845Y330255D01*
X1071538Y329222D01*
X1071461Y328292D01*
X1071615Y327362D01*
X1071845Y326742D01*
X1072305Y326122D01*
X1072841Y325709D01*
X1073378Y325502D01*
X1073915D01*
X1074451Y325709D01*
X1074911Y326019D01*
X1075295Y326432D01*
G01X1078275Y326225D02*
X1078811Y325709D01*
X1079425Y325502D01*
X1080038Y325709D01*
X1080575Y326328D01*
X1080958Y327259D01*
X1081111Y328189D01*
Y329325D01*
X1080958Y330255D01*
X1080575Y331082D01*
X1080115Y331495D01*
X1079578Y331702D01*
X1078965Y331495D01*
X1078505Y331082D01*
X1078198Y330462D01*
X1078045Y329635D01*
X1078198Y328912D01*
X1078581Y328189D01*
X1079041Y327775D01*
X1079578Y327672D01*
X1080191Y327879D01*
X1080651Y328395D01*
X1081111Y329325D01*
G01X1084321Y328085D02*
X1084858Y328809D01*
X1085318Y329222D01*
X1085931Y329429D01*
X1086468Y329222D01*
X1086851Y328809D01*
X1087158Y328189D01*
X1087235Y327465D01*
X1087158Y326845D01*
X1086851Y326225D01*
X1086391Y325709D01*
X1085855Y325502D01*
X1085241Y325709D01*
X1084705Y326328D01*
X1084398Y327259D01*
X1084321Y328292D01*
X1084475Y329635D01*
X1084705Y330359D01*
X1085088Y331082D01*
X1085625Y331599D01*
X1086161Y331702D01*
X1086698Y331495D01*
X1087081Y330979D01*
G01X1071963Y338025D02*
X1071653Y337565D01*
X1071446Y337028D01*
Y336415D01*
X1071756Y335725D01*
X1072273Y335188D01*
X1072893Y334805D01*
X1073926Y334498D01*
X1074856Y334421D01*
X1075786Y334575D01*
X1076406Y334805D01*
X1077026Y335265D01*
X1077439Y335801D01*
X1077646Y336338D01*
Y336875D01*
X1077439Y337411D01*
X1077129Y337871D01*
X1076716Y338255D01*
G01X1076923Y341235D02*
X1077439Y341771D01*
X1077646Y342385D01*
X1077439Y342998D01*
X1076820Y343535D01*
X1075889Y343918D01*
X1074959Y344071D01*
X1073823D01*
X1072893Y343918D01*
X1072066Y343535D01*
X1071653Y343075D01*
X1071446Y342538D01*
X1071653Y341925D01*
X1072066Y341465D01*
X1072686Y341158D01*
X1073513Y341005D01*
X1074236Y341158D01*
X1074959Y341541D01*
X1075373Y342001D01*
X1075476Y342538D01*
X1075269Y343151D01*
X1074753Y343611D01*
X1073823Y344071D01*
G01X1077646Y348738D02*
X1071446D01*
X1072686Y347818D01*
G01X1077646D02*
Y349658D01*
G01X1095714Y243705D02*
X1089514D01*
Y245621D01*
X1089824Y246235D01*
X1090237Y246618D01*
X1091064Y246771D01*
X1091891Y246618D01*
X1092407Y246158D01*
X1092717Y245621D01*
Y243705D01*
G01Y245621D02*
X1095714Y246771D01*
G01Y251438D02*
X1089514D01*
X1090754Y250518D01*
G01X1095714D02*
Y252358D01*
G01X1094474Y255951D02*
X1095197Y256411D01*
X1095611Y257025D01*
X1095714Y257715D01*
X1095611Y258328D01*
X1095094Y258941D01*
X1094474Y259325D01*
X1093854Y259401D01*
X1093131Y259248D01*
X1092614Y258711D01*
X1092407Y258175D01*
Y257485D01*
G01Y258175D02*
X1092097Y258635D01*
X1091581Y259018D01*
X1090961Y259171D01*
X1090341Y259018D01*
X1089824Y258635D01*
X1089514Y257945D01*
X1089617Y257255D01*
X1090031Y256565D01*
G01X1095714Y263838D02*
X1089514D01*
X1090754Y262918D01*
G01X1095714D02*
Y264758D01*
G01X1082446Y333805D02*
X1088646D01*
Y336871D01*
G01X1083479Y340081D02*
X1082859Y340541D01*
X1082549Y341078D01*
X1082446Y341691D01*
X1082653Y342458D01*
X1083169Y342995D01*
X1083789Y343148D01*
X1084409Y343071D01*
X1084926Y342765D01*
X1085959Y341231D01*
X1086683Y340541D01*
X1087716Y340081D01*
X1088646Y339928D01*
Y343148D01*
G01X1083479Y346281D02*
X1082859Y346741D01*
X1082549Y347278D01*
X1082446Y347891D01*
X1082653Y348658D01*
X1083169Y349195D01*
X1083789Y349348D01*
X1084409Y349271D01*
X1084926Y348965D01*
X1085959Y347431D01*
X1086683Y346741D01*
X1087716Y346281D01*
X1088646Y346128D01*
Y349348D01*
G01X1097685Y-244822D02*
Y-238622D01*
X1099601D01*
X1100215Y-238932D01*
X1100598Y-239345D01*
X1100751Y-240172D01*
X1100598Y-240999D01*
X1100138Y-241515D01*
X1099601Y-241825D01*
X1097685D01*
G01X1099601D02*
X1100751Y-244822D01*
G01X1105418D02*
Y-238622D01*
X1104498Y-239862D01*
G01Y-244822D02*
X1106338D01*
G01X1110315Y-244099D02*
X1110851Y-244615D01*
X1111465Y-244822D01*
X1112078Y-244615D01*
X1112615Y-243996D01*
X1112998Y-243065D01*
X1113151Y-242135D01*
Y-240999D01*
X1112998Y-240069D01*
X1112615Y-239242D01*
X1112155Y-238829D01*
X1111618Y-238622D01*
X1111005Y-238829D01*
X1110545Y-239242D01*
X1110238Y-239862D01*
X1110085Y-240689D01*
X1110238Y-241412D01*
X1110621Y-242135D01*
X1111081Y-242549D01*
X1111618Y-242652D01*
X1112231Y-242445D01*
X1112691Y-241929D01*
X1113151Y-240999D01*
G01X1116515Y-244099D02*
X1117051Y-244615D01*
X1117665Y-244822D01*
X1118278Y-244615D01*
X1118815Y-243996D01*
X1119198Y-243065D01*
X1119351Y-242135D01*
Y-240999D01*
X1119198Y-240069D01*
X1118815Y-239242D01*
X1118355Y-238829D01*
X1117818Y-238622D01*
X1117205Y-238829D01*
X1116745Y-239242D01*
X1116438Y-239862D01*
X1116285Y-240689D01*
X1116438Y-241412D01*
X1116821Y-242135D01*
X1117281Y-242549D01*
X1117818Y-242652D01*
X1118431Y-242445D01*
X1118891Y-241929D01*
X1119351Y-240999D01*
G01X1124018Y-244822D02*
Y-238622D01*
X1123098Y-239862D01*
G01Y-244822D02*
X1124938D01*
G01X1107005Y-234842D02*
Y-228642D01*
X1108921D01*
X1109535Y-228952D01*
X1109918Y-229365D01*
X1110071Y-230192D01*
X1109918Y-231019D01*
X1109458Y-231535D01*
X1108921Y-231845D01*
X1107005D01*
G01X1108921D02*
X1110071Y-234842D01*
G01X1114738D02*
Y-228642D01*
X1113818Y-229882D01*
G01Y-234842D02*
X1115658D01*
G01X1111065Y326185D02*
X1110605Y326495D01*
X1110068Y326702D01*
X1109455D01*
X1108765Y326392D01*
X1108228Y325875D01*
X1107845Y325255D01*
X1107538Y324222D01*
X1107461Y323292D01*
X1107615Y322362D01*
X1107845Y321742D01*
X1108305Y321122D01*
X1108841Y320709D01*
X1109378Y320502D01*
X1109915D01*
X1110451Y320709D01*
X1110911Y321019D01*
X1111295Y321432D01*
G01X1114275Y321225D02*
X1114811Y320709D01*
X1115425Y320502D01*
X1116038Y320709D01*
X1116575Y321328D01*
X1116958Y322259D01*
X1117111Y323189D01*
Y324325D01*
X1116958Y325255D01*
X1116575Y326082D01*
X1116115Y326495D01*
X1115578Y326702D01*
X1114965Y326495D01*
X1114505Y326082D01*
X1114198Y325462D01*
X1114045Y324635D01*
X1114198Y323912D01*
X1114581Y323189D01*
X1115041Y322775D01*
X1115578Y322672D01*
X1116191Y322879D01*
X1116651Y323395D01*
X1117111Y324325D01*
G01X1120091Y321432D02*
X1120551Y320915D01*
X1121088Y320605D01*
X1121778Y320502D01*
X1122468Y320709D01*
X1123005Y321122D01*
X1123388Y321845D01*
X1123465Y322672D01*
X1123311Y323499D01*
X1122928Y324015D01*
X1122391Y324429D01*
X1121855Y324532D01*
X1121318Y324429D01*
X1120628Y324015D01*
X1120858Y326702D01*
X1122928D01*
G01X1093963Y335925D02*
X1093653Y335465D01*
X1093446Y334928D01*
Y334315D01*
X1093756Y333625D01*
X1094273Y333088D01*
X1094893Y332705D01*
X1095926Y332398D01*
X1096856Y332321D01*
X1097786Y332475D01*
X1098406Y332705D01*
X1099026Y333165D01*
X1099439Y333701D01*
X1099646Y334238D01*
Y334775D01*
X1099439Y335311D01*
X1099129Y335771D01*
X1098716Y336155D01*
G01X1099646Y340438D02*
X1093446D01*
X1094686Y339518D01*
G01X1099646D02*
Y341358D01*
G01X1093446Y346638D02*
X1093653Y346025D01*
X1094169Y345565D01*
X1094789Y345258D01*
X1095616Y345028D01*
X1096546Y344951D01*
X1097476Y345028D01*
X1098303Y345258D01*
X1098923Y345565D01*
X1099439Y346025D01*
X1099646Y346638D01*
X1099439Y347251D01*
X1098923Y347711D01*
X1098303Y348018D01*
X1097476Y348248D01*
X1096546Y348325D01*
X1095616Y348248D01*
X1094789Y348018D01*
X1094169Y347711D01*
X1093653Y347251D01*
X1093446Y346638D01*
G01X1099646Y352838D02*
X1093446D01*
X1094686Y351918D01*
G01X1099646D02*
Y353758D01*
G01X1102963Y339025D02*
X1102653Y338565D01*
X1102446Y338028D01*
Y337415D01*
X1102756Y336725D01*
X1103273Y336188D01*
X1103893Y335805D01*
X1104926Y335498D01*
X1105856Y335421D01*
X1106786Y335575D01*
X1107406Y335805D01*
X1108026Y336265D01*
X1108439Y336801D01*
X1108646Y337338D01*
Y337875D01*
X1108439Y338411D01*
X1108129Y338871D01*
X1107716Y339255D01*
G01X1107923Y342235D02*
X1108439Y342771D01*
X1108646Y343385D01*
X1108439Y343998D01*
X1107820Y344535D01*
X1106889Y344918D01*
X1105959Y345071D01*
X1104823D01*
X1103893Y344918D01*
X1103066Y344535D01*
X1102653Y344075D01*
X1102446Y343538D01*
X1102653Y342925D01*
X1103066Y342465D01*
X1103686Y342158D01*
X1104513Y342005D01*
X1105236Y342158D01*
X1105959Y342541D01*
X1106373Y343001D01*
X1106476Y343538D01*
X1106269Y344151D01*
X1105753Y344611D01*
X1104823Y345071D01*
G01X1107923Y348435D02*
X1108439Y348971D01*
X1108646Y349585D01*
X1108439Y350198D01*
X1107820Y350735D01*
X1106889Y351118D01*
X1105959Y351271D01*
X1104823D01*
X1103893Y351118D01*
X1103066Y350735D01*
X1102653Y350275D01*
X1102446Y349738D01*
X1102653Y349125D01*
X1103066Y348665D01*
X1103686Y348358D01*
X1104513Y348205D01*
X1105236Y348358D01*
X1105959Y348741D01*
X1106373Y349201D01*
X1106476Y349738D01*
X1106269Y350351D01*
X1105753Y350811D01*
X1104823Y351271D01*
G01X1121995Y335925D02*
X1121685Y335465D01*
X1121478Y334928D01*
Y334315D01*
X1121788Y333625D01*
X1122305Y333088D01*
X1122925Y332705D01*
X1123958Y332398D01*
X1124888Y332321D01*
X1125818Y332475D01*
X1126438Y332705D01*
X1127058Y333165D01*
X1127471Y333701D01*
X1127678Y334238D01*
Y334775D01*
X1127471Y335311D01*
X1127161Y335771D01*
X1126748Y336155D01*
G01X1127678Y340438D02*
X1121478D01*
X1122718Y339518D01*
G01X1127678D02*
Y341358D01*
G01X1121478Y346638D02*
X1121685Y346025D01*
X1122201Y345565D01*
X1122821Y345258D01*
X1123648Y345028D01*
X1124578Y344951D01*
X1125508Y345028D01*
X1126335Y345258D01*
X1126955Y345565D01*
X1127471Y346025D01*
X1127678Y346638D01*
X1127471Y347251D01*
X1126955Y347711D01*
X1126335Y348018D01*
X1125508Y348248D01*
X1124578Y348325D01*
X1123648Y348248D01*
X1122821Y348018D01*
X1122201Y347711D01*
X1121685Y347251D01*
X1121478Y346638D01*
G01Y352838D02*
X1121685Y352225D01*
X1122201Y351765D01*
X1122821Y351458D01*
X1123648Y351228D01*
X1124578Y351151D01*
X1125508Y351228D01*
X1126335Y351458D01*
X1126955Y351765D01*
X1127471Y352225D01*
X1127678Y352838D01*
X1127471Y353451D01*
X1126955Y353911D01*
X1126335Y354218D01*
X1125508Y354448D01*
X1124578Y354525D01*
X1123648Y354448D01*
X1122821Y354218D01*
X1122201Y353911D01*
X1121685Y353451D01*
X1121478Y352838D01*
G01X1117646Y332705D02*
X1111446D01*
Y334621D01*
X1111756Y335235D01*
X1112169Y335618D01*
X1112996Y335771D01*
X1113823Y335618D01*
X1114339Y335158D01*
X1114649Y334621D01*
Y332705D01*
G01Y334621D02*
X1117646Y335771D01*
G01Y341358D02*
X1111446D01*
X1115889Y338521D01*
Y342355D01*
G01X1115063Y345181D02*
X1114339Y345718D01*
X1113926Y346178D01*
X1113719Y346791D01*
X1113926Y347328D01*
X1114339Y347711D01*
X1114959Y348018D01*
X1115683Y348095D01*
X1116303Y348018D01*
X1116923Y347711D01*
X1117439Y347251D01*
X1117646Y346715D01*
X1117439Y346101D01*
X1116820Y345565D01*
X1115889Y345258D01*
X1114856Y345181D01*
X1113513Y345335D01*
X1112789Y345565D01*
X1112066Y345948D01*
X1111549Y346485D01*
X1111446Y347021D01*
X1111653Y347558D01*
X1112169Y347941D01*
G01X1116406Y351151D02*
X1117129Y351611D01*
X1117543Y352225D01*
X1117646Y352915D01*
X1117543Y353528D01*
X1117026Y354141D01*
X1116406Y354525D01*
X1115786Y354601D01*
X1115063Y354448D01*
X1114546Y353911D01*
X1114339Y353375D01*
Y352685D01*
G01Y353375D02*
X1114029Y353835D01*
X1113513Y354218D01*
X1112893Y354371D01*
X1112273Y354218D01*
X1111756Y353835D01*
X1111446Y353145D01*
X1111549Y352455D01*
X1111963Y351765D01*
G01X1127745Y-232562D02*
Y-226362D01*
X1129661D01*
X1130275Y-226672D01*
X1130658Y-227085D01*
X1130811Y-227912D01*
X1130658Y-228739D01*
X1130198Y-229255D01*
X1129661Y-229565D01*
X1127745D01*
G01X1129661D02*
X1130811Y-232562D01*
G01X1133791Y-231322D02*
X1134251Y-232045D01*
X1134865Y-232459D01*
X1135555Y-232562D01*
X1136168Y-232459D01*
X1136781Y-231942D01*
X1137165Y-231322D01*
X1137241Y-230702D01*
X1137088Y-229979D01*
X1136551Y-229462D01*
X1136015Y-229255D01*
X1135325D01*
G01X1136015D02*
X1136475Y-228945D01*
X1136858Y-228429D01*
X1137011Y-227809D01*
X1136858Y-227189D01*
X1136475Y-226672D01*
X1135785Y-226362D01*
X1135095Y-226465D01*
X1134405Y-226879D01*
G01X1142598Y-232562D02*
Y-226362D01*
X1139761Y-230805D01*
X1143595D01*
G01X1148798Y-232562D02*
Y-226362D01*
X1145961Y-230805D01*
X1149795D01*
G01X1139959Y245025D02*
X1139649Y244565D01*
X1139442Y244028D01*
Y243415D01*
X1139752Y242725D01*
X1140269Y242188D01*
X1140889Y241805D01*
X1141922Y241498D01*
X1142852Y241421D01*
X1143782Y241575D01*
X1144402Y241805D01*
X1145022Y242265D01*
X1145435Y242801D01*
X1145642Y243338D01*
Y243875D01*
X1145435Y244411D01*
X1145125Y244871D01*
X1144712Y245255D01*
G01X1144919Y248235D02*
X1145435Y248771D01*
X1145642Y249385D01*
X1145435Y249998D01*
X1144816Y250535D01*
X1143885Y250918D01*
X1142955Y251071D01*
X1141819D01*
X1140889Y250918D01*
X1140062Y250535D01*
X1139649Y250075D01*
X1139442Y249538D01*
X1139649Y248925D01*
X1140062Y248465D01*
X1140682Y248158D01*
X1141509Y248005D01*
X1142232Y248158D01*
X1142955Y248541D01*
X1143369Y249001D01*
X1143472Y249538D01*
X1143265Y250151D01*
X1142749Y250611D01*
X1141819Y251071D01*
G01X1139442Y255738D02*
X1139649Y255125D01*
X1140165Y254665D01*
X1140785Y254358D01*
X1141612Y254128D01*
X1142542Y254051D01*
X1143472Y254128D01*
X1144299Y254358D01*
X1144919Y254665D01*
X1145435Y255125D01*
X1145642Y255738D01*
X1145435Y256351D01*
X1144919Y256811D01*
X1144299Y257118D01*
X1143472Y257348D01*
X1142542Y257425D01*
X1141612Y257348D01*
X1140785Y257118D01*
X1140165Y256811D01*
X1139649Y256351D01*
X1139442Y255738D01*
G01X1128446Y318905D02*
X1134646D01*
Y321971D01*
G01Y327558D02*
X1128446D01*
X1132889Y324721D01*
Y328555D01*
G01X1144642Y332705D02*
X1138442D01*
Y334621D01*
X1138752Y335235D01*
X1139165Y335618D01*
X1139992Y335771D01*
X1140819Y335618D01*
X1141335Y335158D01*
X1141645Y334621D01*
Y332705D01*
G01Y334621D02*
X1144642Y335771D01*
G01Y341358D02*
X1138442D01*
X1142885Y338521D01*
Y342355D01*
G01X1142059Y345181D02*
X1141335Y345718D01*
X1140922Y346178D01*
X1140715Y346791D01*
X1140922Y347328D01*
X1141335Y347711D01*
X1141955Y348018D01*
X1142679Y348095D01*
X1143299Y348018D01*
X1143919Y347711D01*
X1144435Y347251D01*
X1144642Y346715D01*
X1144435Y346101D01*
X1143816Y345565D01*
X1142885Y345258D01*
X1141852Y345181D01*
X1140509Y345335D01*
X1139785Y345565D01*
X1139062Y345948D01*
X1138545Y346485D01*
X1138442Y347021D01*
X1138649Y347558D01*
X1139165Y347941D01*
G01X1138442Y352838D02*
X1138649Y352225D01*
X1139165Y351765D01*
X1139785Y351458D01*
X1140612Y351228D01*
X1141542Y351151D01*
X1142472Y351228D01*
X1143299Y351458D01*
X1143919Y351765D01*
X1144435Y352225D01*
X1144642Y352838D01*
X1144435Y353451D01*
X1143919Y353911D01*
X1143299Y354218D01*
X1142472Y354448D01*
X1141542Y354525D01*
X1140612Y354448D01*
X1139785Y354218D01*
X1139165Y353911D01*
X1138649Y353451D01*
X1138442Y352838D01*
G01X1129963Y339025D02*
X1129653Y338565D01*
X1129446Y338028D01*
Y337415D01*
X1129756Y336725D01*
X1130273Y336188D01*
X1130893Y335805D01*
X1131926Y335498D01*
X1132856Y335421D01*
X1133786Y335575D01*
X1134406Y335805D01*
X1135026Y336265D01*
X1135439Y336801D01*
X1135646Y337338D01*
Y337875D01*
X1135439Y338411D01*
X1135129Y338871D01*
X1134716Y339255D01*
G01X1134923Y342235D02*
X1135439Y342771D01*
X1135646Y343385D01*
X1135439Y343998D01*
X1134820Y344535D01*
X1133889Y344918D01*
X1132959Y345071D01*
X1131823D01*
X1130893Y344918D01*
X1130066Y344535D01*
X1129653Y344075D01*
X1129446Y343538D01*
X1129653Y342925D01*
X1130066Y342465D01*
X1130686Y342158D01*
X1131513Y342005D01*
X1132236Y342158D01*
X1132959Y342541D01*
X1133373Y343001D01*
X1133476Y343538D01*
X1133269Y344151D01*
X1132753Y344611D01*
X1131823Y345071D01*
G01X1135646Y349738D02*
X1135543Y350275D01*
X1135233Y350888D01*
X1134716Y351271D01*
X1133993Y351425D01*
X1133269Y351271D01*
X1132649Y350811D01*
X1132339Y350121D01*
Y349355D01*
X1132133Y348895D01*
X1131616Y348511D01*
X1130893Y348358D01*
X1130169Y348588D01*
X1129653Y349125D01*
X1129446Y349738D01*
X1129653Y350351D01*
X1130169Y350888D01*
X1130893Y351118D01*
X1131616Y350965D01*
X1132133Y350581D01*
X1132339Y350121D01*
Y349355D01*
X1132649Y348665D01*
X1133269Y348205D01*
X1133993Y348051D01*
X1134716Y348205D01*
X1135233Y348588D01*
X1135543Y349201D01*
X1135646Y349738D01*
G01X1142678Y360805D02*
X1136478D01*
Y362721D01*
X1136788Y363335D01*
X1137201Y363718D01*
X1138028Y363871D01*
X1138855Y363718D01*
X1139371Y363258D01*
X1139681Y362721D01*
Y360805D01*
G01Y362721D02*
X1142678Y363871D01*
G01Y368538D02*
X1136478D01*
X1137718Y367618D01*
G01X1142678D02*
Y369458D01*
G01Y374738D02*
X1142575Y375275D01*
X1142265Y375888D01*
X1141748Y376271D01*
X1141025Y376425D01*
X1140301Y376271D01*
X1139681Y375811D01*
X1139371Y375121D01*
Y374355D01*
X1139165Y373895D01*
X1138648Y373511D01*
X1137925Y373358D01*
X1137201Y373588D01*
X1136685Y374125D01*
X1136478Y374738D01*
X1136685Y375351D01*
X1137201Y375888D01*
X1137925Y376118D01*
X1138648Y375965D01*
X1139165Y375581D01*
X1139371Y375121D01*
Y374355D01*
X1139681Y373665D01*
X1140301Y373205D01*
X1141025Y373051D01*
X1141748Y373205D01*
X1142265Y373588D01*
X1142575Y374201D01*
X1142678Y374738D01*
G01X1153646Y332705D02*
X1147446D01*
Y334621D01*
X1147756Y335235D01*
X1148169Y335618D01*
X1148996Y335771D01*
X1149823Y335618D01*
X1150339Y335158D01*
X1150649Y334621D01*
Y332705D01*
G01Y334621D02*
X1153646Y335771D01*
G01Y340438D02*
X1147446D01*
X1148686Y339518D01*
G01X1153646D02*
Y341358D01*
G01X1152406Y344951D02*
X1153129Y345411D01*
X1153543Y346025D01*
X1153646Y346715D01*
X1153543Y347328D01*
X1153026Y347941D01*
X1152406Y348325D01*
X1151786Y348401D01*
X1151063Y348248D01*
X1150546Y347711D01*
X1150339Y347175D01*
Y346485D01*
G01Y347175D02*
X1150029Y347635D01*
X1149513Y348018D01*
X1148893Y348171D01*
X1148273Y348018D01*
X1147756Y347635D01*
X1147446Y346945D01*
X1147549Y346255D01*
X1147963Y345565D01*
G01X1147446Y352838D02*
X1147653Y352225D01*
X1148169Y351765D01*
X1148789Y351458D01*
X1149616Y351228D01*
X1150546Y351151D01*
X1151476Y351228D01*
X1152303Y351458D01*
X1152923Y351765D01*
X1153439Y352225D01*
X1153646Y352838D01*
X1153439Y353451D01*
X1152923Y353911D01*
X1152303Y354218D01*
X1151476Y354448D01*
X1150546Y354525D01*
X1149616Y354448D01*
X1148789Y354218D01*
X1148169Y353911D01*
X1147653Y353451D01*
X1147446Y352838D01*
G01X1162646Y332705D02*
X1156446D01*
Y334621D01*
X1156756Y335235D01*
X1157169Y335618D01*
X1157996Y335771D01*
X1158823Y335618D01*
X1159339Y335158D01*
X1159649Y334621D01*
Y332705D01*
G01Y334621D02*
X1162646Y335771D01*
G01Y341358D02*
X1156446D01*
X1160889Y338521D01*
Y342355D01*
G01X1160063Y345181D02*
X1159339Y345718D01*
X1158926Y346178D01*
X1158719Y346791D01*
X1158926Y347328D01*
X1159339Y347711D01*
X1159959Y348018D01*
X1160683Y348095D01*
X1161303Y348018D01*
X1161923Y347711D01*
X1162439Y347251D01*
X1162646Y346715D01*
X1162439Y346101D01*
X1161820Y345565D01*
X1160889Y345258D01*
X1159856Y345181D01*
X1158513Y345335D01*
X1157789Y345565D01*
X1157066Y345948D01*
X1156549Y346485D01*
X1156446Y347021D01*
X1156653Y347558D01*
X1157169Y347941D01*
G01X1162646Y352685D02*
X1161303Y352838D01*
X1160166Y353068D01*
X1159133Y353375D01*
X1157996Y353758D01*
X1156446Y354371D01*
Y351305D01*
G01X1169245Y-234562D02*
Y-228362D01*
X1171161D01*
X1171775Y-228672D01*
X1172158Y-229085D01*
X1172311Y-229912D01*
X1172158Y-230739D01*
X1171698Y-231255D01*
X1171161Y-231565D01*
X1169245D01*
G01X1171161D02*
X1172311Y-234562D01*
G01X1175521Y-229395D02*
X1175981Y-228775D01*
X1176518Y-228465D01*
X1177131Y-228362D01*
X1177898Y-228569D01*
X1178435Y-229085D01*
X1178588Y-229705D01*
X1178511Y-230325D01*
X1178205Y-230842D01*
X1176671Y-231875D01*
X1175981Y-232599D01*
X1175521Y-233632D01*
X1175368Y-234562D01*
X1178588D01*
G01X1184098D02*
Y-228362D01*
X1181261Y-232805D01*
X1185095D01*
G01X1175995Y-212475D02*
X1175685Y-212935D01*
X1175478Y-213472D01*
Y-214085D01*
X1175788Y-214775D01*
X1176305Y-215312D01*
X1176925Y-215695D01*
X1177958Y-216002D01*
X1178888Y-216079D01*
X1179818Y-215925D01*
X1180438Y-215695D01*
X1181058Y-215235D01*
X1181471Y-214699D01*
X1181678Y-214162D01*
Y-213625D01*
X1181471Y-213089D01*
X1181161Y-212629D01*
X1180748Y-212245D01*
G01X1181678Y-207962D02*
X1175478D01*
X1176718Y-208882D01*
G01X1181678D02*
Y-207042D01*
G01X1178078Y-199895D02*
X1171878D01*
Y-197979D01*
X1172188Y-197365D01*
X1172601Y-196982D01*
X1173428Y-196829D01*
X1174255Y-196982D01*
X1174771Y-197442D01*
X1175081Y-197979D01*
Y-199895D01*
G01Y-197979D02*
X1178078Y-196829D01*
G01Y-192162D02*
X1171878D01*
X1173118Y-193082D01*
G01X1178078D02*
Y-191242D01*
G01X1177148Y-187649D02*
X1177665Y-187189D01*
X1177975Y-186652D01*
X1178078Y-185962D01*
X1177871Y-185272D01*
X1177458Y-184735D01*
X1176735Y-184352D01*
X1175908Y-184275D01*
X1175081Y-184429D01*
X1174565Y-184812D01*
X1174151Y-185349D01*
X1174048Y-185885D01*
X1174151Y-186422D01*
X1174565Y-187112D01*
X1171878Y-186882D01*
Y-184812D01*
G01X1177355Y-181065D02*
X1177871Y-180529D01*
X1178078Y-179915D01*
X1177871Y-179302D01*
X1177252Y-178765D01*
X1176321Y-178382D01*
X1175391Y-178229D01*
X1174255D01*
X1173325Y-178382D01*
X1172498Y-178765D01*
X1172085Y-179225D01*
X1171878Y-179762D01*
X1172085Y-180375D01*
X1172498Y-180835D01*
X1173118Y-181142D01*
X1173945Y-181295D01*
X1174668Y-181142D01*
X1175391Y-180759D01*
X1175805Y-180299D01*
X1175908Y-179762D01*
X1175701Y-179149D01*
X1175185Y-178689D01*
X1174255Y-178229D01*
G01X1173945Y-66762D02*
Y-60562D01*
X1175861D01*
X1176475Y-60872D01*
X1176858Y-61285D01*
X1177011Y-62112D01*
X1176858Y-62939D01*
X1176398Y-63455D01*
X1175861Y-63765D01*
X1173945D01*
G01X1175861D02*
X1177011Y-66762D01*
G01X1181678D02*
Y-60562D01*
X1180758Y-61802D01*
G01Y-66762D02*
X1182598D01*
G01X1188798D02*
Y-60562D01*
X1185961Y-65005D01*
X1189795D01*
G01X1194078Y-66762D02*
X1194615Y-66659D01*
X1195228Y-66349D01*
X1195611Y-65832D01*
X1195765Y-65109D01*
X1195611Y-64385D01*
X1195151Y-63765D01*
X1194461Y-63455D01*
X1193695D01*
X1193235Y-63249D01*
X1192851Y-62732D01*
X1192698Y-62009D01*
X1192928Y-61285D01*
X1193465Y-60769D01*
X1194078Y-60562D01*
X1194691Y-60769D01*
X1195228Y-61285D01*
X1195458Y-62009D01*
X1195305Y-62732D01*
X1194921Y-63249D01*
X1194461Y-63455D01*
X1193695D01*
X1193005Y-63765D01*
X1192545Y-64385D01*
X1192391Y-65109D01*
X1192545Y-65832D01*
X1192928Y-66349D01*
X1193541Y-66659D01*
X1194078Y-66762D01*
G01X1177845Y-76562D02*
Y-70362D01*
X1179761D01*
X1180375Y-70672D01*
X1180758Y-71085D01*
X1180911Y-71912D01*
X1180758Y-72739D01*
X1180298Y-73255D01*
X1179761Y-73565D01*
X1177845D01*
G01X1179761D02*
X1180911Y-76562D01*
G01X1184121Y-71395D02*
X1184581Y-70775D01*
X1185118Y-70465D01*
X1185731Y-70362D01*
X1186498Y-70569D01*
X1187035Y-71085D01*
X1187188Y-71705D01*
X1187111Y-72325D01*
X1186805Y-72842D01*
X1185271Y-73875D01*
X1184581Y-74599D01*
X1184121Y-75632D01*
X1183968Y-76562D01*
X1187188D01*
G01X1191625D02*
X1191778Y-75219D01*
X1192008Y-74082D01*
X1192315Y-73049D01*
X1192698Y-71912D01*
X1193311Y-70362D01*
X1190245D01*
G01X1177045Y-57762D02*
Y-51562D01*
X1178961D01*
X1179575Y-51872D01*
X1179958Y-52285D01*
X1180111Y-53112D01*
X1179958Y-53939D01*
X1179498Y-54455D01*
X1178961Y-54765D01*
X1177045D01*
G01X1178961D02*
X1180111Y-57762D01*
G01X1183321Y-52595D02*
X1183781Y-51975D01*
X1184318Y-51665D01*
X1184931Y-51562D01*
X1185698Y-51769D01*
X1186235Y-52285D01*
X1186388Y-52905D01*
X1186311Y-53525D01*
X1186005Y-54042D01*
X1184471Y-55075D01*
X1183781Y-55799D01*
X1183321Y-56832D01*
X1183168Y-57762D01*
X1186388D01*
G01X1189521Y-55179D02*
X1190058Y-54455D01*
X1190518Y-54042D01*
X1191131Y-53835D01*
X1191668Y-54042D01*
X1192051Y-54455D01*
X1192358Y-55075D01*
X1192435Y-55799D01*
X1192358Y-56419D01*
X1192051Y-57039D01*
X1191591Y-57555D01*
X1191055Y-57762D01*
X1190441Y-57555D01*
X1189905Y-56936D01*
X1189598Y-56005D01*
X1189521Y-54972D01*
X1189675Y-53629D01*
X1189905Y-52905D01*
X1190288Y-52182D01*
X1190825Y-51665D01*
X1191361Y-51562D01*
X1191898Y-51769D01*
X1192281Y-52285D01*
G01X1173945Y-48762D02*
Y-42562D01*
X1175861D01*
X1176475Y-42872D01*
X1176858Y-43285D01*
X1177011Y-44112D01*
X1176858Y-44939D01*
X1176398Y-45455D01*
X1175861Y-45765D01*
X1173945D01*
G01X1175861D02*
X1177011Y-48762D01*
G01X1181678D02*
Y-42562D01*
X1180758Y-43802D01*
G01Y-48762D02*
X1182598D01*
G01X1188798D02*
Y-42562D01*
X1185961Y-47005D01*
X1189795D01*
G01X1193925Y-48762D02*
X1194078Y-47419D01*
X1194308Y-46282D01*
X1194615Y-45249D01*
X1194998Y-44112D01*
X1195611Y-42562D01*
X1192545D01*
G01X1177045Y-39762D02*
Y-33562D01*
X1178961D01*
X1179575Y-33872D01*
X1179958Y-34285D01*
X1180111Y-35112D01*
X1179958Y-35939D01*
X1179498Y-36455D01*
X1178961Y-36765D01*
X1177045D01*
G01X1178961D02*
X1180111Y-39762D01*
G01X1183091Y-38832D02*
X1183551Y-39349D01*
X1184088Y-39659D01*
X1184778Y-39762D01*
X1185468Y-39555D01*
X1186005Y-39142D01*
X1186388Y-38419D01*
X1186465Y-37592D01*
X1186311Y-36765D01*
X1185928Y-36249D01*
X1185391Y-35835D01*
X1184855Y-35732D01*
X1184318Y-35835D01*
X1183628Y-36249D01*
X1183858Y-33562D01*
X1185928D01*
G01X1190978Y-39762D02*
X1191515Y-39659D01*
X1192128Y-39349D01*
X1192511Y-38832D01*
X1192665Y-38109D01*
X1192511Y-37385D01*
X1192051Y-36765D01*
X1191361Y-36455D01*
X1190595D01*
X1190135Y-36249D01*
X1189751Y-35732D01*
X1189598Y-35009D01*
X1189828Y-34285D01*
X1190365Y-33769D01*
X1190978Y-33562D01*
X1191591Y-33769D01*
X1192128Y-34285D01*
X1192358Y-35009D01*
X1192205Y-35732D01*
X1191821Y-36249D01*
X1191361Y-36455D01*
X1190595D01*
X1189905Y-36765D01*
X1189445Y-37385D01*
X1189291Y-38109D01*
X1189445Y-38832D01*
X1189828Y-39349D01*
X1190441Y-39659D01*
X1190978Y-39762D01*
G01X1174478Y100305D02*
X1168278D01*
Y102221D01*
X1168588Y102835D01*
X1169001Y103218D01*
X1169828Y103371D01*
X1170655Y103218D01*
X1171171Y102758D01*
X1171481Y102221D01*
Y100305D01*
G01Y102221D02*
X1174478Y103371D01*
G01X1173238Y106351D02*
X1173961Y106811D01*
X1174375Y107425D01*
X1174478Y108115D01*
X1174375Y108728D01*
X1173858Y109341D01*
X1173238Y109725D01*
X1172618Y109801D01*
X1171895Y109648D01*
X1171378Y109111D01*
X1171171Y108575D01*
Y107885D01*
G01Y108575D02*
X1170861Y109035D01*
X1170345Y109418D01*
X1169725Y109571D01*
X1169105Y109418D01*
X1168588Y109035D01*
X1168278Y108345D01*
X1168381Y107655D01*
X1168795Y106965D01*
G01X1174478Y114238D02*
X1168278D01*
X1169518Y113318D01*
G01X1174478D02*
Y115158D01*
G01Y121358D02*
X1168278D01*
X1172721Y118521D01*
Y122355D01*
G01X1183678Y100305D02*
X1177478D01*
Y102221D01*
X1177788Y102835D01*
X1178201Y103218D01*
X1179028Y103371D01*
X1179855Y103218D01*
X1180371Y102758D01*
X1180681Y102221D01*
Y100305D01*
G01Y102221D02*
X1183678Y103371D01*
G01X1178511Y106581D02*
X1177891Y107041D01*
X1177581Y107578D01*
X1177478Y108191D01*
X1177685Y108958D01*
X1178201Y109495D01*
X1178821Y109648D01*
X1179441Y109571D01*
X1179958Y109265D01*
X1180991Y107731D01*
X1181715Y107041D01*
X1182748Y106581D01*
X1183678Y106428D01*
Y109648D01*
G01Y114238D02*
X1183575Y114775D01*
X1183265Y115388D01*
X1182748Y115771D01*
X1182025Y115925D01*
X1181301Y115771D01*
X1180681Y115311D01*
X1180371Y114621D01*
Y113855D01*
X1180165Y113395D01*
X1179648Y113011D01*
X1178925Y112858D01*
X1178201Y113088D01*
X1177685Y113625D01*
X1177478Y114238D01*
X1177685Y114851D01*
X1178201Y115388D01*
X1178925Y115618D01*
X1179648Y115465D01*
X1180165Y115081D01*
X1180371Y114621D01*
Y113855D01*
X1180681Y113165D01*
X1181301Y112705D01*
X1182025Y112551D01*
X1182748Y112705D01*
X1183265Y113088D01*
X1183575Y113701D01*
X1183678Y114238D01*
G01Y120438D02*
X1177478D01*
X1178718Y119518D01*
G01X1183678D02*
Y121358D01*
G01X1172078Y180805D02*
X1165878D01*
Y182721D01*
X1166188Y183335D01*
X1166601Y183718D01*
X1167428Y183871D01*
X1168255Y183718D01*
X1168771Y183258D01*
X1169081Y182721D01*
Y180805D01*
G01Y182721D02*
X1172078Y183871D01*
G01X1171355Y187235D02*
X1171871Y187771D01*
X1172078Y188385D01*
X1171871Y188998D01*
X1171252Y189535D01*
X1170321Y189918D01*
X1169391Y190071D01*
X1168255D01*
X1167325Y189918D01*
X1166498Y189535D01*
X1166085Y189075D01*
X1165878Y188538D01*
X1166085Y187925D01*
X1166498Y187465D01*
X1167118Y187158D01*
X1167945Y187005D01*
X1168668Y187158D01*
X1169391Y187541D01*
X1169805Y188001D01*
X1169908Y188538D01*
X1169701Y189151D01*
X1169185Y189611D01*
X1168255Y190071D01*
G01X1172078Y194738D02*
X1165878D01*
X1167118Y193818D01*
G01X1172078D02*
Y195658D01*
G01X1181046Y177705D02*
X1174846D01*
Y179621D01*
X1175156Y180235D01*
X1175569Y180618D01*
X1176396Y180771D01*
X1177223Y180618D01*
X1177739Y180158D01*
X1178049Y179621D01*
Y177705D01*
G01Y179621D02*
X1181046Y180771D01*
G01X1179806Y183751D02*
X1180529Y184211D01*
X1180943Y184825D01*
X1181046Y185515D01*
X1180943Y186128D01*
X1180426Y186741D01*
X1179806Y187125D01*
X1179186Y187201D01*
X1178463Y187048D01*
X1177946Y186511D01*
X1177739Y185975D01*
Y185285D01*
G01Y185975D02*
X1177429Y186435D01*
X1176913Y186818D01*
X1176293Y186971D01*
X1175673Y186818D01*
X1175156Y186435D01*
X1174846Y185745D01*
X1174949Y185055D01*
X1175363Y184365D01*
G01X1181046Y192558D02*
X1174846D01*
X1179289Y189721D01*
Y193555D01*
G01X1179806Y196151D02*
X1180529Y196611D01*
X1180943Y197225D01*
X1181046Y197915D01*
X1180943Y198528D01*
X1180426Y199141D01*
X1179806Y199525D01*
X1179186Y199601D01*
X1178463Y199448D01*
X1177946Y198911D01*
X1177739Y198375D01*
Y197685D01*
G01Y198375D02*
X1177429Y198835D01*
X1176913Y199218D01*
X1176293Y199371D01*
X1175673Y199218D01*
X1175156Y198835D01*
X1174846Y198145D01*
X1174949Y197455D01*
X1175363Y196765D01*
G01X1161745Y315470D02*
Y321670D01*
X1163661D01*
X1164275Y321360D01*
X1164658Y320947D01*
X1164811Y320120D01*
X1164658Y319293D01*
X1164198Y318777D01*
X1163661Y318467D01*
X1161745D01*
G01X1163661D02*
X1164811Y315470D01*
G01X1170398D02*
Y321670D01*
X1167561Y317227D01*
X1171395D01*
G01X1174221Y318053D02*
X1174758Y318777D01*
X1175218Y319190D01*
X1175831Y319397D01*
X1176368Y319190D01*
X1176751Y318777D01*
X1177058Y318157D01*
X1177135Y317433D01*
X1177058Y316813D01*
X1176751Y316193D01*
X1176291Y315677D01*
X1175755Y315470D01*
X1175141Y315677D01*
X1174605Y316296D01*
X1174298Y317227D01*
X1174221Y318260D01*
X1174375Y319603D01*
X1174605Y320327D01*
X1174988Y321050D01*
X1175525Y321567D01*
X1176061Y321670D01*
X1176598Y321463D01*
X1176981Y320947D01*
G01X1180421Y318053D02*
X1180958Y318777D01*
X1181418Y319190D01*
X1182031Y319397D01*
X1182568Y319190D01*
X1182951Y318777D01*
X1183258Y318157D01*
X1183335Y317433D01*
X1183258Y316813D01*
X1182951Y316193D01*
X1182491Y315677D01*
X1181955Y315470D01*
X1181341Y315677D01*
X1180805Y316296D01*
X1180498Y317227D01*
X1180421Y318260D01*
X1180575Y319603D01*
X1180805Y320327D01*
X1181188Y321050D01*
X1181725Y321567D01*
X1182261Y321670D01*
X1182798Y321463D01*
X1183181Y320947D01*
G01X1161745Y306470D02*
Y312670D01*
X1163661D01*
X1164275Y312360D01*
X1164658Y311947D01*
X1164811Y311120D01*
X1164658Y310293D01*
X1164198Y309777D01*
X1163661Y309467D01*
X1161745D01*
G01X1163661D02*
X1164811Y306470D01*
G01X1170398D02*
Y312670D01*
X1167561Y308227D01*
X1171395D01*
G01X1175525Y306470D02*
X1175678Y307813D01*
X1175908Y308950D01*
X1176215Y309983D01*
X1176598Y311120D01*
X1177211Y312670D01*
X1174145D01*
G01X1181878D02*
X1181265Y312463D01*
X1180805Y311947D01*
X1180498Y311327D01*
X1180268Y310500D01*
X1180191Y309570D01*
X1180268Y308640D01*
X1180498Y307813D01*
X1180805Y307193D01*
X1181265Y306677D01*
X1181878Y306470D01*
X1182491Y306677D01*
X1182951Y307193D01*
X1183258Y307813D01*
X1183488Y308640D01*
X1183565Y309570D01*
X1183488Y310500D01*
X1183258Y311327D01*
X1182951Y311947D01*
X1182491Y312463D01*
X1181878Y312670D01*
G01X1176678Y333705D02*
X1170478D01*
Y335621D01*
X1170788Y336235D01*
X1171201Y336618D01*
X1172028Y336771D01*
X1172855Y336618D01*
X1173371Y336158D01*
X1173681Y335621D01*
Y333705D01*
G01Y335621D02*
X1176678Y336771D01*
G01Y342358D02*
X1170478D01*
X1174921Y339521D01*
Y343355D01*
G01X1174095Y346181D02*
X1173371Y346718D01*
X1172958Y347178D01*
X1172751Y347791D01*
X1172958Y348328D01*
X1173371Y348711D01*
X1173991Y349018D01*
X1174715Y349095D01*
X1175335Y349018D01*
X1175955Y348711D01*
X1176471Y348251D01*
X1176678Y347715D01*
X1176471Y347101D01*
X1175852Y346565D01*
X1174921Y346258D01*
X1173888Y346181D01*
X1172545Y346335D01*
X1171821Y346565D01*
X1171098Y346948D01*
X1170581Y347485D01*
X1170478Y348021D01*
X1170685Y348558D01*
X1171201Y348941D01*
G01X1176678Y353838D02*
X1176575Y354375D01*
X1176265Y354988D01*
X1175748Y355371D01*
X1175025Y355525D01*
X1174301Y355371D01*
X1173681Y354911D01*
X1173371Y354221D01*
Y353455D01*
X1173165Y352995D01*
X1172648Y352611D01*
X1171925Y352458D01*
X1171201Y352688D01*
X1170685Y353225D01*
X1170478Y353838D01*
X1170685Y354451D01*
X1171201Y354988D01*
X1171925Y355218D01*
X1172648Y355065D01*
X1173165Y354681D01*
X1173371Y354221D01*
Y353455D01*
X1173681Y352765D01*
X1174301Y352305D01*
X1175025Y352151D01*
X1175748Y352305D01*
X1176265Y352688D01*
X1176575Y353301D01*
X1176678Y353838D01*
G01X1161745Y324470D02*
Y330670D01*
X1163661D01*
X1164275Y330360D01*
X1164658Y329947D01*
X1164811Y329120D01*
X1164658Y328293D01*
X1164198Y327777D01*
X1163661Y327467D01*
X1161745D01*
G01X1163661D02*
X1164811Y324470D01*
G01X1170398D02*
Y330670D01*
X1167561Y326227D01*
X1171395D01*
G01X1174221Y327053D02*
X1174758Y327777D01*
X1175218Y328190D01*
X1175831Y328397D01*
X1176368Y328190D01*
X1176751Y327777D01*
X1177058Y327157D01*
X1177135Y326433D01*
X1177058Y325813D01*
X1176751Y325193D01*
X1176291Y324677D01*
X1175755Y324470D01*
X1175141Y324677D01*
X1174605Y325296D01*
X1174298Y326227D01*
X1174221Y327260D01*
X1174375Y328603D01*
X1174605Y329327D01*
X1174988Y330050D01*
X1175525Y330567D01*
X1176061Y330670D01*
X1176598Y330463D01*
X1176981Y329947D01*
G01X1180575Y325193D02*
X1181111Y324677D01*
X1181725Y324470D01*
X1182338Y324677D01*
X1182875Y325296D01*
X1183258Y326227D01*
X1183411Y327157D01*
Y328293D01*
X1183258Y329223D01*
X1182875Y330050D01*
X1182415Y330463D01*
X1181878Y330670D01*
X1181265Y330463D01*
X1180805Y330050D01*
X1180498Y329430D01*
X1180345Y328603D01*
X1180498Y327880D01*
X1180881Y327157D01*
X1181341Y326743D01*
X1181878Y326640D01*
X1182491Y326847D01*
X1182951Y327363D01*
X1183411Y328293D01*
G01X1180945Y-243562D02*
Y-237362D01*
X1182861D01*
X1183475Y-237672D01*
X1183858Y-238085D01*
X1184011Y-238912D01*
X1183858Y-239739D01*
X1183398Y-240255D01*
X1182861Y-240565D01*
X1180945D01*
G01X1182861D02*
X1184011Y-243562D01*
G01X1186991Y-242322D02*
X1187451Y-243045D01*
X1188065Y-243459D01*
X1188755Y-243562D01*
X1189368Y-243459D01*
X1189981Y-242942D01*
X1190365Y-242322D01*
X1190441Y-241702D01*
X1190288Y-240979D01*
X1189751Y-240462D01*
X1189215Y-240255D01*
X1188525D01*
G01X1189215D02*
X1189675Y-239945D01*
X1190058Y-239429D01*
X1190211Y-238809D01*
X1190058Y-238189D01*
X1189675Y-237672D01*
X1188985Y-237362D01*
X1188295Y-237465D01*
X1187605Y-237879D01*
G01X1194678Y-230095D02*
X1188478D01*
Y-228179D01*
X1188788Y-227565D01*
X1189201Y-227182D01*
X1190028Y-227029D01*
X1190855Y-227182D01*
X1191371Y-227642D01*
X1191681Y-228179D01*
Y-230095D01*
G01Y-228179D02*
X1194678Y-227029D01*
G01X1189511Y-223819D02*
X1188891Y-223359D01*
X1188581Y-222822D01*
X1188478Y-222209D01*
X1188685Y-221442D01*
X1189201Y-220905D01*
X1189821Y-220752D01*
X1190441Y-220829D01*
X1190958Y-221135D01*
X1191991Y-222669D01*
X1192715Y-223359D01*
X1193748Y-223819D01*
X1194678Y-223972D01*
Y-220752D01*
G01Y-198295D02*
X1188478D01*
Y-196379D01*
X1188788Y-195765D01*
X1189201Y-195382D01*
X1190028Y-195229D01*
X1190855Y-195382D01*
X1191371Y-195842D01*
X1191681Y-196379D01*
Y-198295D01*
G01Y-196379D02*
X1194678Y-195229D01*
G01Y-190562D02*
X1188478D01*
X1189718Y-191482D01*
G01X1194678D02*
Y-189642D01*
G01X1192095Y-185819D02*
X1191371Y-185282D01*
X1190958Y-184822D01*
X1190751Y-184209D01*
X1190958Y-183672D01*
X1191371Y-183289D01*
X1191991Y-182982D01*
X1192715Y-182905D01*
X1193335Y-182982D01*
X1193955Y-183289D01*
X1194471Y-183749D01*
X1194678Y-184285D01*
X1194471Y-184899D01*
X1193852Y-185435D01*
X1192921Y-185742D01*
X1191888Y-185819D01*
X1190545Y-185665D01*
X1189821Y-185435D01*
X1189098Y-185052D01*
X1188581Y-184515D01*
X1188478Y-183979D01*
X1188685Y-183442D01*
X1189201Y-183059D01*
G01X1188478Y-178162D02*
X1188685Y-178775D01*
X1189201Y-179235D01*
X1189821Y-179542D01*
X1190648Y-179772D01*
X1191578Y-179849D01*
X1192508Y-179772D01*
X1193335Y-179542D01*
X1193955Y-179235D01*
X1194471Y-178775D01*
X1194678Y-178162D01*
X1194471Y-177549D01*
X1193955Y-177089D01*
X1193335Y-176782D01*
X1192508Y-176552D01*
X1191578Y-176475D01*
X1190648Y-176552D01*
X1189821Y-176782D01*
X1189201Y-177089D01*
X1188685Y-177549D01*
X1188478Y-178162D01*
G01X1186046Y-197895D02*
X1179846D01*
Y-195979D01*
X1180156Y-195365D01*
X1180569Y-194982D01*
X1181396Y-194829D01*
X1182223Y-194982D01*
X1182739Y-195442D01*
X1183049Y-195979D01*
Y-197895D01*
G01Y-195979D02*
X1186046Y-194829D01*
G01Y-190162D02*
X1179846D01*
X1181086Y-191082D01*
G01X1186046D02*
Y-189242D01*
G01X1183463Y-185419D02*
X1182739Y-184882D01*
X1182326Y-184422D01*
X1182119Y-183809D01*
X1182326Y-183272D01*
X1182739Y-182889D01*
X1183359Y-182582D01*
X1184083Y-182505D01*
X1184703Y-182582D01*
X1185323Y-182889D01*
X1185839Y-183349D01*
X1186046Y-183885D01*
X1185839Y-184499D01*
X1185220Y-185035D01*
X1184289Y-185342D01*
X1183256Y-185419D01*
X1181913Y-185265D01*
X1181189Y-185035D01*
X1180466Y-184652D01*
X1179949Y-184115D01*
X1179846Y-183579D01*
X1180053Y-183042D01*
X1180569Y-182659D01*
G01X1186046Y-177762D02*
X1179846D01*
X1181086Y-178682D01*
G01X1186046D02*
Y-176842D01*
G01X1192678Y100305D02*
X1186478D01*
Y102221D01*
X1186788Y102835D01*
X1187201Y103218D01*
X1188028Y103371D01*
X1188855Y103218D01*
X1189371Y102758D01*
X1189681Y102221D01*
Y100305D01*
G01Y102221D02*
X1192678Y103371D01*
G01X1191438Y106351D02*
X1192161Y106811D01*
X1192575Y107425D01*
X1192678Y108115D01*
X1192575Y108728D01*
X1192058Y109341D01*
X1191438Y109725D01*
X1190818Y109801D01*
X1190095Y109648D01*
X1189578Y109111D01*
X1189371Y108575D01*
Y107885D01*
G01Y108575D02*
X1189061Y109035D01*
X1188545Y109418D01*
X1187925Y109571D01*
X1187305Y109418D01*
X1186788Y109035D01*
X1186478Y108345D01*
X1186581Y107655D01*
X1186995Y106965D01*
G01X1192678Y114238D02*
X1186478D01*
X1187718Y113318D01*
G01X1192678D02*
Y115158D01*
G01X1190095Y118981D02*
X1189371Y119518D01*
X1188958Y119978D01*
X1188751Y120591D01*
X1188958Y121128D01*
X1189371Y121511D01*
X1189991Y121818D01*
X1190715Y121895D01*
X1191335Y121818D01*
X1191955Y121511D01*
X1192471Y121051D01*
X1192678Y120515D01*
X1192471Y119901D01*
X1191852Y119365D01*
X1190921Y119058D01*
X1189888Y118981D01*
X1188545Y119135D01*
X1187821Y119365D01*
X1187098Y119748D01*
X1186581Y120285D01*
X1186478Y120821D01*
X1186685Y121358D01*
X1187201Y121741D01*
G01X1195745Y208502D02*
Y214702D01*
X1197661D01*
X1198275Y214392D01*
X1198658Y213979D01*
X1198811Y213152D01*
X1198658Y212325D01*
X1198198Y211809D01*
X1197661Y211499D01*
X1195745D01*
G01X1197661D02*
X1198811Y208502D01*
G01X1201791Y209742D02*
X1202251Y209019D01*
X1202865Y208605D01*
X1203555Y208502D01*
X1204168Y208605D01*
X1204781Y209122D01*
X1205165Y209742D01*
X1205241Y210362D01*
X1205088Y211085D01*
X1204551Y211602D01*
X1204015Y211809D01*
X1203325D01*
G01X1204015D02*
X1204475Y212119D01*
X1204858Y212635D01*
X1205011Y213255D01*
X1204858Y213875D01*
X1204475Y214392D01*
X1203785Y214702D01*
X1203095Y214599D01*
X1202405Y214185D01*
G01X1210598Y208502D02*
Y214702D01*
X1207761Y210259D01*
X1211595D01*
G01X1215878Y214702D02*
X1215265Y214495D01*
X1214805Y213979D01*
X1214498Y213359D01*
X1214268Y212532D01*
X1214191Y211602D01*
X1214268Y210672D01*
X1214498Y209845D01*
X1214805Y209225D01*
X1215265Y208709D01*
X1215878Y208502D01*
X1216491Y208709D01*
X1216951Y209225D01*
X1217258Y209845D01*
X1217488Y210672D01*
X1217565Y211602D01*
X1217488Y212532D01*
X1217258Y213359D01*
X1216951Y213979D01*
X1216491Y214495D01*
X1215878Y214702D01*
G01X1194745Y255470D02*
Y261670D01*
X1196661D01*
X1197275Y261360D01*
X1197658Y260947D01*
X1197811Y260120D01*
X1197658Y259293D01*
X1197198Y258777D01*
X1196661Y258467D01*
X1194745D01*
G01X1196661D02*
X1197811Y255470D01*
G01X1203398D02*
Y261670D01*
X1200561Y257227D01*
X1204395D01*
G01X1208525Y255470D02*
X1208678Y256813D01*
X1208908Y257950D01*
X1209215Y258983D01*
X1209598Y260120D01*
X1210211Y261670D01*
X1207145D01*
G01X1213191Y256710D02*
X1213651Y255987D01*
X1214265Y255573D01*
X1214955Y255470D01*
X1215568Y255573D01*
X1216181Y256090D01*
X1216565Y256710D01*
X1216641Y257330D01*
X1216488Y258053D01*
X1215951Y258570D01*
X1215415Y258777D01*
X1214725D01*
G01X1215415D02*
X1215875Y259087D01*
X1216258Y259603D01*
X1216411Y260223D01*
X1216258Y260843D01*
X1215875Y261360D01*
X1215185Y261670D01*
X1214495Y261567D01*
X1213805Y261153D01*
G01X1194745Y264470D02*
Y270670D01*
X1196661D01*
X1197275Y270360D01*
X1197658Y269947D01*
X1197811Y269120D01*
X1197658Y268293D01*
X1197198Y267777D01*
X1196661Y267467D01*
X1194745D01*
G01X1196661D02*
X1197811Y264470D01*
G01X1203398D02*
Y270670D01*
X1200561Y266227D01*
X1204395D01*
G01X1208525Y264470D02*
X1208678Y265813D01*
X1208908Y266950D01*
X1209215Y267983D01*
X1209598Y269120D01*
X1210211Y270670D01*
X1207145D01*
G01X1213575Y265193D02*
X1214111Y264677D01*
X1214725Y264470D01*
X1215338Y264677D01*
X1215875Y265296D01*
X1216258Y266227D01*
X1216411Y267157D01*
Y268293D01*
X1216258Y269223D01*
X1215875Y270050D01*
X1215415Y270463D01*
X1214878Y270670D01*
X1214265Y270463D01*
X1213805Y270050D01*
X1213498Y269430D01*
X1213345Y268603D01*
X1213498Y267880D01*
X1213881Y267157D01*
X1214341Y266743D01*
X1214878Y266640D01*
X1215491Y266847D01*
X1215951Y267363D01*
X1216411Y268293D01*
G01X1194745Y273470D02*
Y279670D01*
X1196661D01*
X1197275Y279360D01*
X1197658Y278947D01*
X1197811Y278120D01*
X1197658Y277293D01*
X1197198Y276777D01*
X1196661Y276467D01*
X1194745D01*
G01X1196661D02*
X1197811Y273470D01*
G01X1203398D02*
Y279670D01*
X1200561Y275227D01*
X1204395D01*
G01X1208525Y273470D02*
X1208678Y274813D01*
X1208908Y275950D01*
X1209215Y276983D01*
X1209598Y278120D01*
X1210211Y279670D01*
X1207145D01*
G01X1214878Y273470D02*
X1215415Y273573D01*
X1216028Y273883D01*
X1216411Y274400D01*
X1216565Y275123D01*
X1216411Y275847D01*
X1215951Y276467D01*
X1215261Y276777D01*
X1214495D01*
X1214035Y276983D01*
X1213651Y277500D01*
X1213498Y278223D01*
X1213728Y278947D01*
X1214265Y279463D01*
X1214878Y279670D01*
X1215491Y279463D01*
X1216028Y278947D01*
X1216258Y278223D01*
X1216105Y277500D01*
X1215721Y276983D01*
X1215261Y276777D01*
X1214495D01*
X1213805Y276467D01*
X1213345Y275847D01*
X1213191Y275123D01*
X1213345Y274400D01*
X1213728Y273883D01*
X1214341Y273573D01*
X1214878Y273470D01*
G01X1214865Y-247879D02*
X1214405Y-247569D01*
X1213868Y-247362D01*
X1213255D01*
X1212565Y-247672D01*
X1212028Y-248189D01*
X1211645Y-248809D01*
X1211338Y-249842D01*
X1211261Y-250772D01*
X1211415Y-251702D01*
X1211645Y-252322D01*
X1212105Y-252942D01*
X1212641Y-253355D01*
X1213178Y-253562D01*
X1213715D01*
X1214251Y-253355D01*
X1214711Y-253045D01*
X1215095Y-252632D01*
G01X1219378Y-253562D02*
X1219915Y-253459D01*
X1220528Y-253149D01*
X1220911Y-252632D01*
X1221065Y-251909D01*
X1220911Y-251185D01*
X1220451Y-250565D01*
X1219761Y-250255D01*
X1218995D01*
X1218535Y-250049D01*
X1218151Y-249532D01*
X1217998Y-248809D01*
X1218228Y-248085D01*
X1218765Y-247569D01*
X1219378Y-247362D01*
X1219991Y-247569D01*
X1220528Y-248085D01*
X1220758Y-248809D01*
X1220605Y-249532D01*
X1220221Y-250049D01*
X1219761Y-250255D01*
X1218995D01*
X1218305Y-250565D01*
X1217845Y-251185D01*
X1217691Y-251909D01*
X1217845Y-252632D01*
X1218228Y-253149D01*
X1218841Y-253459D01*
X1219378Y-253562D01*
G01X1224121Y-248395D02*
X1224581Y-247775D01*
X1225118Y-247465D01*
X1225731Y-247362D01*
X1226498Y-247569D01*
X1227035Y-248085D01*
X1227188Y-248705D01*
X1227111Y-249325D01*
X1226805Y-249842D01*
X1225271Y-250875D01*
X1224581Y-251599D01*
X1224121Y-252632D01*
X1223968Y-253562D01*
X1227188D01*
G01X1209678Y-217195D02*
X1203478D01*
Y-215279D01*
X1203788Y-214665D01*
X1204201Y-214282D01*
X1205028Y-214129D01*
X1205855Y-214282D01*
X1206371Y-214742D01*
X1206681Y-215279D01*
Y-217195D01*
G01Y-215279D02*
X1209678Y-214129D01*
G01Y-208542D02*
X1203478D01*
X1207921Y-211379D01*
Y-207545D01*
G01X1208748Y-204949D02*
X1209265Y-204489D01*
X1209575Y-203952D01*
X1209678Y-203262D01*
X1209471Y-202572D01*
X1209058Y-202035D01*
X1208335Y-201652D01*
X1207508Y-201575D01*
X1206681Y-201729D01*
X1206165Y-202112D01*
X1205751Y-202649D01*
X1205648Y-203185D01*
X1205751Y-203722D01*
X1206165Y-204412D01*
X1203478Y-204182D01*
Y-202112D01*
G01X1203014Y-197895D02*
X1196814D01*
Y-195979D01*
X1197124Y-195365D01*
X1197537Y-194982D01*
X1198364Y-194829D01*
X1199191Y-194982D01*
X1199707Y-195442D01*
X1200017Y-195979D01*
Y-197895D01*
G01Y-195979D02*
X1203014Y-194829D01*
G01Y-190162D02*
X1196814D01*
X1198054Y-191082D01*
G01X1203014D02*
Y-189242D01*
G01X1200431Y-185419D02*
X1199707Y-184882D01*
X1199294Y-184422D01*
X1199087Y-183809D01*
X1199294Y-183272D01*
X1199707Y-182889D01*
X1200327Y-182582D01*
X1201051Y-182505D01*
X1201671Y-182582D01*
X1202291Y-182889D01*
X1202807Y-183349D01*
X1203014Y-183885D01*
X1202807Y-184499D01*
X1202188Y-185035D01*
X1201257Y-185342D01*
X1200224Y-185419D01*
X1198881Y-185265D01*
X1198157Y-185035D01*
X1197434Y-184652D01*
X1196917Y-184115D01*
X1196814Y-183579D01*
X1197021Y-183042D01*
X1197537Y-182659D01*
G01X1197847Y-179219D02*
X1197227Y-178759D01*
X1196917Y-178222D01*
X1196814Y-177609D01*
X1197021Y-176842D01*
X1197537Y-176305D01*
X1198157Y-176152D01*
X1198777Y-176229D01*
X1199294Y-176535D01*
X1200327Y-178069D01*
X1201051Y-178759D01*
X1202084Y-179219D01*
X1203014Y-179372D01*
Y-176152D01*
G01X1213046Y-197895D02*
X1206846D01*
Y-195979D01*
X1207156Y-195365D01*
X1207569Y-194982D01*
X1208396Y-194829D01*
X1209223Y-194982D01*
X1209739Y-195442D01*
X1210049Y-195979D01*
Y-197895D01*
G01Y-195979D02*
X1213046Y-194829D01*
G01Y-190162D02*
X1206846D01*
X1208086Y-191082D01*
G01X1213046D02*
Y-189242D01*
G01X1210463Y-185419D02*
X1209739Y-184882D01*
X1209326Y-184422D01*
X1209119Y-183809D01*
X1209326Y-183272D01*
X1209739Y-182889D01*
X1210359Y-182582D01*
X1211083Y-182505D01*
X1211703Y-182582D01*
X1212323Y-182889D01*
X1212839Y-183349D01*
X1213046Y-183885D01*
X1212839Y-184499D01*
X1212220Y-185035D01*
X1211289Y-185342D01*
X1210256Y-185419D01*
X1208913Y-185265D01*
X1208189Y-185035D01*
X1207466Y-184652D01*
X1206949Y-184115D01*
X1206846Y-183579D01*
X1207053Y-183042D01*
X1207569Y-182659D01*
G01X1211806Y-179449D02*
X1212529Y-178989D01*
X1212943Y-178375D01*
X1213046Y-177685D01*
X1212943Y-177072D01*
X1212426Y-176459D01*
X1211806Y-176075D01*
X1211186Y-175999D01*
X1210463Y-176152D01*
X1209946Y-176689D01*
X1209739Y-177225D01*
Y-177915D01*
G01Y-177225D02*
X1209429Y-176765D01*
X1208913Y-176382D01*
X1208293Y-176229D01*
X1207673Y-176382D01*
X1207156Y-176765D01*
X1206846Y-177455D01*
X1206949Y-178145D01*
X1207363Y-178835D01*
G01X1203845Y-77562D02*
Y-71362D01*
X1205761D01*
X1206375Y-71672D01*
X1206758Y-72085D01*
X1206911Y-72912D01*
X1206758Y-73739D01*
X1206298Y-74255D01*
X1205761Y-74565D01*
X1203845D01*
G01X1205761D02*
X1206911Y-77562D01*
G01X1209891Y-76632D02*
X1210351Y-77149D01*
X1210888Y-77459D01*
X1211578Y-77562D01*
X1212268Y-77355D01*
X1212805Y-76942D01*
X1213188Y-76219D01*
X1213265Y-75392D01*
X1213111Y-74565D01*
X1212728Y-74049D01*
X1212191Y-73635D01*
X1211655Y-73532D01*
X1211118Y-73635D01*
X1210428Y-74049D01*
X1210658Y-71362D01*
X1212728D01*
G01X1216475Y-76839D02*
X1217011Y-77355D01*
X1217625Y-77562D01*
X1218238Y-77355D01*
X1218775Y-76736D01*
X1219158Y-75805D01*
X1219311Y-74875D01*
Y-73739D01*
X1219158Y-72809D01*
X1218775Y-71982D01*
X1218315Y-71569D01*
X1217778Y-71362D01*
X1217165Y-71569D01*
X1216705Y-71982D01*
X1216398Y-72602D01*
X1216245Y-73429D01*
X1216398Y-74152D01*
X1216781Y-74875D01*
X1217241Y-75289D01*
X1217778Y-75392D01*
X1218391Y-75185D01*
X1218851Y-74669D01*
X1219311Y-73739D01*
G01X1200545Y-67762D02*
Y-61562D01*
X1202461D01*
X1203075Y-61872D01*
X1203458Y-62285D01*
X1203611Y-63112D01*
X1203458Y-63939D01*
X1202998Y-64455D01*
X1202461Y-64765D01*
X1200545D01*
G01X1202461D02*
X1203611Y-67762D01*
G01X1208278D02*
Y-61562D01*
X1207358Y-62802D01*
G01Y-67762D02*
X1209198D01*
G01X1215398D02*
Y-61562D01*
X1212561Y-66005D01*
X1216395D01*
G01X1218991Y-66832D02*
X1219451Y-67349D01*
X1219988Y-67659D01*
X1220678Y-67762D01*
X1221368Y-67555D01*
X1221905Y-67142D01*
X1222288Y-66419D01*
X1222365Y-65592D01*
X1222211Y-64765D01*
X1221828Y-64249D01*
X1221291Y-63835D01*
X1220755Y-63732D01*
X1220218Y-63835D01*
X1219528Y-64249D01*
X1219758Y-61562D01*
X1221828D01*
G01X1200345Y-56762D02*
Y-50562D01*
X1202261D01*
X1202875Y-50872D01*
X1203258Y-51285D01*
X1203411Y-52112D01*
X1203258Y-52939D01*
X1202798Y-53455D01*
X1202261Y-53765D01*
X1200345D01*
G01X1202261D02*
X1203411Y-56762D01*
G01X1208078D02*
Y-50562D01*
X1207158Y-51802D01*
G01Y-56762D02*
X1208998D01*
G01X1215198D02*
Y-50562D01*
X1212361Y-55005D01*
X1216195D01*
G01X1221398Y-56762D02*
Y-50562D01*
X1218561Y-55005D01*
X1222395D01*
G01X1201678Y100305D02*
X1195478D01*
Y102221D01*
X1195788Y102835D01*
X1196201Y103218D01*
X1197028Y103371D01*
X1197855Y103218D01*
X1198371Y102758D01*
X1198681Y102221D01*
Y100305D01*
G01Y102221D02*
X1201678Y103371D01*
G01X1200438Y106351D02*
X1201161Y106811D01*
X1201575Y107425D01*
X1201678Y108115D01*
X1201575Y108728D01*
X1201058Y109341D01*
X1200438Y109725D01*
X1199818Y109801D01*
X1199095Y109648D01*
X1198578Y109111D01*
X1198371Y108575D01*
Y107885D01*
G01Y108575D02*
X1198061Y109035D01*
X1197545Y109418D01*
X1196925Y109571D01*
X1196305Y109418D01*
X1195788Y109035D01*
X1195478Y108345D01*
X1195581Y107655D01*
X1195995Y106965D01*
G01X1201678Y114238D02*
X1195478D01*
X1196718Y113318D01*
G01X1201678D02*
Y115158D01*
G01X1200748Y118751D02*
X1201265Y119211D01*
X1201575Y119748D01*
X1201678Y120438D01*
X1201471Y121128D01*
X1201058Y121665D01*
X1200335Y122048D01*
X1199508Y122125D01*
X1198681Y121971D01*
X1198165Y121588D01*
X1197751Y121051D01*
X1197648Y120515D01*
X1197751Y119978D01*
X1198165Y119288D01*
X1195478Y119518D01*
Y121588D01*
G01X1210678Y100305D02*
X1204478D01*
Y102221D01*
X1204788Y102835D01*
X1205201Y103218D01*
X1206028Y103371D01*
X1206855Y103218D01*
X1207371Y102758D01*
X1207681Y102221D01*
Y100305D01*
G01Y102221D02*
X1210678Y103371D01*
G01X1205511Y106581D02*
X1204891Y107041D01*
X1204581Y107578D01*
X1204478Y108191D01*
X1204685Y108958D01*
X1205201Y109495D01*
X1205821Y109648D01*
X1206441Y109571D01*
X1206958Y109265D01*
X1207991Y107731D01*
X1208715Y107041D01*
X1209748Y106581D01*
X1210678Y106428D01*
Y109648D01*
G01Y114238D02*
X1210575Y114775D01*
X1210265Y115388D01*
X1209748Y115771D01*
X1209025Y115925D01*
X1208301Y115771D01*
X1207681Y115311D01*
X1207371Y114621D01*
Y113855D01*
X1207165Y113395D01*
X1206648Y113011D01*
X1205925Y112858D01*
X1205201Y113088D01*
X1204685Y113625D01*
X1204478Y114238D01*
X1204685Y114851D01*
X1205201Y115388D01*
X1205925Y115618D01*
X1206648Y115465D01*
X1207165Y115081D01*
X1207371Y114621D01*
Y113855D01*
X1207681Y113165D01*
X1208301Y112705D01*
X1209025Y112551D01*
X1209748Y112705D01*
X1210265Y113088D01*
X1210575Y113701D01*
X1210678Y114238D01*
G01X1205511Y118981D02*
X1204891Y119441D01*
X1204581Y119978D01*
X1204478Y120591D01*
X1204685Y121358D01*
X1205201Y121895D01*
X1205821Y122048D01*
X1206441Y121971D01*
X1206958Y121665D01*
X1207991Y120131D01*
X1208715Y119441D01*
X1209748Y118981D01*
X1210678Y118828D01*
Y122048D01*
G01X1206963Y303025D02*
X1206653Y302565D01*
X1206446Y302028D01*
Y301415D01*
X1206756Y300725D01*
X1207273Y300188D01*
X1207893Y299805D01*
X1208926Y299498D01*
X1209856Y299421D01*
X1210786Y299575D01*
X1211406Y299805D01*
X1212026Y300265D01*
X1212439Y300801D01*
X1212646Y301338D01*
Y301875D01*
X1212439Y302411D01*
X1212129Y302871D01*
X1211716Y303255D01*
G01X1211923Y306235D02*
X1212439Y306771D01*
X1212646Y307385D01*
X1212439Y307998D01*
X1211820Y308535D01*
X1210889Y308918D01*
X1209959Y309071D01*
X1208823D01*
X1207893Y308918D01*
X1207066Y308535D01*
X1206653Y308075D01*
X1206446Y307538D01*
X1206653Y306925D01*
X1207066Y306465D01*
X1207686Y306158D01*
X1208513Y306005D01*
X1209236Y306158D01*
X1209959Y306541D01*
X1210373Y307001D01*
X1210476Y307538D01*
X1210269Y308151D01*
X1209753Y308611D01*
X1208823Y309071D01*
G01X1212646Y314658D02*
X1206446D01*
X1210889Y311821D01*
Y315655D01*
G01X1236214Y-249095D02*
X1230014D01*
Y-247179D01*
X1230324Y-246565D01*
X1230737Y-246182D01*
X1231564Y-246029D01*
X1232391Y-246182D01*
X1232907Y-246642D01*
X1233217Y-247179D01*
Y-249095D01*
G01Y-247179D02*
X1236214Y-246029D01*
G01X1234974Y-243049D02*
X1235697Y-242589D01*
X1236111Y-241975D01*
X1236214Y-241285D01*
X1236111Y-240672D01*
X1235594Y-240059D01*
X1234974Y-239675D01*
X1234354Y-239599D01*
X1233631Y-239752D01*
X1233114Y-240289D01*
X1232907Y-240825D01*
Y-241515D01*
G01Y-240825D02*
X1232597Y-240365D01*
X1232081Y-239982D01*
X1231461Y-239829D01*
X1230841Y-239982D01*
X1230324Y-240365D01*
X1230014Y-241055D01*
X1230117Y-241745D01*
X1230531Y-242435D01*
G01X1236214Y-235315D02*
X1234871Y-235162D01*
X1233734Y-234932D01*
X1232701Y-234625D01*
X1231564Y-234242D01*
X1230014Y-233629D01*
Y-236695D01*
G01X1235491Y-230265D02*
X1236007Y-229729D01*
X1236214Y-229115D01*
X1236007Y-228502D01*
X1235388Y-227965D01*
X1234457Y-227582D01*
X1233527Y-227429D01*
X1232391D01*
X1231461Y-227582D01*
X1230634Y-227965D01*
X1230221Y-228425D01*
X1230014Y-228962D01*
X1230221Y-229575D01*
X1230634Y-230035D01*
X1231254Y-230342D01*
X1232081Y-230495D01*
X1232804Y-230342D01*
X1233527Y-229959D01*
X1233941Y-229499D01*
X1234044Y-228962D01*
X1233837Y-228349D01*
X1233321Y-227889D01*
X1232391Y-227429D01*
G01X1222678Y223705D02*
X1216478D01*
Y225621D01*
X1216788Y226235D01*
X1217201Y226618D01*
X1218028Y226771D01*
X1218855Y226618D01*
X1219371Y226158D01*
X1219681Y225621D01*
Y223705D01*
G01Y225621D02*
X1222678Y226771D01*
G01X1221438Y229751D02*
X1222161Y230211D01*
X1222575Y230825D01*
X1222678Y231515D01*
X1222575Y232128D01*
X1222058Y232741D01*
X1221438Y233125D01*
X1220818Y233201D01*
X1220095Y233048D01*
X1219578Y232511D01*
X1219371Y231975D01*
Y231285D01*
G01Y231975D02*
X1219061Y232435D01*
X1218545Y232818D01*
X1217925Y232971D01*
X1217305Y232818D01*
X1216788Y232435D01*
X1216478Y231745D01*
X1216581Y231055D01*
X1216995Y230365D01*
G01X1221438Y235951D02*
X1222161Y236411D01*
X1222575Y237025D01*
X1222678Y237715D01*
X1222575Y238328D01*
X1222058Y238941D01*
X1221438Y239325D01*
X1220818Y239401D01*
X1220095Y239248D01*
X1219578Y238711D01*
X1219371Y238175D01*
Y237485D01*
G01Y238175D02*
X1219061Y238635D01*
X1218545Y239018D01*
X1217925Y239171D01*
X1217305Y239018D01*
X1216788Y238635D01*
X1216478Y237945D01*
X1216581Y237255D01*
X1216995Y236565D01*
G01X1217511Y242381D02*
X1216891Y242841D01*
X1216581Y243378D01*
X1216478Y243991D01*
X1216685Y244758D01*
X1217201Y245295D01*
X1217821Y245448D01*
X1218441Y245371D01*
X1218958Y245065D01*
X1219991Y243531D01*
X1220715Y242841D01*
X1221748Y242381D01*
X1222678Y242228D01*
Y245448D01*
G01X1246646Y-249095D02*
X1240446D01*
Y-247179D01*
X1240756Y-246565D01*
X1241169Y-246182D01*
X1241996Y-246029D01*
X1242823Y-246182D01*
X1243339Y-246642D01*
X1243649Y-247179D01*
Y-249095D01*
G01Y-247179D02*
X1246646Y-246029D01*
G01Y-241362D02*
X1240446D01*
X1241686Y-242282D01*
G01X1246646D02*
Y-240442D01*
G01X1241479Y-236619D02*
X1240859Y-236159D01*
X1240549Y-235622D01*
X1240446Y-235009D01*
X1240653Y-234242D01*
X1241169Y-233705D01*
X1241789Y-233552D01*
X1242409Y-233629D01*
X1242926Y-233935D01*
X1243959Y-235469D01*
X1244683Y-236159D01*
X1245716Y-236619D01*
X1246646Y-236772D01*
Y-233552D01*
G01X1245406Y-230649D02*
X1246129Y-230189D01*
X1246543Y-229575D01*
X1246646Y-228885D01*
X1246543Y-228272D01*
X1246026Y-227659D01*
X1245406Y-227275D01*
X1244786Y-227199D01*
X1244063Y-227352D01*
X1243546Y-227889D01*
X1243339Y-228425D01*
Y-229115D01*
G01Y-228425D02*
X1243029Y-227965D01*
X1242513Y-227582D01*
X1241893Y-227429D01*
X1241273Y-227582D01*
X1240756Y-227965D01*
X1240446Y-228655D01*
X1240549Y-229345D01*
X1240963Y-230035D01*
G01X1245646Y-203295D02*
X1239446D01*
Y-201379D01*
X1239756Y-200765D01*
X1240169Y-200382D01*
X1240996Y-200229D01*
X1241823Y-200382D01*
X1242339Y-200842D01*
X1242649Y-201379D01*
Y-203295D01*
G01Y-201379D02*
X1245646Y-200229D01*
G01Y-194642D02*
X1239446D01*
X1243889Y-197479D01*
Y-193645D01*
G01X1244923Y-190665D02*
X1245439Y-190129D01*
X1245646Y-189515D01*
X1245439Y-188902D01*
X1244820Y-188365D01*
X1243889Y-187982D01*
X1242959Y-187829D01*
X1241823D01*
X1240893Y-187982D01*
X1240066Y-188365D01*
X1239653Y-188825D01*
X1239446Y-189362D01*
X1239653Y-189975D01*
X1240066Y-190435D01*
X1240686Y-190742D01*
X1241513Y-190895D01*
X1242236Y-190742D01*
X1242959Y-190359D01*
X1243373Y-189899D01*
X1243476Y-189362D01*
X1243269Y-188749D01*
X1242753Y-188289D01*
X1241823Y-187829D01*
G01X1244406Y-184849D02*
X1245129Y-184389D01*
X1245543Y-183775D01*
X1245646Y-183085D01*
X1245543Y-182472D01*
X1245026Y-181859D01*
X1244406Y-181475D01*
X1243786Y-181399D01*
X1243063Y-181552D01*
X1242546Y-182089D01*
X1242339Y-182625D01*
Y-183315D01*
G01Y-182625D02*
X1242029Y-182165D01*
X1241513Y-181782D01*
X1240893Y-181629D01*
X1240273Y-181782D01*
X1239756Y-182165D01*
X1239446Y-182855D01*
X1239549Y-183545D01*
X1239963Y-184235D01*
G01X1246646Y-91295D02*
X1240446D01*
Y-89379D01*
X1240756Y-88765D01*
X1241169Y-88382D01*
X1241996Y-88229D01*
X1242823Y-88382D01*
X1243339Y-88842D01*
X1243649Y-89379D01*
Y-91295D01*
G01Y-89379D02*
X1246646Y-88229D01*
G01Y-82642D02*
X1240446D01*
X1244889Y-85479D01*
Y-81645D01*
G01X1245923Y-78665D02*
X1246439Y-78129D01*
X1246646Y-77515D01*
X1246439Y-76902D01*
X1245820Y-76365D01*
X1244889Y-75982D01*
X1243959Y-75829D01*
X1242823D01*
X1241893Y-75982D01*
X1241066Y-76365D01*
X1240653Y-76825D01*
X1240446Y-77362D01*
X1240653Y-77975D01*
X1241066Y-78435D01*
X1241686Y-78742D01*
X1242513Y-78895D01*
X1243236Y-78742D01*
X1243959Y-78359D01*
X1244373Y-77899D01*
X1244476Y-77362D01*
X1244269Y-76749D01*
X1243753Y-76289D01*
X1242823Y-75829D01*
G01X1241479Y-72619D02*
X1240859Y-72159D01*
X1240549Y-71622D01*
X1240446Y-71009D01*
X1240653Y-70242D01*
X1241169Y-69705D01*
X1241789Y-69552D01*
X1242409Y-69629D01*
X1242926Y-69935D01*
X1243959Y-71469D01*
X1244683Y-72159D01*
X1245716Y-72619D01*
X1246646Y-72772D01*
Y-69552D01*
G01Y29705D02*
X1240446D01*
Y31621D01*
X1240756Y32235D01*
X1241169Y32618D01*
X1241996Y32771D01*
X1242823Y32618D01*
X1243339Y32158D01*
X1243649Y31621D01*
Y29705D01*
G01Y31621D02*
X1246646Y32771D01*
G01Y38358D02*
X1240446D01*
X1244889Y35521D01*
Y39355D01*
G01X1245923Y42335D02*
X1246439Y42871D01*
X1246646Y43485D01*
X1246439Y44098D01*
X1245820Y44635D01*
X1244889Y45018D01*
X1243959Y45171D01*
X1242823D01*
X1241893Y45018D01*
X1241066Y44635D01*
X1240653Y44175D01*
X1240446Y43638D01*
X1240653Y43025D01*
X1241066Y42565D01*
X1241686Y42258D01*
X1242513Y42105D01*
X1243236Y42258D01*
X1243959Y42641D01*
X1244373Y43101D01*
X1244476Y43638D01*
X1244269Y44251D01*
X1243753Y44711D01*
X1242823Y45171D01*
G01X1245716Y48151D02*
X1246233Y48611D01*
X1246543Y49148D01*
X1246646Y49838D01*
X1246439Y50528D01*
X1246026Y51065D01*
X1245303Y51448D01*
X1244476Y51525D01*
X1243649Y51371D01*
X1243133Y50988D01*
X1242719Y50451D01*
X1242616Y49915D01*
X1242719Y49378D01*
X1243133Y48688D01*
X1240446Y48918D01*
Y50988D01*
G01X1246646Y136705D02*
X1240446D01*
Y138621D01*
X1240756Y139235D01*
X1241169Y139618D01*
X1241996Y139771D01*
X1242823Y139618D01*
X1243339Y139158D01*
X1243649Y138621D01*
Y136705D01*
G01Y138621D02*
X1246646Y139771D01*
G01Y145358D02*
X1240446D01*
X1244889Y142521D01*
Y146355D01*
G01X1245923Y149335D02*
X1246439Y149871D01*
X1246646Y150485D01*
X1246439Y151098D01*
X1245820Y151635D01*
X1244889Y152018D01*
X1243959Y152171D01*
X1242823D01*
X1241893Y152018D01*
X1241066Y151635D01*
X1240653Y151175D01*
X1240446Y150638D01*
X1240653Y150025D01*
X1241066Y149565D01*
X1241686Y149258D01*
X1242513Y149105D01*
X1243236Y149258D01*
X1243959Y149641D01*
X1244373Y150101D01*
X1244476Y150638D01*
X1244269Y151251D01*
X1243753Y151711D01*
X1242823Y152171D01*
G01X1246646Y157758D02*
X1240446D01*
X1244889Y154921D01*
Y158755D01*
G01X1242898Y213002D02*
Y219202D01*
X1240061Y214759D01*
X1243895D01*
G01X1253791Y229702D02*
Y225259D01*
X1254098Y224328D01*
X1254711Y223709D01*
X1255478Y223502D01*
X1256245Y223709D01*
X1256858Y224328D01*
X1257165Y225259D01*
Y229702D01*
G01X1261678Y223502D02*
X1262215Y223605D01*
X1262828Y223915D01*
X1263211Y224432D01*
X1263365Y225155D01*
X1263211Y225879D01*
X1262751Y226499D01*
X1262061Y226809D01*
X1261295D01*
X1260835Y227015D01*
X1260451Y227532D01*
X1260298Y228255D01*
X1260528Y228979D01*
X1261065Y229495D01*
X1261678Y229702D01*
X1262291Y229495D01*
X1262828Y228979D01*
X1263058Y228255D01*
X1262905Y227532D01*
X1262521Y227015D01*
X1262061Y226809D01*
X1261295D01*
X1260605Y226499D01*
X1260145Y225879D01*
X1259991Y225155D01*
X1260145Y224432D01*
X1260528Y223915D01*
X1261141Y223605D01*
X1261678Y223502D01*
G01X1286678Y185705D02*
X1280478D01*
Y187621D01*
X1280788Y188235D01*
X1281201Y188618D01*
X1282028Y188771D01*
X1282855Y188618D01*
X1283371Y188158D01*
X1283681Y187621D01*
Y185705D01*
G01Y187621D02*
X1286678Y188771D01*
G01X1285438Y191751D02*
X1286161Y192211D01*
X1286575Y192825D01*
X1286678Y193515D01*
X1286575Y194128D01*
X1286058Y194741D01*
X1285438Y195125D01*
X1284818Y195201D01*
X1284095Y195048D01*
X1283578Y194511D01*
X1283371Y193975D01*
Y193285D01*
G01Y193975D02*
X1283061Y194435D01*
X1282545Y194818D01*
X1281925Y194971D01*
X1281305Y194818D01*
X1280788Y194435D01*
X1280478Y193745D01*
X1280581Y193055D01*
X1280995Y192365D01*
G01X1285438Y197951D02*
X1286161Y198411D01*
X1286575Y199025D01*
X1286678Y199715D01*
X1286575Y200328D01*
X1286058Y200941D01*
X1285438Y201325D01*
X1284818Y201401D01*
X1284095Y201248D01*
X1283578Y200711D01*
X1283371Y200175D01*
Y199485D01*
G01Y200175D02*
X1283061Y200635D01*
X1282545Y201018D01*
X1281925Y201171D01*
X1281305Y201018D01*
X1280788Y200635D01*
X1280478Y199945D01*
X1280581Y199255D01*
X1280995Y198565D01*
G01X1285438Y204151D02*
X1286161Y204611D01*
X1286575Y205225D01*
X1286678Y205915D01*
X1286575Y206528D01*
X1286058Y207141D01*
X1285438Y207525D01*
X1284818Y207601D01*
X1284095Y207448D01*
X1283578Y206911D01*
X1283371Y206375D01*
Y205685D01*
G01Y206375D02*
X1283061Y206835D01*
X1282545Y207218D01*
X1281925Y207371D01*
X1281305Y207218D01*
X1280788Y206835D01*
X1280478Y206145D01*
X1280581Y205455D01*
X1280995Y204765D01*
G01X1273291Y212932D02*
X1273751Y212415D01*
X1274288Y212105D01*
X1274978Y212002D01*
X1275668Y212209D01*
X1276205Y212622D01*
X1276588Y213345D01*
X1276665Y214172D01*
X1276511Y214999D01*
X1276128Y215515D01*
X1275591Y215929D01*
X1275055Y216032D01*
X1274518Y215929D01*
X1273828Y215515D01*
X1274058Y218202D01*
X1276128D01*
G01X1276978Y233002D02*
X1277515Y233105D01*
X1278128Y233415D01*
X1278511Y233932D01*
X1278665Y234655D01*
X1278511Y235379D01*
X1278051Y235999D01*
X1277361Y236309D01*
X1276595D01*
X1276135Y236515D01*
X1275751Y237032D01*
X1275598Y237755D01*
X1275828Y238479D01*
X1276365Y238995D01*
X1276978Y239202D01*
X1277591Y238995D01*
X1278128Y238479D01*
X1278358Y237755D01*
X1278205Y237032D01*
X1277821Y236515D01*
X1277361Y236309D01*
X1276595D01*
X1275905Y235999D01*
X1275445Y235379D01*
X1275291Y234655D01*
X1275445Y233932D01*
X1275828Y233415D01*
X1276441Y233105D01*
X1276978Y233002D01*
G01X1299745Y199502D02*
Y205702D01*
X1301661D01*
X1302275Y205392D01*
X1302658Y204979D01*
X1302811Y204152D01*
X1302658Y203325D01*
X1302198Y202809D01*
X1301661Y202499D01*
X1299745D01*
G01X1301661D02*
X1302811Y199502D01*
G01X1305791Y200742D02*
X1306251Y200019D01*
X1306865Y199605D01*
X1307555Y199502D01*
X1308168Y199605D01*
X1308781Y200122D01*
X1309165Y200742D01*
X1309241Y201362D01*
X1309088Y202085D01*
X1308551Y202602D01*
X1308015Y202809D01*
X1307325D01*
G01X1308015D02*
X1308475Y203119D01*
X1308858Y203635D01*
X1309011Y204255D01*
X1308858Y204875D01*
X1308475Y205392D01*
X1307785Y205702D01*
X1307095Y205599D01*
X1306405Y205185D01*
G01X1311991Y200742D02*
X1312451Y200019D01*
X1313065Y199605D01*
X1313755Y199502D01*
X1314368Y199605D01*
X1314981Y200122D01*
X1315365Y200742D01*
X1315441Y201362D01*
X1315288Y202085D01*
X1314751Y202602D01*
X1314215Y202809D01*
X1313525D01*
G01X1314215D02*
X1314675Y203119D01*
X1315058Y203635D01*
X1315211Y204255D01*
X1315058Y204875D01*
X1314675Y205392D01*
X1313985Y205702D01*
X1313295Y205599D01*
X1312605Y205185D01*
G01X1318421Y202085D02*
X1318958Y202809D01*
X1319418Y203222D01*
X1320031Y203429D01*
X1320568Y203222D01*
X1320951Y202809D01*
X1321258Y202189D01*
X1321335Y201465D01*
X1321258Y200845D01*
X1320951Y200225D01*
X1320491Y199709D01*
X1319955Y199502D01*
X1319341Y199709D01*
X1318805Y200328D01*
X1318498Y201259D01*
X1318421Y202292D01*
X1318575Y203635D01*
X1318805Y204359D01*
X1319188Y205082D01*
X1319725Y205599D01*
X1320261Y205702D01*
X1320798Y205495D01*
X1321181Y204979D01*
G01X1295674Y185705D02*
X1289474D01*
Y187621D01*
X1289784Y188235D01*
X1290197Y188618D01*
X1291024Y188771D01*
X1291851Y188618D01*
X1292367Y188158D01*
X1292677Y187621D01*
Y185705D01*
G01Y187621D02*
X1295674Y188771D01*
G01X1294434Y191751D02*
X1295157Y192211D01*
X1295571Y192825D01*
X1295674Y193515D01*
X1295571Y194128D01*
X1295054Y194741D01*
X1294434Y195125D01*
X1293814Y195201D01*
X1293091Y195048D01*
X1292574Y194511D01*
X1292367Y193975D01*
Y193285D01*
G01Y193975D02*
X1292057Y194435D01*
X1291541Y194818D01*
X1290921Y194971D01*
X1290301Y194818D01*
X1289784Y194435D01*
X1289474Y193745D01*
X1289577Y193055D01*
X1289991Y192365D01*
G01X1294434Y197951D02*
X1295157Y198411D01*
X1295571Y199025D01*
X1295674Y199715D01*
X1295571Y200328D01*
X1295054Y200941D01*
X1294434Y201325D01*
X1293814Y201401D01*
X1293091Y201248D01*
X1292574Y200711D01*
X1292367Y200175D01*
Y199485D01*
G01Y200175D02*
X1292057Y200635D01*
X1291541Y201018D01*
X1290921Y201171D01*
X1290301Y201018D01*
X1289784Y200635D01*
X1289474Y199945D01*
X1289577Y199255D01*
X1289991Y198565D01*
G01X1295674Y206758D02*
X1289474D01*
X1293917Y203921D01*
Y207755D01*
G01X1299745Y209502D02*
Y215702D01*
X1301661D01*
X1302275Y215392D01*
X1302658Y214979D01*
X1302811Y214152D01*
X1302658Y213325D01*
X1302198Y212809D01*
X1301661Y212499D01*
X1299745D01*
G01X1301661D02*
X1302811Y209502D01*
G01X1305791Y210742D02*
X1306251Y210019D01*
X1306865Y209605D01*
X1307555Y209502D01*
X1308168Y209605D01*
X1308781Y210122D01*
X1309165Y210742D01*
X1309241Y211362D01*
X1309088Y212085D01*
X1308551Y212602D01*
X1308015Y212809D01*
X1307325D01*
G01X1308015D02*
X1308475Y213119D01*
X1308858Y213635D01*
X1309011Y214255D01*
X1308858Y214875D01*
X1308475Y215392D01*
X1307785Y215702D01*
X1307095Y215599D01*
X1306405Y215185D01*
G01X1311991Y210742D02*
X1312451Y210019D01*
X1313065Y209605D01*
X1313755Y209502D01*
X1314368Y209605D01*
X1314981Y210122D01*
X1315365Y210742D01*
X1315441Y211362D01*
X1315288Y212085D01*
X1314751Y212602D01*
X1314215Y212809D01*
X1313525D01*
G01X1314215D02*
X1314675Y213119D01*
X1315058Y213635D01*
X1315211Y214255D01*
X1315058Y214875D01*
X1314675Y215392D01*
X1313985Y215702D01*
X1313295Y215599D01*
X1312605Y215185D01*
G01X1318191Y210432D02*
X1318651Y209915D01*
X1319188Y209605D01*
X1319878Y209502D01*
X1320568Y209709D01*
X1321105Y210122D01*
X1321488Y210845D01*
X1321565Y211672D01*
X1321411Y212499D01*
X1321028Y213015D01*
X1320491Y213429D01*
X1319955Y213532D01*
X1319418Y213429D01*
X1318728Y213015D01*
X1318958Y215702D01*
X1321028D01*
G01X1299745Y219502D02*
Y225702D01*
X1301661D01*
X1302275Y225392D01*
X1302658Y224979D01*
X1302811Y224152D01*
X1302658Y223325D01*
X1302198Y222809D01*
X1301661Y222499D01*
X1299745D01*
G01X1301661D02*
X1302811Y219502D01*
G01X1305791Y220742D02*
X1306251Y220019D01*
X1306865Y219605D01*
X1307555Y219502D01*
X1308168Y219605D01*
X1308781Y220122D01*
X1309165Y220742D01*
X1309241Y221362D01*
X1309088Y222085D01*
X1308551Y222602D01*
X1308015Y222809D01*
X1307325D01*
G01X1308015D02*
X1308475Y223119D01*
X1308858Y223635D01*
X1309011Y224255D01*
X1308858Y224875D01*
X1308475Y225392D01*
X1307785Y225702D01*
X1307095Y225599D01*
X1306405Y225185D01*
G01X1311991Y220742D02*
X1312451Y220019D01*
X1313065Y219605D01*
X1313755Y219502D01*
X1314368Y219605D01*
X1314981Y220122D01*
X1315365Y220742D01*
X1315441Y221362D01*
X1315288Y222085D01*
X1314751Y222602D01*
X1314215Y222809D01*
X1313525D01*
G01X1314215D02*
X1314675Y223119D01*
X1315058Y223635D01*
X1315211Y224255D01*
X1315058Y224875D01*
X1314675Y225392D01*
X1313985Y225702D01*
X1313295Y225599D01*
X1312605Y225185D01*
G01X1319725Y219502D02*
X1319878Y220845D01*
X1320108Y221982D01*
X1320415Y223015D01*
X1320798Y224152D01*
X1321411Y225702D01*
X1318345D01*
G01X1299745Y230202D02*
Y236402D01*
X1301661D01*
X1302275Y236092D01*
X1302658Y235679D01*
X1302811Y234852D01*
X1302658Y234025D01*
X1302198Y233509D01*
X1301661Y233199D01*
X1299745D01*
G01X1301661D02*
X1302811Y230202D01*
G01X1305791Y231442D02*
X1306251Y230719D01*
X1306865Y230305D01*
X1307555Y230202D01*
X1308168Y230305D01*
X1308781Y230822D01*
X1309165Y231442D01*
X1309241Y232062D01*
X1309088Y232785D01*
X1308551Y233302D01*
X1308015Y233509D01*
X1307325D01*
G01X1308015D02*
X1308475Y233819D01*
X1308858Y234335D01*
X1309011Y234955D01*
X1308858Y235575D01*
X1308475Y236092D01*
X1307785Y236402D01*
X1307095Y236299D01*
X1306405Y235885D01*
G01X1311991Y231442D02*
X1312451Y230719D01*
X1313065Y230305D01*
X1313755Y230202D01*
X1314368Y230305D01*
X1314981Y230822D01*
X1315365Y231442D01*
X1315441Y232062D01*
X1315288Y232785D01*
X1314751Y233302D01*
X1314215Y233509D01*
X1313525D01*
G01X1314215D02*
X1314675Y233819D01*
X1315058Y234335D01*
X1315211Y234955D01*
X1315058Y235575D01*
X1314675Y236092D01*
X1313985Y236402D01*
X1313295Y236299D01*
X1312605Y235885D01*
G01X1319878Y230202D02*
X1320415Y230305D01*
X1321028Y230615D01*
X1321411Y231132D01*
X1321565Y231855D01*
X1321411Y232579D01*
X1320951Y233199D01*
X1320261Y233509D01*
X1319495D01*
X1319035Y233715D01*
X1318651Y234232D01*
X1318498Y234955D01*
X1318728Y235679D01*
X1319265Y236195D01*
X1319878Y236402D01*
X1320491Y236195D01*
X1321028Y235679D01*
X1321258Y234955D01*
X1321105Y234232D01*
X1320721Y233715D01*
X1320261Y233509D01*
X1319495D01*
X1318805Y233199D01*
X1318345Y232579D01*
X1318191Y231855D01*
X1318345Y231132D01*
X1318728Y230615D01*
X1319341Y230305D01*
X1319878Y230202D01*
G01X1302065Y246185D02*
X1301605Y246495D01*
X1301068Y246702D01*
X1300455D01*
X1299765Y246392D01*
X1299228Y245875D01*
X1298845Y245255D01*
X1298538Y244222D01*
X1298461Y243292D01*
X1298615Y242362D01*
X1298845Y241742D01*
X1299305Y241122D01*
X1299841Y240709D01*
X1300378Y240502D01*
X1300915D01*
X1301451Y240709D01*
X1301911Y241019D01*
X1302295Y241432D01*
G01X1304891Y241742D02*
X1305351Y241019D01*
X1305965Y240605D01*
X1306655Y240502D01*
X1307268Y240605D01*
X1307881Y241122D01*
X1308265Y241742D01*
X1308341Y242362D01*
X1308188Y243085D01*
X1307651Y243602D01*
X1307115Y243809D01*
X1306425D01*
G01X1307115D02*
X1307575Y244119D01*
X1307958Y244635D01*
X1308111Y245255D01*
X1307958Y245875D01*
X1307575Y246392D01*
X1306885Y246702D01*
X1306195Y246599D01*
X1305505Y246185D01*
G01X1311475Y241225D02*
X1312011Y240709D01*
X1312625Y240502D01*
X1313238Y240709D01*
X1313775Y241328D01*
X1314158Y242259D01*
X1314311Y243189D01*
Y244325D01*
X1314158Y245255D01*
X1313775Y246082D01*
X1313315Y246495D01*
X1312778Y246702D01*
X1312165Y246495D01*
X1311705Y246082D01*
X1311398Y245462D01*
X1311245Y244635D01*
X1311398Y243912D01*
X1311781Y243189D01*
X1312241Y242775D01*
X1312778Y242672D01*
X1313391Y242879D01*
X1313851Y243395D01*
X1314311Y244325D01*
M02*
